G04 ================== begin FILE IDENTIFICATION RECORD ==================*
G04 Layout Name:  9324_DA0F0TMBIJ0_F0T_Motherboard_J_v01_20230324_0910.brd*
G04 Film Name:    smt*
G04 File Format:  Gerber RS274X*
G04 File Origin:  Cadence Allegro 17.2-S081*
G04 Origin Date:  Sat Mar 25 08:44:51 2023*
G04 *
G04 Layer:  DRAWING FORMAT/TITLE_BLOCK_A*
G04 Layer:  DRAWING FORMAT/TITLE_BLOCK*
G04 Layer:  VIA CLASS/SOLDERMASK_TOP*
G04 Layer:  PIN/SOLDERMASK_TOP*
G04 Layer:  PACKAGE GEOMETRY/SOLDERMASK_TOP*
G04 Layer:  MANUFACTURING/PHOTOPLOT_OUTLINE*
G04 Layer:  DRAWING FORMAT/TITLE_DATA_SMT*
G04 Layer:  BOARD GEOMETRY/SOLDERMASK_TOP*
G04 *
G04 Offset:    (0.00 0.00)*
G04 Mirror:    No*
G04 Mode:      Positive*
G04 Rotation:  0*
G04 FullContactRelief:  No*
G04 UndefLineWidth:     6.00*
G04 ================== end FILE IDENTIFICATION RECORD ====================*
%FSLAX25Y25*MOIN*%
%IR0*IPPOS*OFA0.00000B0.00000*MIA0B0*SFA1.00000B1.00000*%
%AMMACRO253*
4,1,5,.00791,.01972,
.00791,-.01264,
.00083,-.01972,
-.00791,-.01972,
-.00791,.01972,
.00791,.01972,
0.0*
%
%ADD253MACRO253*%
%AMMACRO228*
4,1,5,.05712,.05712,
.05712,-.04217,
.04217,-.05712,
-.05712,-.05712,
-.05712,.05712,
.05712,.05712,
0.0*
%
%ADD228MACRO228*%
%ADD289R,.021X.104*%
%AMMACRO251*
4,1,32,-.06201,-.01575,
-.0502,-.01575,
-.0502,.00197,
-.04035,.00197,
-.04035,-.01575,
-.03248,-.01575,
-.03248,.00197,
-.02461,.00197,
-.02461,-.01575,
-.01673,-.01575,
-.01673,.00197,
-.00886,.00197,
-.00886,-.01575,
-.00098,-.01575,
-.00098,.00197,
.00689,.00197,
.00689,-.01575,
.01476,-.01575,
.01476,.00197,
.02264,.00197,
.02264,-.01575,
.03051,-.01575,
.03051,.00197,
.03839,.00197,
.03839,-.01575,
.04626,-.01575,
.04626,.00197,
.05413,.00197,
.05413,-.01575,
.06201,-.01575,
.06201,.01575,
-.06201,.01575,
-.06201,-.01575,
0.0*
%
%ADD251MACRO251*%
%ADD33R,.113X.04*%
%AMMACRO94*
4,1,44,.00295,.01381,
.003639,.01375,
.004307,.013571,
.004934,.01328,
.005501,.012883,
.00599,.012394,
.006387,.011828,
.00668,.011201,
.006859,.010533,
.00692,.009845,
.00692,.00984,
.00692,-.00984,
.00686,-.010529,
.006681,-.011197,
.00639,-.011824,
.005993,-.012391,
.005504,-.01288,
.004938,-.013277,
.004311,-.01357,
.003643,-.013749,
.002955,-.01381,
.00295,-.01381,
-.00295,-.01381,
-.003639,-.01375,
-.004307,-.013571,
-.004934,-.01328,
-.005501,-.012883,
-.00599,-.012394,
-.006387,-.011828,
-.00668,-.011201,
-.006859,-.010533,
-.00692,-.009845,
-.00692,-.00984,
-.00692,.00984,
-.00686,.010529,
-.006681,.011197,
-.00639,.011824,
-.005993,.012391,
-.005504,.01288,
-.004938,.013277,
-.004311,.01357,
-.003643,.013749,
-.002955,.01381,
-.00295,.01381,
.00295,.01381,
0.0*
%
%ADD94MACRO94*%
%ADD65R,.13X.052*%
%AMMACRO312*
4,1,28,.01191,-.0059,
.011835,-.006923,
.01158,-.007917,
.011155,-.008851,
.010575,-.009697,
.009857,-.01043,
.009023,-.011027,
.008097,-.01147,
.007109,-.011746,
.006087,-.011845,
.00602,-.01185,
-.00149,-.01184,
-.00149,-.00948,
-.01192,-.00947,
-.0119,.00949,
-.00147,.00948,
-.00147,.01184,
.00604,.01183,
.007062,.011745,
.008053,.011479,
.008983,.011045,
.009824,.010457,
.010549,.009731,
.011138,.008891,
.011571,.007961,
.011837,.006969,
.011926,.005947,
.01193,.00588,
.01191,-.0059,
0.0*
%
%ADD312MACRO312*%
%ADD131R,.103X.071*%
%AMMACRO58*
4,1,8,-.06499,-.03153,
-.06499,.03153,
-.01768,.03153,
-.01768,-.01571,
.01769,-.01571,
.01769,.03153,
.06499,.03153,
.06499,-.03153,
-.06499,-.03153,
0.0*
%
%ADD58MACRO58*%
%ADD238R,.071X.103*%
%AMMACRO297*
4,1,8,-.09255,.08468,
.0295,.08468,
.0295,.09452,
.09255,.09452,
.09255,-.09452,
.0295,-.09452,
.0295,-.08468,
-.09255,-.08468,
-.09255,.08468,
0.0*
%
%ADD297MACRO297*%
%ADD192R,.114X.053*%
%ADD187R,.13X.064*%
%ADD97R,.103X.046*%
%AMMACRO303*
4,1,32,-.05512,-.01181,
-.04331,-.01181,
-.04331,.00098,
-.03543,.00098,
-.03543,-.01181,
-.02362,-.01181,
-.02362,.00098,
-.01575,.00098,
-.01575,-.01181,
-.00394,-.01181,
-.00394,.00098,
.00394,.00098,
.00394,-.01181,
.01575,-.01181,
.01575,.00098,
.02362,.00098,
.02362,-.01181,
.03543,-.01181,
.03543,.00098,
.04331,.00098,
.04331,-.01181,
.05512,-.01181,
.05512,.00098,
.06299,.00098,
.06299,-.01181,
.0748,-.01181,
.0748,.01181,
-.0748,.01181,
-.0748,-.01181,
-.06299,-.01181,
-.06299,.00098,
-.05512,.00098,
-.05512,-.01181,
0.0*
%
%ADD303MACRO303*%
%ADD296R,.064X.13*%
%AMMACRO204*
4,1,8,.00292,-.01971,
.00292,.00194,
-.00292,.00194,
-.00292,-.01971,
-.01676,-.01971,
-.01676,.01972,
.01676,.01972,
.01676,-.01971,
.00292,-.01971,
0.0*
%
%ADD204MACRO204*%
%AMMACRO125*
4,1,8,.01971,.00292,
-.00194,.00292,
-.00194,-.00292,
.01971,-.00292,
.01971,-.01676,
-.01972,-.01676,
-.01972,.01676,
.01971,.01676,
.01971,.00292,
0.0*
%
%ADD125MACRO125*%
%ADD101R,.046X.103*%
%ADD191C,.02*%
%ADD280C,.012*%
%ADD225O,.141X.068*%
%ADD150C,.03*%
%ADD144C,.021*%
%AMMACRO36*
4,1,44,-.02365,.00984,
-.02359,.010529,
-.023412,.011197,
-.02312,.011824,
-.022724,.012391,
-.022235,.01288,
-.021669,.013277,
-.021043,.01357,
-.020375,.013749,
-.019686,.01381,
-.01968,.01381,
.01968,.01381,
.020369,.01375,
.021037,.013572,
.021664,.01328,
.022231,.012884,
.02272,.012395,
.023117,.011829,
.02341,.011203,
.023589,.010535,
.02365,.009846,
.02365,.00984,
.02365,-.00984,
.02359,-.010529,
.023412,-.011197,
.02312,-.011824,
.022724,-.012391,
.022235,-.01288,
.021669,-.013277,
.021043,-.01357,
.020375,-.013749,
.019686,-.01381,
.01968,-.01381,
-.01968,-.01381,
-.020369,-.01375,
-.021037,-.013572,
-.021664,-.01328,
-.022231,-.012884,
-.02272,-.012395,
-.023117,-.011829,
-.02341,-.011203,
-.023589,-.010535,
-.02365,-.009846,
-.02365,-.00984,
-.02365,.00984,
0.0*
%
%ADD36MACRO36*%
%ADD28O,.115X.066*%
%AMMACRO311*
4,1,28,-.0119,.00591,
-.011824,.006933,
-.011566,.007926,
-.011141,.00886,
-.010559,.009705,
-.00984,.010437,
-.009004,.011032,
-.008078,.011474,
-.007089,.011747,
-.006068,.011845,
-.00601,.01185,
.0015,.01184,
.0015,.00948,
.01193,.00947,
.01191,-.00949,
.00148,-.00948,
.00148,-.01184,
-.00603,-.01183,
-.007052,-.011745,
-.008043,-.011479,
-.008973,-.011045,
-.009814,-.010457,
-.010539,-.009731,
-.011127,-.008891,
-.011561,-.007961,
-.011827,-.00697,
-.011916,-.005948,
-.01192,-.00589,
-.0119,.00591,
0.0*
%
%ADD311MACRO311*%
%ADD229C,.013*%
%ADD221C,.04*%
%ADD299R,.123X.067*%
%ADD259C,.05*%
%ADD183R,.17X.083*%
%ADD281C,.015*%
%AMMACRO269*
21,1,.044,.075,0.0,0.0,135.*%
%ADD269MACRO269*%
%ADD244R,.067X.123*%
%ADD117R,.083X.17*%
%ADD40C,.06*%
%ADD279C,.016*%
%ADD255R,.0081X.016*%
%ADD193C,.061*%
%AMMACRO70*
4,1,21,.014,.0055,
.014,-.0055,
-.0085,-.0055,
-.009455,-.005416,
-.010381,-.005168,
-.01125,-.004763,
-.012035,-.004213,
-.012713,-.003535,
-.013263,-.00275,
-.013668,-.001881,
-.013916,-.000955,
-.014,0.0,
-.013916,.000955,
-.013668,.001881,
-.013263,.00275,
-.012713,.003535,
-.012035,.004213,
-.01125,.004763,
-.010381,.005168,
-.009455,.005416,
-.0085,.0055,
.014,.0055,
0.0*
%
%ADD70MACRO70*%
%ADD17C,.034*%
%AMMACRO295*
4,1,6,-.032,.08861,
.00444,.08861,
.00444,.01952,
.032,.01952,
.032,-.08861,
-.032,-.08861,
-.032,.08861,
0.0*
%
%ADD295MACRO295*%
%ADD290R,.021X.189*%
%ADD87R,.174X.028*%
%ADD82R,.016X.0081*%
%AMMACRO63*
4,1,21,.0055,-.014,
-.0055,-.014,
-.0055,.0085,
-.005416,.009455,
-.005168,.010381,
-.004763,.01125,
-.004213,.012035,
-.003535,.012713,
-.00275,.013263,
-.001881,.013668,
-.000955,.013916,
0.0,.014,
.000955,.013916,
.001881,.013668,
.00275,.013263,
.003535,.012713,
.004213,.012035,
.004763,.01125,
.005168,.010381,
.005416,.009455,
.0055,.0085,
.0055,-.014,
0.0*
%
%ADD63MACRO63*%
%ADD116R,.028X.174*%
%ADD143C,.019*%
%ADD138R,.182X.058*%
%ADD31C,.064*%
%ADD163C,.065*%
%ADD256R,.099X.115*%
%ADD84C,.066*%
%ADD189C,.085*%
%AMMACRO156*
21,1,.016,.0081,0.0,0.0,45.322*%
%ADD156MACRO156*%
%ADD30C,.068*%
%AMMACRO195*
4,1,8,-.0445,-.08,
-.0445,.08,
.0445,.08,
.0445,.0216,
.0165,.0216,
.0165,-.0216,
.0445,-.0216,
.0445,-.08,
-.0445,-.08,
0.0*
%
%ADD195MACRO195*%
%ADD137R,.182X.099*%
%ADD130R,.071X.071*%
%ADD119C,.03417*%
%ADD206R,.036X.036*%
%ADD314C,.0395*%
%ADD98R,.064X.064*%
%ADD178R,.134X.0888*%
%ADD169R,.065X.065*%
%AMMACRO104*
4,1,5,.03578,.03652,
.03578,-.03652,
-.02673,-.03652,
-.03578,-.02747,
-.03578,.03652,
.03578,.03652,
0.0*
%
%ADD104MACRO104*%
%AMMACRO304*
4,1,24,.01051,-.04391,
.01188,-.04527,
.03394,-.04527,
.03394,-.03346,
.02016,-.03348,
.02016,-.02559,
.03394,-.02559,
.03394,-.01379,
.02016,-.0138,
.02016,-.0059,
.03394,-.00592,
.03394,.00591,
.02016,.00589,
.02016,.01378,
.03394,.01378,
.03394,.0256,
.02016,.02557,
.02016,.03347,
.03394,.03347,
.03394,.04527,
.01188,.04527,
.00913,.04255,
-.03394,.04255,
-.03394,-.04391,
.01051,-.04391,
0.0*
%
%ADD304MACRO304*%
%AMMACRO227*
4,1,30,-.08273,-.12417,
-.100642,-.108127,
-.115497,-.089217,
-.126842,-.068015,
-.134333,-.045165,
-.137743,-.021362,
-.136967,.002672,
-.132029,.026206,
-.12308,.048525,
-.110391,.068951,
-.094348,.086864,
-.075439,.101718,
-.054237,.113063,
-.031387,.120554,
-.007583,.123964,
.016451,.123188,
.039985,.118251,
.062304,.109302,
.08273,.096613,
.100642,.08057,
.115497,.06166,
.126842,.040458,
.134333,.017608,
.137743,-.006195,
.136967,-.030229,
.132029,-.053763,
.12308,-.076082,
.110391,-.096509,
.094348,-.114421,
.08273,-.12417,
-.08273,-.12417,
0.0*
%
%ADD227MACRO227*%
%ADD86R,.066X.066*%
%ADD78R,.0888X.134*%
%ADD313C,.0785*%
%ADD263R,.068X.068*%
%AMMACRO230*
4,1,5,.05023,.05023,
.05023,-.03528,
.03528,-.05023,
-.05023,-.05023,
-.05023,.05023,
.05023,.05023,
0.0*
%
%ADD230MACRO230*%
%ADD148R,.189X.089*%
%AMMACRO243*
4,1,5,-.01362,-.00692,
-.01873,-.00181,
-.01873,.00692,
.01873,.00692,
.01873,-.00692,
-.01362,-.00692,
0.0*
%
%ADD243MACRO243*%
%ADD120R,.03417X.03417*%
%AMMACRO48*
4,1,5,.01578,-.00692,
-.01067,-.00692,
-.01578,-.00181,
-.01578,.00692,
.01578,.00692,
.01578,-.00692,
0.0*
%
%ADD48MACRO48*%
%AMMACRO261*
4,1,14,.02956,-.11716,
-.02956,-.11716,
-.02956,.11716,
.02956,.11716,
.02956,-.02817,
.027197,-.03143,
.025436,-.035051,
.02433,-.038922,
.023914,-.042927,
.024199,-.046943,
.025177,-.050849,
.026819,-.054525,
.029074,-.057861,
.02956,-.05844,
.02956,-.11716,
0.0*
%
%ADD261MACRO261*%
%AMMACRO50*
4,1,5,-.00692,-.01578,
-.00692,.01067,
-.00181,.01578,
.00692,.01578,
.00692,-.01578,
-.00692,-.01578,
0.0*
%
%ADD50MACRO50*%
%AMMACRO278*
4,1,28,-.01259,-.00426,
-.013262,-.003485,
-.013784,-.002602,
-.014146,-.001641,
-.014335,-.000633,
-.014346,.000393,
-.014178,.001405,
-.013838,.002373,
-.013334,.003267,
-.012683,.004061,
-.01264,.00411,
-.00733,.00942,
-.00566,.00775,
.00172,.01513,
.01513,.00172,
.00775,-.00566,
.00942,-.00733,
.00411,-.01264,
.003321,-.013297,
.002433,-.01381,
.001469,-.014162,
.000458,-.01434,
-.000568,-.014341,
-.001578,-.014163,
-.002543,-.013812,
-.003431,-.0133,
-.004218,-.01264,
-.00426,-.01259,
-.01259,-.00426,
0.0*
%
%ADD278MACRO278*%
%AMMACRO68*
4,1,17,-.0055,.014,
.0055,.014,
.0055,-.0085,
.005491,-.00882,
.005463,-.009139,
.00543,-.00938,
.00088,-.01393,
-.000076,-.014,
-.00103,-.013903,
-.001953,-.013642,
-.002816,-.013225,
-.003593,-.012664,
-.004262,-.011977,
-.004801,-.011184,
-.005194,-.01031,
-.005429,-.00938,
-.0055,-.0085,
-.0055,.014,
0.0*
%
%ADD68MACRO68*%
%AMMACRO45*
4,1,17,-.014,-.0055,
-.014,.0055,
.0085,.0055,
.00882,.005491,
.009139,.005463,
.00938,.00543,
.01393,.00088,
.014,-.000076,
.013903,-.00103,
.013642,-.001953,
.013225,-.002816,
.012664,-.003593,
.011977,-.004262,
.011184,-.004801,
.01031,-.005194,
.00938,-.005429,
.0085,-.0055,
-.014,-.0055,
0.0*
%
%ADD45MACRO45*%
%AMMACRO22*
4,1,28,-.00589,-.01192,
-.006913,-.011842,
-.007907,-.011587,
-.008842,-.011163,
-.009688,-.010584,
-.010422,-.009866,
-.011019,-.009032,
-.011463,-.008107,
-.011739,-.007119,
-.01184,-.006097,
-.01184,-.00603,
-.01184,.00148,
-.00948,.00148,
-.00948,.01191,
.00948,.01191,
.00948,.00148,
.01184,.00148,
.01184,-.00603,
.011751,-.007052,
.011486,-.008044,
.011053,-.008974,
.010465,-.009815,
.00974,-.010541,
.0089,-.01113,
.00797,-.011564,
.006979,-.01183,
.005957,-.01192,
.00589,-.01192,
-.00589,-.01192,
0.0*
%
%ADD22MACRO22*%
%AMMACRO16*
4,1,28,-.01192,.00589,
-.011842,.006913,
-.011587,.007907,
-.011163,.008842,
-.010584,.009688,
-.009866,.010422,
-.009032,.011019,
-.008107,.011463,
-.007119,.011739,
-.006097,.01184,
-.00603,.01184,
.00148,.01184,
.00148,.00948,
.01191,.00948,
.01191,-.00948,
.00148,-.00948,
.00148,-.01184,
-.00603,-.01184,
-.007052,-.011751,
-.008044,-.011486,
-.008974,-.011053,
-.009815,-.010465,
-.010541,-.00974,
-.01113,-.0089,
-.011564,-.00797,
-.01183,-.006979,
-.01192,-.005957,
-.01192,-.00589,
-.01192,.00589,
0.0*
%
%ADD16MACRO16*%
%ADD214C,.06974*%
%ADD118C,.03968*%
%AMMACRO109*
4,1,6,.04334,.1083,
.04334,-.1083,
-.01578,-.1083,
-.01578,-.03743,
-.04334,-.03743,
-.04334,.1083,
.04334,.1083,
0.0*
%
%ADD109MACRO109*%
%AMMACRO55*
4,1,5,.01578,-.00692,
-.01578,-.00692,
-.01578,.00181,
-.01067,.00692,
.01578,.00692,
.01578,-.00692,
0.0*
%
%ADD55MACRO55*%
%AMMACRO264*
4,1,14,-.02956,.11716,
.02956,.11716,
.02956,-.11716,
-.02956,-.11716,
-.02956,-.05844,
-.027197,-.05518,
-.025436,-.051559,
-.02433,-.047688,
-.023914,-.043683,
-.024199,-.039667,
-.025177,-.035761,
-.026819,-.032085,
-.029074,-.028749,
-.02956,-.02817,
-.02956,.11716,
0.0*
%
%ADD264MACRO264*%
%AMMACRO241*
4,1,8,-.02661,.02021,
.0266,.02021,
.0266,-.02021,
.01276,-.02021,
.01276,.00637,
-.01277,.00637,
-.01277,-.02021,
-.02661,-.02021,
-.02661,.02021,
0.0*
%
%ADD241MACRO241*%
%AMMACRO126*
4,1,9,.01972,.00969,
.01972,-.01676,
-.01971,-.01676,
-.01971,-.00292,
.00194,-.00292,
.00194,.00292,
-.01971,.00292,
-.01971,.01676,
.01264,.01676,
.01972,.00969,
0.0*
%
%ADD126MACRO126*%
%AMMACRO49*
4,1,5,-.00692,-.01578,
-.00692,.01578,
.00181,.01578,
.00692,.01067,
.00692,-.01578,
-.00692,-.01578,
0.0*
%
%ADD49MACRO49*%
%AMMACRO277*
4,1,28,.01259,.00425,
.013259,.003472,
.01378,.002588,
.01414,.001628,
.014328,.000619,
.014338,-.000407,
.01417,-.001419,
.013828,-.002387,
.013323,-.00328,
.012671,-.004072,
.01263,-.00412,
.00732,-.00943,
.00565,-.00776,
-.00173,-.01513,
-.01513,-.00173,
-.00776,.00565,
-.00943,.00732,
-.00412,.01263,
-.003332,.013288,
-.002444,.013802,
-.00148,.014154,
-.00047,.014333,
.000556,.014334,
.001567,.014157,
.002531,.013807,
.003421,.013295,
.004207,.012636,
.00425,.01259,
.01259,.00425,
0.0*
%
%ADD277MACRO277*%
%AMMACRO205*
4,1,9,.00969,-.01972,
-.01676,-.01972,
-.01676,.01971,
-.00292,.01971,
-.00292,-.00194,
.00292,-.00194,
.00292,.01971,
.01676,.01971,
.01676,-.01264,
.00969,-.01972,
0.0*
%
%ADD205MACRO205*%
%AMMACRO66*
4,1,17,-.0055,.014,
.0055,.014,
.0055,-.0085,
.005416,-.009455,
.005168,-.010382,
.004763,-.011251,
.004213,-.012037,
.003535,-.012715,
.002749,-.013265,
.00188,-.01367,
.000953,-.013919,
-.000002,-.014002,
-.00089,-.01393,
-.00543,-.00939,
-.005472,-.009073,
-.005495,-.008754,
-.0055,-.0085,
-.0055,.014,
0.0*
%
%ADD66MACRO66*%
%AMMACRO43*
4,1,17,-.014,-.0055,
-.014,.0055,
.0085,.0055,
.009455,.005416,
.010382,.005168,
.011251,.004763,
.012037,.004213,
.012715,.003535,
.013265,.002749,
.01367,.00188,
.013919,.000953,
.014002,-.000002,
.01393,-.00089,
.00939,-.00543,
.009073,-.005472,
.008754,-.005495,
.0085,-.0055,
-.014,-.0055,
0.0*
%
%ADD43MACRO43*%
%AMMACRO23*
4,1,28,.0059,.01191,
.006923,.01183,
.007916,.011573,
.00885,.011148,
.009696,.010567,
.010428,.009849,
.011024,.009013,
.011466,.008088,
.011741,.007099,
.01184,.006078,
.01184,.00602,
.01184,-.00149,
.00948,-.00149,
.00948,-.01192,
-.00948,-.01192,
-.00948,-.00149,
-.01184,-.00149,
-.01184,.00602,
-.011751,.007042,
-.011486,.008033,
-.011053,.008964,
-.010465,.009805,
-.00974,.010531,
-.0089,.01112,
-.007971,.011554,
-.00698,.01182,
-.005958,.01191,
-.0059,.01191,
.0059,.01191,
0.0*
%
%ADD23MACRO23*%
%AMMACRO20*
4,1,28,.01191,-.0059,
.01183,-.006923,
.011573,-.007916,
.011148,-.00885,
.010567,-.009696,
.009849,-.010428,
.009013,-.011024,
.008088,-.011466,
.007099,-.011741,
.006078,-.01184,
.00602,-.01184,
-.00149,-.01184,
-.00149,-.00948,
-.01192,-.00948,
-.01192,.00948,
-.00149,.00948,
-.00149,.01184,
.00602,.01184,
.007042,.011751,
.008033,.011486,
.008964,.011053,
.009805,.010465,
.010531,.00974,
.01112,.0089,
.011554,.007971,
.01182,.00698,
.01191,.005958,
.01191,.0059,
.01191,-.0059,
0.0*
%
%ADD20MACRO20*%
%ADD233R,.06974X.06974*%
%ADD282O,.013X.01*%
%ADD283O,.01X.013*%
%AMMACRO309*
4,1,5,-.00791,-.01972,
-.00791,.01264,
-.00083,.01972,
.00791,.01972,
.00791,-.01972,
-.00791,-.01972,
0.0*
%
%ADD309MACRO309*%
%ADD301R,.201X.132*%
%AMMACRO249*
4,1,5,.10239,-.10239,
-.10239,-.10239,
-.10239,.08941,
-.08941,.10239,
.10239,.10239,
.10239,-.10239,
0.0*
%
%ADD249MACRO249*%
%AMMACRO176*
4,1,5,-.01972,.00791,
.01264,.00791,
.01972,.00083,
.01972,-.00791,
-.01972,-.00791,
-.01972,.00791,
0.0*
%
%ADD176MACRO176*%
%ADD159R,.03X.011*%
%ADD158R,.011X.03*%
%AMMACRO60*
4,1,8,.06499,.03153,
.06499,-.03153,
.01768,-.03153,
.01768,.01571,
-.01769,.01571,
-.01769,-.03153,
-.06499,-.03153,
-.06499,.03153,
.06499,.03153,
0.0*
%
%ADD60MACRO60*%
%ADD224R,.17X.201*%
%ADD153R,.05X.021*%
%ADD110R,.13X.126*%
%ADD80R,.024X.02*%
%AMMACRO310*
4,1,32,.06201,.01575,
.0502,.01575,
.0502,-.00197,
.04035,-.00197,
.04035,.01575,
.03248,.01575,
.03248,-.00197,
.02461,-.00197,
.02461,.01575,
.01673,.01575,
.01673,-.00197,
.00886,-.00197,
.00886,.01575,
.00098,.01575,
.00098,-.00197,
-.00689,-.00197,
-.00689,.01575,
-.01476,.01575,
-.01476,-.00197,
-.02264,-.00197,
-.02264,.01575,
-.03051,.01575,
-.03051,-.00197,
-.03839,-.00197,
-.03839,.01575,
-.04626,.01575,
-.04626,-.00197,
-.05413,-.00197,
-.05413,.01575,
-.06201,.01575,
-.06201,-.01575,
.06201,-.01575,
.06201,.01575,
0.0*
%
%ADD310MACRO310*%
%ADD136R,.042X.03*%
%ADD79R,.024X.021*%
%ADD54R,.04X.014*%
%ADD298R,.05X.032*%
%ADD287R,.03X.042*%
%ADD248R,.022X.015*%
%ADD246R,.026X.011*%
%ADD203R,.032X.014*%
%AMMACRO173*
4,1,32,.01575,-.06201,
.01575,-.0502,
-.00197,-.0502,
-.00197,-.04035,
.01575,-.04035,
.01575,-.03248,
-.00197,-.03248,
-.00197,-.02461,
.01575,-.02461,
.01575,-.01673,
-.00197,-.01673,
-.00197,-.00886,
.01575,-.00886,
.01575,-.00098,
-.00197,-.00098,
-.00197,.00689,
.01575,.00689,
.01575,.01476,
-.00197,.01476,
-.00197,.02264,
.01575,.02264,
.01575,.03051,
-.00197,.03051,
-.00197,.03839,
.01575,.03839,
.01575,.04626,
-.00197,.04626,
-.00197,.05413,
.01575,.05413,
.01575,.06201,
-.01575,.06201,
-.01575,-.06201,
.01575,-.06201,
0.0*
%
%ADD173MACRO173*%
%ADD149R,.021X.024*%
%ADD133R,.07X.021*%
%AMMACRO95*
4,1,44,.01381,-.00295,
.01375,-.003639,
.013571,-.004307,
.01328,-.004934,
.012883,-.005501,
.012394,-.00599,
.011828,-.006387,
.011201,-.00668,
.010533,-.006859,
.009845,-.00692,
.00984,-.00692,
-.00984,-.00692,
-.010529,-.00686,
-.011197,-.006681,
-.011824,-.00639,
-.012391,-.005993,
-.01288,-.005504,
-.013277,-.004938,
-.01357,-.004311,
-.013749,-.003643,
-.01381,-.002955,
-.01381,-.00295,
-.01381,.00295,
-.01375,.003639,
-.013571,.004307,
-.01328,.004934,
-.012883,.005501,
-.012394,.00599,
-.011828,.006387,
-.011201,.00668,
-.010533,.006859,
-.009845,.00692,
-.00984,.00692,
.00984,.00692,
.010529,.00686,
.011197,.006681,
.011824,.00639,
.012391,.005993,
.01288,.005504,
.013277,.004938,
.01357,.004311,
.013749,.003643,
.01381,.002955,
.01381,.00295,
.01381,-.00295,
0.0*
%
%ADD95MACRO95*%
%ADD27R,.024X.022*%
%ADD247R,.015X.022*%
%ADD245R,.011X.026*%
%ADD239R,.024X.014*%
%ADD236R,.032X.05*%
%ADD177R,.036X.011*%
%ADD127R,.014X.032*%
%ADD89R,.022X.016*%
%ADD85R,.17X.134*%
%ADD71R,.022X.024*%
%ADD24R,.033X.014*%
%ADD300R,.134X.134*%
%ADD262R,.063X.021*%
%ADD254R,.011X.036*%
%ADD237R,.274X.13*%
%ADD219R,.024X.015*%
%ADD142R,.028X.02*%
%ADD108R,.016X.022*%
%ADD76R,.028X.011*%
%ADD34R,.014X.033*%
%ADD284R,.06X.052*%
%ADD196R,.024X.016*%
%ADD180R,.04X.036*%
%ADD172R,.02X.028*%
%ADD111R,.012X.018*%
%ADD106R,.026X.014*%
%ADD75R,.011X.028*%
%ADD46R,.028X.021*%
%ADD18R,.04X.044*%
%ADD12R,.038X.02*%
%ADD286R,.063X.014*%
%AMMACRO270*
21,1,.032,.036,0.0,0.0,45.*%
%ADD270MACRO270*%
%ADD242R,.054X.014*%
%ADD220R,.025X.016*%
%ADD212R,.018X.014*%
%ADD198R,.019X.013*%
%ADD186R,.036X.04*%
%ADD184R,.048X.02*%
%ADD165R,.021X.028*%
%ADD147R,.06X.044*%
%ADD121R,.036X.014*%
%ADD107R,.014X.026*%
%ADD92R,.028X.013*%
%ADD41R,.036X.032*%
%ADD306R,.027X.015*%
%AMMACRO235*
4,1,8,-.08468,-.09255,
-.08468,.0295,
-.09452,.0295,
-.09452,.09255,
.09452,.09255,
.09452,.0295,
.08468,.0295,
.08468,-.09255,
-.08468,-.09255,
0.0*
%
%ADD235MACRO235*%
%ADD231R,.06X.054*%
%ADD213R,.019X.014*%
%ADD211R,.014X.018*%
%ADD207R,.052X.044*%
%ADD199R,.013X.019*%
%ADD182R,.058X.02*%
%ADD179R,.073X.05*%
%ADD170R,.036X.015*%
%ADD167R,.044X.06*%
%ADD152R,.05X.028*%
%ADD145R,.056X.022*%
%ADD123R,.014X.054*%
%ADD122R,.014X.036*%
%ADD90R,.013X.028*%
%ADD83R,.06X.018*%
%ADD59R,.02X.048*%
%ADD47R,.032X.036*%
%ADD308R,.015X.027*%
%ADD305R,.028X.015*%
%ADD267C,.142*%
%ADD215R,.063X.052*%
%ADD210R,.014X.019*%
%ADD188R,.018X.06*%
%ADD175R,.036X.016*%
%AMMACRO113*
4,1,6,.032,-.08861,
-.00444,-.08861,
-.00444,-.01952,
-.032,-.01952,
-.032,.08861,
.032,.08861,
.032,-.08861,
0.0*
%
%ADD113MACRO113*%
%ADD96R,.028X.032*%
%AMMACRO74*
21,1,.016,.0081,0.0,0.0,135.*%
%ADD74MACRO74*%
%AMMACRO67*
4,1,21,-.0055,.014,
.0055,.014,
.0055,-.0085,
.005416,-.009455,
.005168,-.010381,
.004763,-.01125,
.004213,-.012035,
.003535,-.012713,
.00275,-.013263,
.001881,-.013668,
.000955,-.013916,
0.0,-.014,
-.000955,-.013916,
-.001881,-.013668,
-.00275,-.013263,
-.003535,-.012713,
-.004213,-.012035,
-.004763,-.01125,
-.005168,-.010381,
-.005416,-.009455,
-.0055,-.0085,
-.0055,.014,
0.0*
%
%ADD67MACRO67*%
%ADD56R,.056X.014*%
%AMMACRO44*
4,1,21,-.014,-.0055,
-.014,.0055,
.0085,.0055,
.009455,.005416,
.010381,.005168,
.01125,.004763,
.012035,.004213,
.012713,.003535,
.013263,.00275,
.013668,.001881,
.013916,.000955,
.014,0.0,
.013916,-.000955,
.013668,-.001881,
.013263,-.00275,
.012713,-.003535,
.012035,-.004213,
.01125,-.004763,
.010381,-.005168,
.009455,-.005416,
.0085,-.0055,
-.014,-.0055,
0.0*
%
%ADD44MACRO44*%
%ADD37R,.02X.058*%
%ADD307R,.015X.028*%
%ADD252R,.016X.036*%
%ADD234R,.052X.063*%
%ADD162C,.26*%
%ADD154R,.053X.018*%
%ADD146R,.036X.026*%
%ADD132R,.06X.056*%
%ADD105R,.064X.061*%
%ADD42R,.054X.044*%
%ADD32R,.019X.016*%
%ADD11R,.038X.024*%
%ADD293R,.036X.044*%
%ADD250R,.083X.016*%
%ADD232R,.193X.19*%
%ADD223R,.026X.072*%
%ADD218R,.058X.014*%
%ADD216R,.052X.029*%
%ADD201R,.056X.06*%
%ADD197R,.067X.05*%
%ADD194R,.016X.019*%
%ADD155R,.063X.018*%
%ADD140R,.026X.036*%
%ADD114O,.319X.256*%
%ADD99R,.04X.067*%
%ADD72R,.044X.054*%
%ADD39R,.019X.061*%
%ADD19C,.414*%
%ADD288R,.094X.015*%
%ADD226R,.054X.019*%
%ADD190R,.067X.015*%
%ADD174R,.016X.083*%
%ADD168R,.044X.019*%
%ADD164R,.018X.063*%
%ADD102R,.081X.073*%
%ADD21C,.145*%
%ADD13C,.118*%
%ADD265R,.046X.028*%
%ADD141R,.028X.028*%
%ADD134C,.155*%
%ADD124C,.182*%
%ADD115R,.067X.016*%
%ADD91R,.073X.081*%
%ADD258R,.054X.039*%
%ADD209C,.237*%
%ADD200R,.028X.046*%
%ADD185R,.067X.044*%
%ADD171R,.028X.028*%
%ADD161R,.056X.028*%
%ADD157R,.048X.018*%
%AMMACRO302*
4,1,30,.08089,-.09065,
.08227,-.09203,
.10433,-.09203,
.10433,-.08022,
.08309,-.08022,
.08171,-.07884,
.02464,-.07884,
.02464,.02608,
.06988,.02609,
.06988,.09203,
-.06988,.09203,
-.06988,.01427,
-.04035,.01427,
-.04035,-.02116,
-.10433,-.02117,
-.10433,-.03298,
-.09055,-.03298,
-.09055,-.04085,
-.10433,-.04084,
-.10433,-.05261,
-.09055,-.05266,
-.09055,-.06053,
-.10433,-.06054,
-.10433,-.07237,
-.09055,-.07237,
-.09055,-.08022,
-.10433,-.08022,
-.10433,-.09203,
-.08227,-.09203,
-.08089,-.09065,
.08089,-.09065,
0.0*
%
%ADD302MACRO302*%
%ADD266R,.018X.048*%
%ADD217R,.048X.028*%
%ADD151R,.028X.056*%
%ADD139C,.319*%
%ADD73R,.067X.018*%
%ADD291R,.056X.065*%
%ADD257R,.028X.048*%
%AMMACRO240*
4,1,8,.0445,.08,
.0445,-.08,
-.0445,-.08,
-.0445,-.0216,
-.0165,-.0216,
-.0165,.0216,
-.0445,.0216,
-.0445,.08,
.0445,.08,
0.0*
%
%ADD240MACRO240*%
%ADD181R,.058X.028*%
%ADD135C,.009*%
%ADD112R,.028X.093*%
%ADD81R,.067X.019*%
%ADD38R,.028X.058*%
%ADD222C,.178*%
%ADD208C,.295*%
%ADD35R,.144X.144*%
%ADD268R,.048X.058*%
%ADD260R,.028X.069*%
%AMMACRO93*
4,1,44,.05318,.04921,
.05318,-.04921,
.05312,-.049899,
.052941,-.050567,
.05265,-.051194,
.052253,-.051761,
.051764,-.05225,
.051198,-.052647,
.050571,-.05294,
.049903,-.053119,
.049214,-.05318,
.04921,-.05318,
-.04921,-.05318,
-.049899,-.05312,
-.050567,-.052941,
-.051194,-.05265,
-.051761,-.052253,
-.05225,-.051764,
-.052647,-.051198,
-.05294,-.050571,
-.053119,-.049903,
-.05318,-.049214,
-.05318,-.04921,
-.05318,.04921,
-.05312,.049899,
-.052941,.050567,
-.05265,.051194,
-.052253,.051761,
-.051764,.05225,
-.051198,.052647,
-.050571,.05294,
-.049903,.053119,
-.049214,.05318,
-.04921,.05318,
.04921,.05318,
.049899,.05312,
.050567,.052941,
.051194,.05265,
.051761,.052253,
.05225,.051764,
.052647,.051198,
.05294,.050571,
.053119,.049903,
.05318,.049214,
.05318,.04921,
0.0*
%
%ADD93MACRO93*%
%ADD29R,.063X.02447*%
%ADD166R,.128X.128*%
%ADD100R,.095X.085*%
%ADD202R,.138X.138*%
%ADD103R,.085X.095*%
%ADD77R,.148X.148*%
%ADD10C,.398*%
%AMMACRO129*
4,1,5,.00692,-.01362,
.00181,-.01873,
-.00692,-.01873,
-.00692,.01873,
.00692,.01873,
.00692,-.01362,
0.0*
%
%ADD129MACRO129*%
%AMMACRO57*
4,1,5,-.01578,.00692,
.01067,.00692,
.01578,.00181,
.01578,-.00692,
-.01578,-.00692,
-.01578,.00692,
0.0*
%
%ADD57MACRO57*%
%AMMACRO53*
4,1,5,.00692,.01578,
.00692,-.01067,
.00181,-.01578,
-.00692,-.01578,
-.00692,.01578,
.00692,.01578,
0.0*
%
%ADD53MACRO53*%
%ADD160R,.178X.178*%
%AMMACRO294*
4,1,5,-.03578,-.03652,
-.03578,.03652,
.02673,.03652,
.03578,.02747,
.03578,-.03652,
-.03578,-.03652,
0.0*
%
%ADD294MACRO294*%
%AMMACRO276*
4,1,28,-.00426,.01259,
-.003485,.013262,
-.002602,.013784,
-.001641,.014146,
-.000633,.014335,
.000393,.014346,
.001405,.014178,
.002373,.013838,
.003267,.013334,
.004061,.012683,
.00411,.01264,
.00942,.00733,
.00775,.00566,
.01513,-.00172,
.00172,-.01513,
-.00566,-.00775,
-.00733,-.00942,
-.01264,-.00411,
-.013297,-.003321,
-.01381,-.002433,
-.014162,-.001469,
-.01434,-.000458,
-.014341,.000568,
-.014163,.001578,
-.013812,.002543,
-.0133,.003431,
-.01264,.004218,
-.01259,.00426,
-.00426,.01259,
0.0*
%
%ADD276MACRO276*%
%AMMACRO274*
4,1,28,.00426,-.01259,
.003485,-.013262,
.002602,-.013784,
.001641,-.014146,
.000633,-.014335,
-.000393,-.014346,
-.001405,-.014178,
-.002373,-.013838,
-.003267,-.013334,
-.004061,-.012683,
-.00411,-.01264,
-.00942,-.00733,
-.00775,-.00566,
-.01513,.00172,
-.00172,.01513,
.00566,.00775,
.00733,.00942,
.01264,.00411,
.013297,.003321,
.01381,.002433,
.014162,.001469,
.01434,.000458,
.014341,-.000568,
.014163,-.001578,
.013812,-.002543,
.0133,-.003431,
.01264,-.004218,
.01259,-.00426,
.00426,-.01259,
0.0*
%
%ADD274MACRO274*%
%AMMACRO272*
4,1,28,.01259,.00426,
.013262,.003485,
.013784,.002602,
.014146,.001641,
.014335,.000633,
.014346,-.000393,
.014178,-.001405,
.013838,-.002373,
.013334,-.003267,
.012683,-.004061,
.01264,-.00411,
.00733,-.00942,
.00566,-.00775,
-.00172,-.01513,
-.01513,-.00172,
-.00775,.00566,
-.00942,.00733,
-.00411,.01264,
-.003321,.013297,
-.002433,.01381,
-.001469,.014162,
-.000458,.01434,
.000568,.014341,
.001578,.014163,
.002543,.013812,
.003431,.0133,
.004218,.01264,
.00426,.01259,
.01259,.00426,
0.0*
%
%ADD272MACRO272*%
%AMMACRO26*
4,1,28,.00589,.01192,
.006913,.011842,
.007907,.011587,
.008842,.011163,
.009688,.010584,
.010422,.009866,
.011019,.009032,
.011463,.008107,
.011739,.007119,
.01184,.006097,
.01184,.00603,
.01184,-.00148,
.00948,-.00148,
.00948,-.01191,
-.00948,-.01191,
-.00948,-.00148,
-.01184,-.00148,
-.01184,.00603,
-.011751,.007052,
-.011486,.008044,
-.011053,.008974,
-.010465,.009815,
-.00974,.010541,
-.0089,.01113,
-.00797,.011564,
-.006979,.01183,
-.005957,.01192,
-.00589,.01192,
.00589,.01192,
0.0*
%
%ADD26MACRO26*%
%AMMACRO15*
4,1,28,.01192,-.00589,
.011842,-.006913,
.011587,-.007907,
.011163,-.008842,
.010584,-.009688,
.009866,-.010422,
.009032,-.011019,
.008107,-.011463,
.007119,-.011739,
.006097,-.01184,
.00603,-.01184,
-.00148,-.01184,
-.00148,-.00948,
-.01191,-.00948,
-.01191,.00948,
-.00148,.00948,
-.00148,.01184,
.00603,.01184,
.007052,.011751,
.008044,.011486,
.008974,.011053,
.009815,.010465,
.010541,.00974,
.01113,.0089,
.011564,.00797,
.01183,.006979,
.01192,.005957,
.01192,.00589,
.01192,-.00589,
0.0*
%
%ADD15MACRO15*%
%AMMACRO285*
21,1,.016,.0081,0.0,0.0,134.695*%
%ADD285MACRO285*%
%AMMACRO52*
4,1,5,.00692,.01578,
.00692,-.01578,
-.00181,-.01578,
-.00692,-.01067,
-.00692,.01578,
.00692,.01578,
0.0*
%
%ADD52MACRO52*%
%AMMACRO51*
4,1,5,-.01578,.00692,
.01578,.00692,
.01578,-.00181,
.01067,-.00692,
-.01578,-.00692,
-.01578,.00692,
0.0*
%
%ADD51MACRO51*%
%AMMACRO128*
4,1,8,-.02021,-.02661,
-.02021,.0266,
.02021,.0266,
.02021,.01276,
-.00637,.01276,
-.00637,-.01277,
.02021,-.01277,
.02021,-.02661,
-.02021,-.02661,
0.0*
%
%ADD128MACRO128*%
%AMMACRO61*
4,1,17,.014,.0055,
.014,-.0055,
-.0085,-.0055,
-.00882,-.005491,
-.009139,-.005463,
-.00938,-.00543,
-.01393,-.00088,
-.014,.000076,
-.013903,.00103,
-.013642,.001953,
-.013225,.002816,
-.012664,.003593,
-.011977,.004262,
-.011184,.004801,
-.01031,.005194,
-.00938,.005429,
-.0085,.0055,
.014,.0055,
0.0*
%
%ADD61MACRO61*%
%AMMACRO275*
4,1,28,.00425,-.01259,
.003472,-.013259,
.002588,-.01378,
.001628,-.01414,
.000619,-.014328,
-.000407,-.014338,
-.001419,-.01417,
-.002387,-.013828,
-.00328,-.013323,
-.004072,-.012671,
-.00412,-.01263,
-.00943,-.00732,
-.00776,-.00565,
-.01513,.00173,
-.00173,.01513,
.00565,.00776,
.00732,.00943,
.01263,.00412,
.013288,.003332,
.013802,.002444,
.014154,.00148,
.014333,.00047,
.014334,-.000556,
.014157,-.001567,
.013807,-.002531,
.013295,-.003421,
.012636,-.004207,
.01259,-.00425,
.00425,-.01259,
0.0*
%
%ADD275MACRO275*%
%AMMACRO273*
4,1,28,-.00425,.01259,
-.003472,.013259,
-.002588,.01378,
-.001628,.01414,
-.000619,.014328,
.000407,.014338,
.001419,.01417,
.002387,.013828,
.00328,.013323,
.004072,.012671,
.00412,.01263,
.00943,.00732,
.00776,.00565,
.01513,-.00173,
.00173,-.01513,
-.00565,-.00776,
-.00732,-.00943,
-.01263,-.00412,
-.013288,-.003332,
-.013802,-.002444,
-.014154,-.00148,
-.014333,-.00047,
-.014334,.000556,
-.014157,.001567,
-.013807,.002531,
-.013295,.003421,
-.012636,.004207,
-.01259,.00425,
-.00425,.01259,
0.0*
%
%ADD273MACRO273*%
%AMMACRO271*
4,1,28,-.01259,-.00425,
-.013259,-.003472,
-.01378,-.002588,
-.01414,-.001628,
-.014328,-.000619,
-.014338,.000407,
-.01417,.001419,
-.013828,.002387,
-.013323,.00328,
-.012671,.004072,
-.01263,.00412,
-.00732,.00943,
-.00565,.00776,
.00173,.01513,
.01513,.00173,
.00776,-.00565,
.00943,-.00732,
.00412,-.01263,
.003332,-.013288,
.002444,-.013802,
.00148,-.014154,
.00047,-.014333,
-.000556,-.014334,
-.001567,-.014157,
-.002531,-.013807,
-.003421,-.013295,
-.004207,-.012636,
-.00425,-.01259,
-.01259,-.00425,
0.0*
%
%ADD271MACRO271*%
%AMMACRO64*
4,1,17,.0055,-.014,
-.0055,-.014,
-.0055,.0085,
-.005491,.00882,
-.005463,.009139,
-.00543,.00938,
-.00088,.01393,
.000076,.014,
.00103,.013903,
.001953,.013642,
.002816,.013225,
.003593,.012664,
.004262,.011977,
.004801,.011184,
.005194,.01031,
.005429,.00938,
.0055,.0085,
.0055,-.014,
0.0*
%
%ADD64MACRO64*%
%AMMACRO25*
4,1,28,-.0059,-.01191,
-.006923,-.01183,
-.007916,-.011573,
-.00885,-.011148,
-.009696,-.010567,
-.010428,-.009849,
-.011024,-.009013,
-.011466,-.008088,
-.011741,-.007099,
-.01184,-.006078,
-.01184,-.00602,
-.01184,.00149,
-.00948,.00149,
-.00948,.01192,
.00948,.01192,
.00948,.00149,
.01184,.00149,
.01184,-.00602,
.011751,-.007042,
.011486,-.008033,
.011053,-.008964,
.010465,-.009805,
.00974,-.010531,
.0089,-.01112,
.007971,-.011554,
.00698,-.01182,
.005958,-.01191,
.0059,-.01191,
-.0059,-.01191,
0.0*
%
%ADD25MACRO25*%
%AMMACRO14*
4,1,28,-.01191,.0059,
-.01183,.006923,
-.011573,.007916,
-.011148,.00885,
-.010567,.009696,
-.009849,.010428,
-.009013,.011024,
-.008088,.011466,
-.007099,.011741,
-.006078,.01184,
-.00602,.01184,
.00149,.01184,
.00149,.00948,
.01192,.00948,
.01192,-.00948,
.00149,-.00948,
.00149,-.01184,
-.00602,-.01184,
-.007042,-.011751,
-.008033,-.011486,
-.008964,-.011053,
-.009805,-.010465,
-.010531,-.00974,
-.01112,-.0089,
-.011554,-.007971,
-.01182,-.00698,
-.01191,-.005958,
-.01191,-.0059,
-.01191,.0059,
0.0*
%
%ADD14MACRO14*%
%AMMACRO88*
4,1,6,.1083,-.04334,
-.1083,-.04334,
-.1083,.01578,
-.03743,.01578,
-.03743,.04334,
.1083,.04334,
.1083,-.04334,
0.0*
%
%ADD88MACRO88*%
%AMMACRO292*
4,1,6,-.04334,-.1083,
-.04334,.1083,
.01578,.1083,
.01578,.03743,
.04334,.03743,
.04334,-.1083,
-.04334,-.1083,
0.0*
%
%ADD292MACRO292*%
%AMMACRO69*
4,1,17,.014,.0055,
.014,-.0055,
-.0085,-.0055,
-.009455,-.005416,
-.010382,-.005168,
-.011251,-.004763,
-.012037,-.004213,
-.012715,-.003535,
-.013265,-.002749,
-.01367,-.00188,
-.013919,-.000953,
-.014002,.000002,
-.01393,.00089,
-.00939,.00543,
-.009073,.005472,
-.008754,.005495,
-.0085,.0055,
.014,.0055,
0.0*
%
%ADD69MACRO69*%
%AMMACRO62*
4,1,17,.0055,-.014,
-.0055,-.014,
-.0055,.0085,
-.005416,.009455,
-.005168,.010382,
-.004763,.011251,
-.004213,.012037,
-.003535,.012715,
-.002749,.013265,
-.00188,.01367,
-.000953,.013919,
.000002,.014002,
.00089,.01393,
.00543,.00939,
.005472,.009073,
.005495,.008754,
.0055,.0085,
.0055,-.014,
0.0*
%
%ADD62MACRO62*%
%ADD315C,.01*%
%ADD316C,.006*%
%ADD317C,.1582*%
G75*
%LPD*%
G75*
G36*
G01X31220Y146662D02*
G03I-5900J0D01*
G37*
G36*
G01X46500Y1580802D02*
G03I-5900J0D01*
G37*
G36*
G01X55375Y124912D02*
G02X66445Y113077I5535J-5917D01*
G01X61845Y108774D01*
G02X50775Y120609I-5535J5917D01*
G01X55375Y124912D01*
G37*
G36*
G01X198098Y260082D02*
G02X156728I-20685J0D01*
G01Y294334D01*
G02X198098I20685J0D01*
G01Y260082D01*
G37*
G36*
G01X156626Y1644764D02*
Y1671142D01*
G02X197996I20685J0D01*
G01Y1644764D01*
G02X156626I-20685J0D01*
G37*
G36*
G01X197996D02*
G02X156626I-20685J0D01*
G01Y1671142D01*
G02X197996I20685J0D01*
G01Y1644764D01*
G37*
G36*
G01X499080Y647432D02*
G03I-5900J0D01*
G37*
G36*
G01X683500Y260110D02*
Y294362D01*
G02X724870I20685J0D01*
G01Y260110D01*
G02X683500I-20685J0D01*
G37*
G36*
G01X825575Y204724D02*
G02I-19885J0D01*
G37*
G36*
G01X857240Y1420330D02*
G02I-16000J0D01*
G37*
G36*
G01X948624Y321653D02*
G02I-19885J0D01*
G37*
G36*
G01X938720Y1310432D02*
G03I-5900J0D01*
G37*
G36*
G01X1032240Y1420330D02*
G02I-16000J0D01*
G37*
G36*
G01X1077543Y204724D02*
G02I-19885J0D01*
G37*
G36*
G01X1118570Y541642D02*
G03I-5900J0D01*
G37*
G36*
G01X1174240Y260082D02*
G02X1132870I-20685J0D01*
G01Y294334D01*
G02X1174240I20685J0D01*
G01Y260082D01*
G37*
G36*
G01X1659642Y260110D02*
Y294362D01*
G02X1701012I20685J0D01*
G01Y260110D01*
G02X1659642I-20685J0D01*
G37*
G36*
G01X1700917Y1671142D02*
Y1644764D01*
G02X1659547I-20685J0D01*
G01Y1671142D01*
G02X1700917I20685J0D01*
G37*
G36*
G01X1659547D02*
G02X1700917I20685J0D01*
G01Y1644764D01*
G02X1659547I-20685J0D01*
G01Y1671142D01*
G37*
G36*
G01X1776979Y1714960D02*
G02I-10050J0D01*
G37*
G36*
G01X1813890Y1656032D02*
G03I-5900J0D01*
G37*
G36*
G01X1837827Y127165D02*
G02X1821622I-8103J0D01*
G01Y133465D01*
G02X1837827I8103J0D01*
G01Y127165D01*
G37*
G36*
G01X1841520Y210432D02*
G03I-5900J0D01*
G37*
%LPC*%
G75*
G54D317*
X1766929Y1714960D03*
%LPD*%
G75*
G54D100*
X169744Y1396960D03*
X207887D03*
X323727Y1355106D03*
X355855Y1332308D03*
X387983Y1318882D03*
X420111D03*
X452239D03*
X484367D03*
X516495Y1332308D03*
X548623Y1355106D03*
X683363Y1396985D03*
X721506D03*
X1143055Y1433289D03*
X1181198D03*
X1299988Y1355342D03*
X1331996Y1332308D03*
X1364124Y1318882D03*
X1396252D03*
X1428380D03*
X1460508D03*
X1492636Y1332308D03*
X1524764Y1355106D03*
X1644529Y1430581D03*
X1682672D03*
G54D200*
X726010Y1627615D03*
X722270D03*
X718530D03*
Y1638245D03*
X726010D03*
X726830Y1659065D03*
X719350D03*
X723090Y1668395D03*
X785400Y365335D03*
X781660Y374665D03*
X789140D03*
X803540Y372315D03*
X799800D03*
X796060D03*
Y382945D03*
X803540D03*
X824800Y434035D03*
X821060Y443365D03*
X842940Y430185D03*
X839200D03*
X835460D03*
X828540Y443365D03*
X835460Y440815D03*
X842940D03*
G54D110*
X228840Y685948D03*
X255218D03*
X1054629Y281400D03*
X1081007D03*
X1601355Y602634D03*
X1627733D03*
G54D101*
X164470Y1430123D03*
X178840D03*
X678299Y1430118D03*
X692669D03*
X990710Y288546D03*
X976340D03*
X1152361Y1466422D03*
X1137991D03*
X1639465Y1463714D03*
X1653835D03*
X1682863Y648743D03*
X1697233D03*
G54D102*
X211120Y578610D03*
Y612610D03*
Y646610D03*
X1642853Y641972D03*
Y675972D03*
Y709972D03*
G54D201*
X746517Y126419D03*
X757935D03*
G54D210*
X793000Y1576714D03*
X791032D03*
X789063D03*
X787095D03*
X785126D03*
X783158D03*
Y1594332D03*
X785126D03*
X787095D03*
X789063D03*
X791032D03*
X793000D03*
X825158Y1576714D03*
Y1594332D03*
X835000Y1576714D03*
X833032D03*
X831063D03*
X829095D03*
X827126D03*
Y1594332D03*
X829095D03*
X831063D03*
X833032D03*
X835000D03*
X875032Y1576714D03*
X873063D03*
X871095D03*
X869126D03*
X867158D03*
Y1594332D03*
X869126D03*
X871095D03*
X873063D03*
X875032D03*
X877000Y1576714D03*
Y1594332D03*
X919000Y1576714D03*
X917032D03*
X915063D03*
X913095D03*
X911126D03*
X909158D03*
Y1594332D03*
X911126D03*
X913095D03*
X915063D03*
X917032D03*
X919000D03*
G54D111*
X211090Y681519D03*
X1645883Y607063D03*
G54D300*
X1745799Y1516211D03*
X1779963D03*
G54D120*
X230906Y1734212D03*
X297835D03*
X495079D03*
X562008D03*
X1238780D03*
X1305709D03*
X1502953D03*
X1569882D03*
G54D10*
X27559Y87795D03*
X40708Y631890D03*
Y1368897D03*
X51181Y1714961D03*
X373622Y87795D03*
X395670Y1714961D03*
X661023Y631890D03*
X707677Y1714961D03*
X800787Y87795D03*
X931692Y757874D03*
Y1072834D03*
Y1387795D03*
X1045865Y87795D03*
X1155708Y1714961D03*
X1271260Y631890D03*
X1461805Y1714961D03*
X1499606Y87795D03*
X1816771Y631890D03*
Y1368897D03*
X1806299Y1714961D03*
X1829921Y87795D03*
G54D103*
X211101Y588157D03*
Y622157D03*
Y656157D03*
X1642872Y632425D03*
Y666425D03*
Y700425D03*
G54D202*
X735882Y1585521D03*
X788079Y1585523D03*
X830079D03*
X872079D03*
X914079D03*
G54D112*
X218862Y685948D03*
X1638111Y602634D03*
G54D211*
X781189Y1576664D03*
Y1594382D03*
X794969Y1576664D03*
Y1594382D03*
X823189Y1576664D03*
Y1594382D03*
X836969Y1576664D03*
Y1594382D03*
X865189Y1576664D03*
Y1594382D03*
X878969Y1576664D03*
Y1594382D03*
X907189Y1576664D03*
Y1594382D03*
X920969Y1576664D03*
Y1594382D03*
G54D121*
X256978Y107835D03*
Y111771D03*
X464818Y303145D03*
Y305114D03*
Y307082D03*
Y309051D03*
X470654D03*
Y307082D03*
Y305114D03*
X498218Y302445D03*
Y304414D03*
Y306382D03*
Y308351D03*
X504054D03*
Y306382D03*
Y304414D03*
X690134Y111960D03*
Y115896D03*
X993943Y190419D03*
Y192387D03*
Y194356D03*
Y196325D03*
Y198293D03*
Y200261D03*
X1004967D03*
Y198293D03*
Y196325D03*
Y194356D03*
Y192387D03*
X993943Y202230D03*
Y204199D03*
Y206167D03*
X1004967D03*
Y204199D03*
Y202230D03*
X1732099Y108959D03*
Y112895D03*
G54D220*
X834903Y529786D03*
G54D310*
X1803633Y1521592D03*
G54D301*
X1766878Y222028D03*
Y266320D03*
G54D130*
X286253Y154803D03*
X601156Y205978D03*
X823514Y136898D03*
X847479Y214391D03*
X1174681Y1625220D03*
X1734992Y370384D03*
G54D302*
X1765429Y287264D03*
G54D140*
X336240Y147638D03*
X332500D03*
X328760D03*
Y157086D03*
X336240D03*
X442900Y117195D03*
X450380D03*
Y107747D03*
X446640D03*
X442900D03*
X513444Y460733D03*
Y470181D03*
X517184D03*
X520924Y460733D03*
Y470181D03*
X762013Y1703816D03*
X754533D03*
Y1713264D03*
X758273D03*
X762013D03*
X1531917Y116180D03*
X1539397D03*
Y106732D03*
X1535657D03*
X1531917D03*
X1542401Y147711D03*
Y138263D03*
X1549881Y147711D03*
Y138263D03*
X1546141D03*
X1729954Y411578D03*
X1737434D03*
Y402130D03*
X1733694D03*
X1729954D03*
X1765670Y444538D03*
Y453986D03*
X1769410D03*
X1773150Y444538D03*
Y453986D03*
G54D11*
X14092Y290137D03*
Y298207D03*
X28068Y290137D03*
Y298207D03*
X44692Y290637D03*
Y298707D03*
X58668Y290637D03*
Y298707D03*
X1744422Y151527D03*
Y159597D03*
X1758398Y151527D03*
Y159597D03*
G54D113*
X213303Y685948D03*
G54D122*
X272333Y104291D03*
X270364D03*
X268395D03*
X266427D03*
X264459D03*
X262490D03*
X260521D03*
X258553D03*
Y115315D03*
X260521D03*
X262490D03*
X264459D03*
X266427D03*
X268395D03*
X270364D03*
X272333D03*
X274301Y104291D03*
X467736Y302358D03*
Y309838D03*
X501136Y301658D03*
Y309138D03*
X695646Y108416D03*
X693677D03*
X691709D03*
Y119440D03*
X693677D03*
X695646D03*
X707457Y108416D03*
X705489D03*
X703520D03*
X701551D03*
X699583D03*
X697615D03*
Y119440D03*
X699583D03*
X701551D03*
X703520D03*
X705489D03*
X997487Y207742D03*
X1001423D03*
X1737611Y105415D03*
X1735642D03*
X1733674D03*
Y116439D03*
X1735642D03*
X1737611D03*
X1749422Y105415D03*
X1747454D03*
X1745485D03*
X1743516D03*
X1741548D03*
X1739580D03*
Y116439D03*
X1741548D03*
X1743516D03*
X1745485D03*
X1747454D03*
G54D212*
X779220Y1578633D03*
Y1592413D03*
X796938Y1578633D03*
Y1592413D03*
X821220Y1578633D03*
Y1592413D03*
X838938Y1578633D03*
Y1592413D03*
X863220Y1578633D03*
Y1592413D03*
X880938Y1578633D03*
Y1592413D03*
X905220Y1578633D03*
Y1592413D03*
X922938Y1578633D03*
Y1592413D03*
G54D203*
X761223Y271354D03*
Y273322D03*
Y275290D03*
X769097D03*
Y273322D03*
Y271354D03*
X1509488Y297812D03*
Y301748D03*
G54D20*
X39484Y200862D03*
Y192862D03*
X39204Y216362D03*
X30704D03*
X39204Y208362D03*
Y232362D03*
Y224342D03*
X30704Y224362D03*
X39204Y240362D03*
X36164Y302472D03*
X62258Y1520094D03*
Y1536094D03*
Y1540094D03*
Y1560094D03*
X65790Y302926D03*
X68592Y421746D03*
X82624Y278798D03*
Y295798D03*
Y286262D03*
Y303262D03*
X84875Y376026D03*
X84858Y386502D03*
X80975Y424319D03*
Y420319D03*
X91285Y438519D03*
Y442519D03*
X80674Y648574D03*
Y644564D03*
X88624D03*
X80674Y652564D03*
X88624Y648564D03*
Y656564D03*
Y652564D03*
X89503Y685488D03*
X88492Y694209D03*
X89492Y690644D03*
X87122Y1589872D03*
X91729Y1683071D03*
X91704Y1694362D03*
X91714Y1686622D03*
X110999Y216596D03*
X107934Y517925D03*
X110079Y685490D03*
X98734Y718880D03*
X110258Y1524594D03*
Y1544594D03*
Y1548594D03*
Y1536594D03*
Y1540594D03*
Y1560594D03*
Y1564594D03*
X96172Y1581852D03*
Y1597867D03*
X96247Y1601867D03*
Y1615821D03*
Y1619821D03*
X96157Y1630362D03*
Y1642362D03*
X112059Y186362D03*
X113996Y282995D03*
Y278875D03*
Y274800D03*
Y300354D03*
Y306236D03*
X115798Y523785D03*
X127222Y647103D03*
X125658Y665515D03*
Y661515D03*
X125634Y669400D03*
X119217Y1535767D03*
X119319Y1541935D03*
X119390Y1548027D03*
X124704Y1678362D03*
Y1670362D03*
Y1674362D03*
X117704Y1696362D03*
X124704Y1692362D03*
Y1688362D03*
Y1708362D03*
Y1700362D03*
Y1704362D03*
X130466Y404571D03*
X128222Y656603D03*
Y652603D03*
X131665Y643603D03*
X130541Y1727182D03*
Y1731182D03*
X146880Y415062D03*
Y423383D03*
Y427383D03*
Y419383D03*
Y431383D03*
Y435383D03*
Y439383D03*
Y443383D03*
X146981Y498810D03*
Y502810D03*
X146946Y506533D03*
X146981Y522810D03*
X146529Y688207D03*
X145601Y1396275D03*
Y1392745D03*
X160042Y1412173D03*
X151204Y1708362D03*
Y1712362D03*
X158204Y1716362D03*
X161384Y409362D03*
X175380Y421383D03*
Y425383D03*
Y443383D03*
Y430883D03*
X168595Y1443390D03*
X183966Y393071D03*
Y385071D03*
Y389071D03*
Y405071D03*
X182966Y1535462D03*
X182852Y1544028D03*
X182932Y1548486D03*
X182955Y1539723D03*
X182923Y1552874D03*
Y1557874D03*
X185051Y1723592D03*
X204608Y420255D03*
Y414755D03*
Y425755D03*
Y436755D03*
Y431255D03*
Y442255D03*
Y447755D03*
Y453255D03*
Y458755D03*
Y462755D03*
Y468255D03*
X199585Y570901D03*
X200057Y588879D03*
X199585Y604901D03*
X200057Y622879D03*
X199585Y638901D03*
X200057Y656879D03*
X195035Y681291D03*
X194126Y693623D03*
X198185Y1412173D03*
X196352Y1719697D03*
X208102Y1718017D03*
X202109Y1733022D03*
X215038Y452735D03*
X218375Y567981D03*
X217276Y596107D03*
X218375Y601981D03*
X217276Y630107D03*
X218375Y635981D03*
X217276Y664107D03*
X214525Y673737D03*
X233504Y154126D03*
X245204Y71862D03*
X250281Y111743D03*
X272984Y136962D03*
X270034Y142892D03*
X270037Y159203D03*
Y155203D03*
X265704Y214022D03*
X269538Y422735D03*
X269520Y418579D03*
X269538Y426735D03*
X269570Y431039D03*
X269538Y443735D03*
X259754Y458617D03*
X276751Y99183D03*
X279884Y136962D03*
X280764Y210802D03*
X298401Y71513D03*
X298431Y75673D03*
X299537Y151703D03*
Y156203D03*
X292104Y637809D03*
X320041Y91803D03*
X309203Y595318D03*
X317699Y599926D03*
X315130Y1369807D03*
X325526Y69863D03*
X323289Y563176D03*
X342984Y161862D03*
X349717Y709995D03*
X346153Y1347521D03*
X366684Y130162D03*
X366584Y156202D03*
X356204Y221862D03*
X379204Y128452D03*
X379224Y124312D03*
X378281Y1334095D03*
X387834Y1627062D03*
X388644Y124322D03*
X388559Y128491D03*
X399080Y1330142D03*
X397809Y1413619D03*
X399402Y1432571D03*
Y1427569D03*
X402405Y1541810D03*
Y1556810D03*
X411343Y161162D03*
X412027Y1334095D03*
X418461Y1390306D03*
X411799Y1390325D03*
X406388Y1404207D03*
Y1400684D03*
X406315Y1397038D03*
X406383Y1407727D03*
X408202Y1427569D03*
Y1432571D03*
X414184Y1611300D03*
Y1607400D03*
X412916Y1680267D03*
X422821Y67465D03*
Y62665D03*
X426559Y117491D03*
X431948Y128515D03*
Y124015D03*
X420681Y149373D03*
Y157466D03*
Y161466D03*
Y153477D03*
X431204Y214862D03*
Y209862D03*
X426204Y225362D03*
X426904Y232562D03*
Y236562D03*
Y240562D03*
X430639Y1330042D03*
X432905Y1543810D03*
Y1555810D03*
X430029Y1579466D03*
X449805Y149864D03*
X439802Y498733D03*
Y504233D03*
Y509733D03*
Y515233D03*
Y520733D03*
Y526233D03*
Y542733D03*
X448312Y537483D03*
X439802Y547769D03*
Y552769D03*
X442537Y1334095D03*
X454477Y75985D03*
X459623Y115948D03*
X458805Y149864D03*
Y154864D03*
X463564Y1330533D03*
X454073Y1393959D03*
X453085Y1420625D03*
Y1409125D03*
Y1413125D03*
Y1417125D03*
Y1427632D03*
Y1424125D03*
X453074Y1431134D03*
X453064Y1611923D03*
X475237Y66575D03*
X475211Y61129D03*
X475167Y55935D03*
X484305Y158864D03*
X483204Y391362D03*
X474665Y1334095D03*
X480950Y1400385D03*
X479555Y1411144D03*
X469397Y1614682D03*
X469354Y1618626D03*
X475414Y1643242D03*
Y1659242D03*
Y1651242D03*
Y1667242D03*
X475344Y1673462D03*
Y1685462D03*
X492320Y305398D03*
X492294Y313582D03*
X496204Y391362D03*
X494102Y547947D03*
X495724Y1319592D03*
X488134Y1631038D03*
X506934Y86422D03*
X502564Y93582D03*
X509984Y209862D03*
X503984Y228362D03*
X505484Y237862D03*
X508484Y288862D03*
X508241Y315404D03*
X511204Y420862D03*
X507002Y507819D03*
Y511819D03*
Y519819D03*
Y515819D03*
Y523819D03*
Y527819D03*
Y539819D03*
X506793Y1347521D03*
X526204Y420862D03*
X525864Y478492D03*
X529884Y489112D03*
Y495112D03*
X528322Y1338837D03*
X539304Y103352D03*
X539374Y108062D03*
X550454Y149802D03*
X538434Y442376D03*
Y450330D03*
Y446396D03*
X538921Y1370319D03*
X555454Y131756D03*
X562204Y167112D03*
Y161362D03*
X562704Y184862D03*
X557548Y253202D03*
Y257202D03*
X573704Y167112D03*
X578418Y262632D03*
X569673Y305247D03*
X568024Y442656D03*
X568001Y451710D03*
X571899Y498546D03*
X581984Y514362D03*
X591304Y129642D03*
X598204Y174612D03*
X584934Y190092D03*
X584940Y198378D03*
Y210378D03*
Y202378D03*
Y206378D03*
X584704Y225362D03*
Y221362D03*
X599298Y257532D03*
X589548Y252202D03*
X588029Y296657D03*
Y311571D03*
Y304052D03*
X594289Y363354D03*
X591054Y488212D03*
X594484Y524862D03*
X604704Y164612D03*
X614440Y202878D03*
Y207378D03*
X602914Y458688D03*
X602704Y482362D03*
X603704Y514862D03*
X621291Y184022D03*
X630048Y249202D03*
Y260202D03*
X619704Y442862D03*
Y457862D03*
X641537Y88035D03*
X641497Y92085D03*
X648145Y134506D03*
X648128Y144982D03*
X640204Y230362D03*
X640629Y298297D03*
Y315587D03*
Y310962D03*
Y302247D03*
X635984Y392862D03*
X634704Y411362D03*
X634484Y406862D03*
X634704Y426362D03*
Y421362D03*
Y441862D03*
Y431362D03*
X634707Y436650D03*
X634704Y457862D03*
Y452862D03*
Y447862D03*
Y462862D03*
X634684Y482662D03*
X646709Y1653194D03*
X645209Y1695694D03*
X645204Y1718362D03*
Y1722362D03*
X649484Y93362D03*
X655094Y120412D03*
X649204Y161862D03*
Y166362D03*
Y171362D03*
X655729Y290371D03*
X648984Y392862D03*
X649484Y406862D03*
Y402362D03*
X649704Y416362D03*
Y441862D03*
Y431362D03*
Y452862D03*
Y457862D03*
Y447862D03*
Y467862D03*
Y462862D03*
X659220Y1392770D03*
Y1396300D03*
X673114Y391602D03*
X673661Y1412198D03*
X668556Y1642667D03*
X668577Y1655557D03*
X668502Y1651557D03*
X668604Y1672862D03*
Y1668862D03*
X671704Y1708362D03*
X666704Y1720362D03*
X671704Y1724362D03*
Y1716362D03*
Y1732362D03*
X683437Y115868D03*
X684884Y1442245D03*
X694631Y1632667D03*
X694706Y1644667D03*
X694716Y1648843D03*
X695104Y1658862D03*
X690104Y1670862D03*
X695104Y1666862D03*
Y1674862D03*
Y1682862D03*
X709907Y103308D03*
X713204Y161862D03*
Y157362D03*
X711804Y1412198D03*
X707626Y1563733D03*
X707596Y1583683D03*
X706564Y1607102D03*
Y1611022D03*
X707556Y1601963D03*
X721254Y1644550D03*
X721817Y1676500D03*
X733007Y95158D03*
X732977Y90998D03*
X760102Y89348D03*
X754617Y111288D03*
X748719Y142050D03*
X751184Y167537D03*
X751144Y276322D03*
X757596Y1579183D03*
Y1587183D03*
Y1592183D03*
X748139Y1674362D03*
X777773Y158026D03*
X777787Y153728D03*
X766726Y299279D03*
X766627Y311249D03*
X766154Y317432D03*
X763704Y393212D03*
Y418212D03*
Y423212D03*
Y428212D03*
X777824Y464862D03*
Y469862D03*
X762824Y464862D03*
Y469862D03*
Y488862D03*
Y483862D03*
Y479862D03*
X777824Y488862D03*
X762834Y497659D03*
X765004Y1388562D03*
Y1392762D03*
Y1406062D03*
X764904Y1410262D03*
X768636Y1594893D03*
X782644Y267822D03*
Y281822D03*
X780526Y299279D03*
X792904Y393462D03*
X778704Y413212D03*
Y408212D03*
Y403212D03*
Y398212D03*
X792904Y402500D03*
X778704Y418212D03*
Y423212D03*
X792824Y464862D03*
Y474862D03*
X791384Y483262D03*
X805946Y269800D03*
X808324Y469862D03*
Y474862D03*
X810136Y1577793D03*
Y1593793D03*
Y1601793D03*
Y1609793D03*
X824592Y274885D03*
Y279885D03*
X834445Y58632D03*
X831204Y166862D03*
Y176362D03*
X836119Y275045D03*
Y280045D03*
X830462Y389012D03*
Y397276D03*
X830484Y384400D03*
X830461Y413260D03*
X838484Y446800D03*
X827247Y494000D03*
X827254Y498082D03*
X841704Y495362D03*
X827254Y502082D03*
Y523082D03*
Y515082D03*
X851804Y162762D03*
X851394Y185812D03*
X859317Y273217D03*
X859287Y269057D03*
X852384Y476900D03*
X852136Y1577793D03*
Y1593793D03*
Y1601793D03*
Y1609793D03*
X874204Y166362D03*
X867970Y394620D03*
Y390620D03*
Y382415D03*
X868022Y406812D03*
Y418836D03*
X867804Y431462D03*
X860104Y503162D03*
Y499062D03*
X860254Y515582D03*
Y519582D03*
X882204Y176862D03*
Y171362D03*
X884199Y183169D03*
X884209Y187449D03*
X886412Y267407D03*
X880899Y289439D03*
X887806Y874405D03*
X888376Y920325D03*
X894136Y1577793D03*
Y1593793D03*
Y1601793D03*
Y1609793D03*
X936136Y1581393D03*
Y1585393D03*
Y1589393D03*
X958329Y484271D03*
X958304Y480262D03*
X958355Y540727D03*
X958356Y536806D03*
X961274Y997496D03*
X964463Y1551855D03*
X984608Y185347D03*
X984333Y276394D03*
X980778Y356910D03*
X989241Y363660D03*
X987829Y1551855D03*
X997396Y217233D03*
Y221233D03*
X996507Y363155D03*
X1018711Y195114D03*
X1018704Y199076D03*
X1016679Y203423D03*
Y210423D03*
Y214423D03*
Y218423D03*
Y222423D03*
X1011222Y363356D03*
X1021253Y517728D03*
Y512574D03*
X1011195Y1551855D03*
X1037317Y264130D03*
X1027317Y297264D03*
Y305313D03*
Y301313D03*
X1034561Y1551855D03*
X1044011Y291105D03*
X1045472Y502161D03*
X1057927Y1551855D03*
X1082173Y78553D03*
X1072689Y382141D03*
X1076648Y509645D03*
X1081293Y1551855D03*
X1079441Y1663950D03*
X1097703Y65262D03*
X1094594Y379251D03*
X1094474Y369061D03*
X1094534Y374131D03*
X1101514Y1679870D03*
Y1675970D03*
X1100034Y1672030D03*
X1107116Y55505D03*
X1118912Y1429074D03*
Y1432604D03*
X1104659Y1551855D03*
X1124587Y60545D03*
X1124487Y56545D03*
X1124587Y64545D03*
X1133353Y1448502D03*
X1122094Y1612320D03*
X1122064Y1608420D03*
X1151854Y211231D03*
X1140374Y377011D03*
X1145017Y1479313D03*
X1152454Y1618960D03*
X1153494Y373231D03*
X1159145Y1622340D03*
Y1626220D03*
Y1630090D03*
X1163909Y1642600D03*
X1159145Y1633880D03*
X1178729Y202174D03*
Y198174D03*
Y186174D03*
Y218174D03*
Y214174D03*
X1171496Y1448502D03*
X1175364Y1601100D03*
Y1609100D03*
Y1605100D03*
X1175244Y1612960D03*
X1182055D03*
X1174909Y1642600D03*
X1185555Y61311D03*
X1185455Y65811D03*
X1185475Y57111D03*
X1198284Y93200D03*
X1196460Y127804D03*
X1200459Y236592D03*
X1196479Y1642910D03*
X1185909Y1642600D03*
X1196319Y1688390D03*
X1207245Y57130D03*
X1210704Y189362D03*
X1213889Y1673963D03*
X1206565Y1677873D03*
X1213819Y1681773D03*
X1207089Y1688435D03*
X1231484Y94200D03*
Y98400D03*
X1220077Y140962D03*
X1231577Y168162D03*
X1220077Y185462D03*
X1231577Y172962D03*
X1217889Y1688700D03*
X1245366Y98785D03*
X1242044Y191279D03*
X1242077Y197462D03*
X1251077Y201562D03*
Y211762D03*
Y205362D03*
X1262077Y217462D03*
X1251077Y215762D03*
X1262077Y233462D03*
Y221462D03*
X1251077Y219662D03*
X1262077Y229462D03*
Y225462D03*
Y243562D03*
Y238662D03*
Y247562D03*
X1251162Y245442D03*
X1262277Y251562D03*
X1270238Y88572D03*
Y96768D03*
X1281775Y98828D03*
X1269577Y233462D03*
X1291391Y1370043D03*
X1305518Y64572D03*
X1308247Y81775D03*
X1299149Y81169D03*
X1328048Y261514D03*
X1322294Y1347521D03*
X1354422Y1334095D03*
X1371736Y81111D03*
X1375221Y1330142D03*
X1373110Y1417374D03*
X1373950Y1413019D03*
X1388168Y1334095D03*
X1394602Y1390306D03*
X1382529Y1400684D03*
Y1404207D03*
X1387160Y1390335D03*
X1382524Y1407727D03*
X1411867Y227948D03*
X1406780Y1330042D03*
X1409892Y1565037D03*
X1409832Y1576197D03*
X1409892Y1570037D03*
X1402384Y1586400D03*
Y1590200D03*
X1405484Y1626362D03*
Y1634362D03*
Y1638362D03*
X1418678Y1334095D03*
X1420317Y1516435D03*
X1420557Y1532255D03*
X1420317Y1521335D03*
X1420557Y1537155D03*
X1420707Y1548375D03*
Y1543475D03*
X1423754Y1603262D03*
X1427254Y1608442D03*
X1427194Y1616932D03*
X1413959Y1622200D03*
X1439705Y1330533D03*
X1430214Y1393959D03*
X1429226Y1417125D03*
Y1413125D03*
Y1409125D03*
Y1420625D03*
Y1427632D03*
Y1424125D03*
X1429254Y1431150D03*
X1443164Y1590382D03*
X1443884Y1606800D03*
Y1602600D03*
X1439284Y1632900D03*
Y1620300D03*
X1444217Y1665495D03*
X1444127Y1673955D03*
X1444131Y1669629D03*
X1447984Y211862D03*
Y215862D03*
X1450806Y1334095D03*
X1457091Y1400385D03*
X1455696Y1411144D03*
X1455392Y1560037D03*
Y1565037D03*
X1453114Y1586262D03*
X1457449Y1612800D03*
X1474367Y225448D03*
Y233448D03*
X1466867Y242448D03*
X1474569Y263378D03*
Y255378D03*
X1466569Y271378D03*
X1471865Y1319592D03*
X1484392Y281456D03*
X1491884Y421982D03*
X1487864Y431972D03*
X1482934Y1347521D03*
X1498893Y280027D03*
X1504463Y1338837D03*
X1519484Y116462D03*
X1518484Y136162D03*
X1520052Y243362D03*
Y235116D03*
Y258616D03*
Y254616D03*
X1511385Y288030D03*
X1519742Y284956D03*
X1515862Y1369919D03*
X1545436Y152873D03*
X1546221Y634165D03*
X1566063Y655416D03*
Y659416D03*
X1568940Y735691D03*
Y732165D03*
X1592062Y219526D03*
Y227526D03*
X1591823Y248008D03*
X1591843Y243890D03*
X1591803Y252126D03*
X1607264Y654542D03*
X1605444Y722582D03*
X1600400Y1420169D03*
Y1433669D03*
Y1438169D03*
Y1452071D03*
X1614304Y586762D03*
X1620386Y1426366D03*
Y1429896D03*
X1629517Y117627D03*
Y129627D03*
Y121627D03*
X1634827Y1445794D03*
X1649066Y652601D03*
Y686601D03*
Y720601D03*
X1646091Y1476695D03*
X1664787Y550382D03*
X1657713Y544622D03*
X1665844Y598522D03*
X1656892Y635791D03*
Y669791D03*
Y703791D03*
X1672970Y1445794D03*
X1671582Y1493362D03*
Y1501362D03*
Y1516862D03*
Y1533862D03*
Y1520862D03*
Y1545862D03*
X1671657Y1561557D03*
X1671582Y1557557D03*
X1671657Y1581321D03*
X1687415Y495290D03*
Y499290D03*
X1704778Y369773D03*
Y373773D03*
X1702868Y401485D03*
X1696760Y525507D03*
Y529507D03*
Y533507D03*
Y549507D03*
X1703904Y688130D03*
Y691730D03*
Y695330D03*
X1704944Y726552D03*
X1714701Y174970D03*
X1717674Y364962D03*
X1706511Y655141D03*
X1725402Y112867D03*
X1722913Y474859D03*
Y478869D03*
X1725639Y688211D03*
X1751872Y100307D03*
X1754204Y372452D03*
X1739185Y486837D03*
X1744419Y1451841D03*
X1763552Y76797D03*
X1763522Y72637D03*
X1766494Y164362D03*
X1760125Y433221D03*
X1763225Y461393D03*
X1763335Y465893D03*
X1760740Y692742D03*
X1757509Y1475951D03*
X1785162Y92927D03*
X1774859Y169903D03*
X1782912Y291876D03*
X1782927Y295643D03*
Y299243D03*
X1790647Y70987D03*
X1802749Y165565D03*
X1795255Y367866D03*
X1794553Y390252D03*
X1787783Y403932D03*
Y410432D03*
Y418932D03*
Y425432D03*
X1798511Y1527366D03*
X1806274Y156557D03*
X1813234Y179897D03*
X1819283Y407932D03*
Y403225D03*
X1818783Y421432D03*
Y427932D03*
X1818725Y472521D03*
X1809625Y1494318D03*
Y1498318D03*
X1818198Y1504241D03*
X1826535Y363731D03*
X1820216Y371329D03*
X1826535Y367701D03*
X1826153Y379552D03*
X1820053Y395552D03*
X1826153Y383952D03*
X1835425Y459121D03*
X1838819Y182712D03*
X1845939Y176722D03*
G54D230*
X926789Y986734D03*
G54D104*
X205439Y684016D03*
G54D221*
X841240Y1407480D03*
X832154Y1411244D03*
X828390Y1420330D03*
X832154Y1429416D03*
X841240Y1433180D03*
X850326Y1411244D03*
X854090Y1420330D03*
X850326Y1429416D03*
X1003390Y1420330D03*
X1016240Y1407480D03*
X1007154Y1411244D03*
Y1429416D03*
X1016240Y1433180D03*
X1025326Y1411244D03*
X1029090Y1420330D03*
X1025326Y1429416D03*
G54D311*
X1806657Y1502389D03*
G54D131*
X285803Y243637D03*
X301551D03*
X312693Y59753D03*
X328441D03*
X747269Y79238D03*
X763017D03*
X890259Y256240D03*
X906007D03*
X1655999Y385598D03*
X1671747D03*
X1784364Y61037D03*
X1800112D03*
G54D222*
X841240Y1420330D03*
X1016240D03*
G54D240*
X986830Y-11500D03*
Y18500D03*
X1296222Y-21511D03*
Y-1511D03*
Y18489D03*
X1488581Y-21511D03*
Y-1511D03*
Y18489D03*
G54D141*
X333568Y388690D03*
Y394596D03*
Y400628D03*
Y406534D03*
X340654Y394596D03*
Y388690D03*
Y406534D03*
Y400628D03*
X366714Y363438D03*
Y369344D03*
Y375696D03*
Y381602D03*
Y400628D03*
Y406534D03*
X373800Y363438D03*
Y369344D03*
Y375696D03*
Y381602D03*
Y406534D03*
Y400628D03*
G54D21*
X49280Y337402D03*
X41870Y1511291D03*
X441043Y1672205D03*
Y1718465D03*
X1416437Y1672204D03*
Y1718464D03*
X1808192Y1569255D03*
X1812980Y502472D03*
G54D114*
X250326Y185236D03*
X368437D03*
G54D105*
X205161Y691777D03*
X1651812Y596805D03*
G54D132*
X306757Y112844D03*
Y124262D03*
X1022484Y146805D03*
Y158223D03*
X1776878Y113968D03*
Y125386D03*
G54D123*
X260128Y109803D03*
X263671D03*
X267214D03*
X270758D03*
X693284Y113928D03*
X696827D03*
X700370D03*
X703914D03*
X1735249Y110927D03*
X1738792D03*
X1742335D03*
X1745879D03*
G54D213*
X779270Y1580602D03*
Y1582570D03*
Y1584539D03*
Y1586507D03*
Y1588476D03*
Y1590444D03*
X796888Y1582570D03*
Y1580602D03*
Y1590444D03*
Y1588476D03*
Y1586507D03*
Y1584539D03*
X821270Y1580602D03*
Y1582570D03*
Y1584539D03*
Y1586507D03*
Y1588476D03*
Y1590444D03*
X838888Y1582570D03*
Y1580602D03*
Y1590444D03*
Y1588476D03*
Y1586507D03*
Y1584539D03*
X863270Y1580602D03*
Y1582570D03*
Y1584539D03*
Y1586507D03*
Y1588476D03*
Y1590444D03*
X880888Y1582570D03*
Y1580602D03*
Y1590444D03*
Y1588476D03*
Y1586507D03*
Y1584539D03*
X905270Y1580602D03*
Y1582570D03*
Y1584539D03*
Y1586507D03*
Y1588476D03*
Y1590444D03*
X922888Y1582570D03*
Y1580602D03*
Y1590444D03*
Y1588476D03*
Y1586507D03*
Y1584539D03*
G54D231*
X925102Y1531780D03*
X933290D03*
G54D12*
X14092Y292892D03*
Y295452D03*
X28068D03*
Y292892D03*
X44692Y293392D03*
Y295952D03*
X58668D03*
Y293392D03*
X1744422Y154282D03*
Y156842D03*
X1758398D03*
Y154282D03*
G54D30*
X57646Y12480D03*
X137272D03*
X186622D03*
X266858D03*
X315598D03*
X502528Y33268D03*
X582154D03*
X631504D03*
X711740D03*
X760480D03*
X1532055Y12480D03*
X1611681D03*
X1661031D03*
X1741267D03*
X1790007D03*
G54D150*
X384600Y1595100D03*
X411162Y1414126D03*
X710486Y77695D03*
X919488Y1660733D03*
X956800Y1663725D03*
X1132187Y1582738D03*
G54D204*
X765160Y270763D03*
G54D303*
X1765429Y276192D03*
G54D312*
X1809624Y1502387D03*
G54D160*
X427474Y1412789D03*
X1403615D03*
G54D151*
X386824Y1657204D03*
Y1678070D03*
X401824Y1657204D03*
X396824D03*
X391824D03*
Y1678070D03*
X396824D03*
X401824D03*
X1457757Y1655836D03*
X1452757D03*
Y1676702D03*
X1457757D03*
X1467757Y1655836D03*
X1462757D03*
Y1676702D03*
X1467757D03*
G54D115*
X229825Y423824D03*
Y426383D03*
Y428942D03*
Y431501D03*
Y434060D03*
Y436619D03*
Y439179D03*
Y441738D03*
Y444297D03*
Y446856D03*
Y449415D03*
Y451974D03*
X251873Y428942D03*
Y426383D03*
Y423824D03*
Y444297D03*
Y441738D03*
Y439179D03*
Y436619D03*
Y434060D03*
Y431501D03*
Y451974D03*
Y449415D03*
Y446856D03*
X464994Y513372D03*
Y515931D03*
Y518490D03*
Y521049D03*
Y523608D03*
Y526167D03*
Y528727D03*
Y531286D03*
Y533845D03*
Y536404D03*
Y538963D03*
Y541522D03*
X487042Y526167D03*
Y523608D03*
Y521049D03*
Y518490D03*
Y515931D03*
Y513372D03*
Y541522D03*
Y538963D03*
Y536404D03*
Y533845D03*
Y531286D03*
Y528727D03*
G54D124*
X277098Y185236D03*
X395208D03*
G54D13*
X25320Y146662D03*
X40600Y1580802D03*
X493180Y647432D03*
X932820Y1310432D03*
X1112670Y541642D03*
X1807990Y1656032D03*
X1835620Y210432D03*
G54D223*
X892000Y886962D03*
X887000D03*
X882000D03*
Y907762D03*
X887000D03*
X892000D03*
X897000Y886962D03*
Y907762D03*
X1540989Y601238D03*
Y622038D03*
X1555989Y601238D03*
X1550989D03*
X1545989D03*
Y622038D03*
X1550989D03*
X1555989D03*
G54D232*
X929196Y1546760D03*
G54D250*
X1025215Y282445D03*
X1035451Y280083D03*
Y282445D03*
X1797432Y1517261D03*
Y1514899D03*
X1807668D03*
G54D106*
X199866Y680633D03*
Y682602D03*
Y684570D03*
Y686539D03*
Y688507D03*
Y690476D03*
Y692444D03*
X432640Y1632513D03*
Y1630545D03*
Y1628576D03*
Y1626608D03*
Y1624639D03*
Y1622671D03*
Y1620702D03*
Y1634482D03*
X451340Y1632513D03*
Y1630545D03*
Y1628576D03*
Y1626608D03*
Y1624639D03*
Y1622671D03*
Y1620702D03*
Y1634482D03*
X919407Y981813D03*
Y983781D03*
Y985750D03*
Y987718D03*
Y989687D03*
Y991655D03*
X934171Y981813D03*
Y991655D03*
Y989687D03*
Y987718D03*
Y985750D03*
Y983781D03*
X1657107Y607949D03*
Y605980D03*
Y604012D03*
Y602043D03*
Y600075D03*
Y598106D03*
Y596138D03*
G54D142*
X333568Y391643D03*
Y403581D03*
X340654Y391643D03*
Y403581D03*
X366714Y366391D03*
Y378649D03*
Y403581D03*
X373800Y366391D03*
Y378649D03*
Y403581D03*
G54D133*
X303147Y572658D03*
Y575158D03*
Y577658D03*
Y580158D03*
Y582658D03*
Y585158D03*
Y587658D03*
Y590158D03*
X324347Y572658D03*
Y575158D03*
Y577658D03*
Y580158D03*
Y582658D03*
Y585158D03*
Y587658D03*
Y590158D03*
G54D205*
X765160Y275881D03*
G54D241*
X999456Y189090D03*
G54D214*
X828780Y1694890D03*
Y1684890D03*
X818780Y1694890D03*
Y1684890D03*
X828780Y1704890D03*
X818780D03*
X828780Y1714890D03*
X818780D03*
X853780Y1694890D03*
Y1684890D03*
Y1704890D03*
Y1714890D03*
X863780Y1694890D03*
Y1684890D03*
Y1704890D03*
Y1714890D03*
X888780Y1684890D03*
Y1694890D03*
Y1704890D03*
Y1714890D03*
X898780Y1684890D03*
Y1694890D03*
Y1704890D03*
Y1714890D03*
X918780Y1684890D03*
Y1694890D03*
Y1704890D03*
Y1714890D03*
X928780Y1684890D03*
X938780D03*
X928780Y1694890D03*
X938780D03*
X928780Y1704890D03*
X938780D03*
X928780Y1714890D03*
X958780Y1694890D03*
Y1684890D03*
Y1704890D03*
Y1714890D03*
X968780Y1694890D03*
Y1684890D03*
Y1704890D03*
Y1714890D03*
X993780Y1684890D03*
Y1694890D03*
X1003780Y1684890D03*
Y1694890D03*
X993780Y1704890D03*
Y1714890D03*
X1003780Y1704890D03*
Y1714890D03*
X1028780Y1684890D03*
Y1694890D03*
X1038780Y1684890D03*
Y1694890D03*
X1028780Y1704890D03*
Y1714890D03*
X1038780Y1704890D03*
Y1714890D03*
G54D22*
X42809Y363429D03*
X39008D03*
X36524Y392288D03*
X54620Y58834D03*
X50308D03*
X59322Y363429D03*
X51114D03*
X56163Y414020D03*
X59833Y1615851D03*
Y1606851D03*
X50333Y1615851D03*
X54333D03*
X47333Y1656851D03*
X53700Y1674717D03*
X63429Y363429D03*
X67681D03*
X69523Y414020D03*
X77588Y656669D03*
X75274Y1546611D03*
X74100Y1615817D03*
X78000D03*
X73833Y1683751D03*
X77833Y1683651D03*
X69833D03*
X86302Y637122D03*
X89461Y660648D03*
X85565Y660656D03*
X93547Y685662D03*
X82311Y709866D03*
X84048Y1571478D03*
X88048D03*
X92251D03*
X81900Y1615817D03*
X85800D03*
X81833Y1683651D03*
X110987Y541732D03*
X97549Y685582D03*
X100931Y702294D03*
X100914Y709264D03*
X107170Y1517259D03*
X96251Y1571478D03*
X104900Y1608917D03*
X124170Y480330D03*
X120060D03*
X115060Y541739D03*
X127377Y541972D03*
X123257Y541902D03*
X119087Y541812D03*
X114021Y663874D03*
X118021D03*
X135006Y490632D03*
X130006D03*
X141103Y480330D03*
X145213D03*
X149568Y1400187D03*
X155098Y1563182D03*
X159107Y1563110D03*
X158118Y1708534D03*
X166631Y1409462D03*
X191267Y699543D03*
X187711Y1400187D03*
X176793Y1579491D03*
X195888Y575488D03*
X199941Y597590D03*
X195888Y609488D03*
X199941Y631590D03*
X195888Y643488D03*
X193461Y666660D03*
X195467Y699543D03*
X204174Y1408762D03*
X200720Y1710379D03*
X222907Y318773D03*
X247487Y104777D03*
X243487D03*
X254297Y124060D03*
X250297D03*
X246297D03*
X242297D03*
X254756Y156819D03*
X271797Y124060D03*
X261297D03*
X268297Y127560D03*
X259933Y143819D03*
X260100Y153979D03*
X263240Y239299D03*
X289357Y116020D03*
X277240Y239299D03*
X303573Y1358370D03*
X313995Y232266D03*
X306956Y559884D03*
X320614Y1366708D03*
X325617Y81260D03*
X332700Y138879D03*
X328700D03*
X338249Y224026D03*
X328965Y231756D03*
X332465D03*
X324106Y599390D03*
X328106D03*
X335673Y1336070D03*
X339811Y123194D03*
X342285Y210626D03*
X346203Y210644D03*
X346249Y224026D03*
X342249D03*
X352742Y1343910D03*
X367807Y1322109D03*
X386004Y1329935D03*
X385123Y1643266D03*
X378547Y1643272D03*
X374391Y1650968D03*
X374509Y1682676D03*
X399935Y1322109D03*
X391563Y1642736D03*
X414595Y944490D03*
X418595D03*
X410795D03*
X414616Y936165D03*
X414626Y959273D03*
X410826D03*
X418626D03*
X418671Y973774D03*
X414626D03*
X410871D03*
X410800Y988185D03*
X414600D03*
X418600D03*
X414550Y1002667D03*
X410838D03*
X418550D03*
X418591Y1017127D03*
X410816D03*
X414591D03*
X417104Y1329935D03*
X407125Y1419520D03*
X407557Y1655402D03*
X422395Y944490D03*
X422426Y959273D03*
X422471Y973774D03*
X422400Y988185D03*
X422350Y1002667D03*
X422391Y1017127D03*
X432063Y1322109D03*
X429383Y1597171D03*
X433383D03*
X437840Y122288D03*
X452071Y261006D03*
X445720Y399279D03*
X451720Y408279D03*
X451520Y479354D03*
X442520D03*
X437520D03*
X447520D03*
X448873Y1329935D03*
X446258Y1436148D03*
X449778D03*
X438020Y1564954D03*
X450020D03*
X437990Y1644294D03*
X441990D03*
X468323Y261088D03*
X455720Y408279D03*
X462720Y399279D03*
X466520Y470354D03*
X456520Y479354D03*
X461520D03*
X462704Y944490D03*
X466704Y936165D03*
X462704D03*
X458904D03*
X466704Y944490D03*
X458904D03*
X466704Y959273D03*
X458904D03*
X462704D03*
X466704Y973774D03*
X458904D03*
X462704D03*
X466704Y988185D03*
X462704D03*
X458904D03*
X466704Y1002667D03*
X458904D03*
X462704D03*
X466704Y1017127D03*
X458904D03*
X462704D03*
X464191Y1322109D03*
X468620Y1404479D03*
X459520Y1549454D03*
X456020Y1574954D03*
X464020D03*
X457220Y1586512D03*
X464930Y1651749D03*
X473500Y234879D03*
X475252Y261027D03*
X481500Y293879D03*
X478720Y363379D03*
X482720D03*
X479169Y479213D03*
X474169D03*
X484169D03*
X470504Y936165D03*
Y944490D03*
Y959273D03*
Y973774D03*
Y988185D03*
Y1002667D03*
Y1017127D03*
X481254Y1329927D03*
X477368Y1404487D03*
X472701D03*
X481468D03*
X476281Y1416010D03*
X480252D03*
X499096Y261731D03*
X492936Y261774D03*
X485500Y293879D03*
X494720Y363379D03*
X488169Y479213D03*
X498169D03*
X493169D03*
X496319Y1335535D03*
X485712Y1421994D03*
X517020Y83379D03*
X512220D03*
X515804Y261980D03*
X509496Y262056D03*
X514720Y363379D03*
X510720D03*
X502720D03*
X504040Y378419D03*
X513720Y392879D03*
X509720D03*
X503169Y470213D03*
X513382Y1343910D03*
X525720Y290879D03*
X527720Y363379D03*
X520830Y380899D03*
X529720Y392879D03*
X525720D03*
X528447Y1358333D03*
X535720Y363379D03*
X545510Y1366708D03*
X552720Y164879D03*
X559300Y417274D03*
X552000Y1456879D03*
X569300Y408424D03*
X589330Y88037D03*
X593240D03*
X597220Y88379D03*
X598724Y150388D03*
X593220Y179379D03*
Y187379D03*
X596800Y502049D03*
X614384Y121909D03*
X610104D03*
X602278D03*
X599720Y179379D03*
Y187379D03*
X614095Y275147D03*
X608895D03*
X611609Y320937D03*
X603822Y320887D03*
X622000Y88379D03*
X630951Y121909D03*
X626699D03*
X622592D03*
X627064Y253219D03*
X619496Y320987D03*
X627236Y320968D03*
X647725Y1646211D03*
X643725D03*
X653820Y84279D03*
X655000Y91879D03*
X661865Y508571D03*
X654927Y525197D03*
X659039Y518108D03*
X663187Y1400212D03*
X650225Y1702711D03*
X676643Y108902D03*
X680623D03*
X670220Y498379D03*
X675220D03*
X680220D03*
X675220Y511379D03*
X680250Y1408587D03*
X694453Y128185D03*
X687453D03*
X683453D03*
X688290Y382439D03*
X690220Y511379D03*
X685220D03*
X704000Y76379D03*
X704953Y128185D03*
X700963Y128245D03*
X713220Y380879D03*
X711220Y511379D03*
X705220D03*
X701330Y1400212D03*
X711780Y1617447D03*
X723933Y135505D03*
X727000Y368242D03*
X722500D03*
X718393Y1408587D03*
X725552Y1602610D03*
X719612Y1602700D03*
X722630Y1649987D03*
X726720Y1644457D03*
X735800Y368242D03*
X731400D03*
X745220Y498379D03*
Y524879D03*
X730680Y1644457D03*
X760193Y100745D03*
X758220Y441879D03*
X751220Y524879D03*
X761700Y511979D03*
X759859Y1689112D03*
X765160Y281339D03*
X776000Y363879D03*
X764000D03*
X771960Y363999D03*
X767960D03*
X777220Y445379D03*
X772952Y1584210D03*
X763359Y1723612D03*
X789720Y425379D03*
X787520Y516999D03*
X798400Y363217D03*
X806000D03*
X796546Y413143D03*
X819114Y117715D03*
X827114D03*
X823114D03*
X826614Y147215D03*
X813800Y383117D03*
X818000D03*
X824220Y425379D03*
X816670Y502439D03*
X812810Y516899D03*
X815252Y1585110D03*
X839360Y117599D03*
X831114Y117715D03*
X840220Y184879D03*
Y197879D03*
X836300Y421417D03*
X844935Y90268D03*
X844220Y184879D03*
Y197879D03*
X856190Y187127D03*
X845505Y284508D03*
Y294794D03*
X849000Y438217D03*
X857252Y1585110D03*
X886503Y278804D03*
X891747Y867871D03*
X887897D03*
X881372Y914972D03*
X899252Y1585110D03*
X921757Y964704D03*
X916974D03*
X926823Y964669D03*
X957027Y195914D03*
X947348Y985594D03*
X961137Y195866D03*
X981445Y175600D03*
X977195Y203940D03*
X981789Y360977D03*
X987139Y424473D03*
X1005699Y167360D03*
X996415Y175090D03*
X999915D03*
X1005395Y214440D03*
X991140Y424473D03*
X1009735Y153960D03*
X1015275Y153966D03*
X1016506Y424321D03*
X1012506D03*
X1023220Y182116D03*
X1034835Y296227D03*
X1031025D03*
X1025958Y362681D03*
X1029922Y362686D03*
X1043424Y283015D03*
X1038606Y296227D03*
X1091457Y1641367D03*
X1103457D03*
X1113140Y1670008D03*
X1105457Y1669967D03*
X1122879Y1436516D03*
X1124862Y1617767D03*
X1124762Y1625427D03*
X1139942Y1444891D03*
X1152720Y183379D03*
X1156720D03*
X1161022Y1436516D03*
X1164830Y1657632D03*
X1159930D03*
X1173374Y170148D03*
X1178085Y1444891D03*
X1181930Y1657632D03*
X1175830D03*
X1170930D03*
X1191206Y136066D03*
X1185030Y1627478D03*
X1192500Y1657942D03*
X1197400D03*
X1186830Y1657632D03*
X1197240Y1703422D03*
X1192340D03*
X1211720Y207379D03*
X1207220D03*
X1215720D03*
X1212610Y219169D03*
X1207530Y219069D03*
X1216610Y219169D03*
X1209900Y244090D03*
X1216656D03*
X1203267Y1653002D03*
X1208010Y1703467D03*
X1203110D03*
X1213910Y1703732D03*
X1218810D03*
X1263150Y300033D03*
X1251150D03*
X1281940Y87789D03*
X1267322Y103681D03*
X1274864Y107229D03*
X1267150Y300033D03*
X1279834Y1358606D03*
X1286013Y79416D03*
X1297342Y287924D03*
X1293398D03*
X1290437Y749482D03*
X1296875Y1366944D03*
X1313788Y62317D03*
X1303264Y74807D03*
X1307542Y298334D03*
X1303542D03*
X1311820Y1335535D03*
X1328883Y1343910D03*
X1343948Y1322109D03*
X1362145Y1329935D03*
X1366369Y86587D03*
X1366001Y95612D03*
X1376076Y1322109D03*
X1394736Y944489D03*
X1390736D03*
X1390719Y936155D03*
X1386936Y944489D03*
X1386967Y959272D03*
X1390767D03*
X1394767D03*
X1390812Y973773D03*
X1394812D03*
X1387012D03*
X1394741Y988184D03*
X1390741D03*
X1386941D03*
X1390691Y1002666D03*
X1394691D03*
X1386891D03*
X1394732Y1017126D03*
X1386869D03*
X1390732D03*
X1393245Y1329935D03*
X1382347Y1394120D03*
X1385066Y1419520D03*
X1398536Y944489D03*
X1398567Y959272D03*
X1398612Y973773D03*
X1398541Y988184D03*
X1398491Y1002666D03*
X1398532Y1017126D03*
X1408204Y1322109D03*
X1402680Y1600289D03*
X1425014Y1329935D03*
X1427349Y1436658D03*
X1423519Y1436668D03*
X1422680Y1584917D03*
X1438845Y944489D03*
X1435045D03*
X1438845Y936164D03*
X1442845Y944489D03*
Y936164D03*
X1435045D03*
X1442845Y959272D03*
X1438845D03*
X1435045D03*
X1438845Y973773D03*
X1442845D03*
X1435045D03*
X1442845Y988184D03*
X1438845D03*
X1435045D03*
X1438845Y1002666D03*
X1435045D03*
X1442845D03*
X1438845Y1017126D03*
X1442845D03*
X1435045D03*
X1440332Y1322109D03*
X1444720Y1404479D03*
X1438547Y1640852D03*
X1443617Y1640832D03*
X1455600Y291217D03*
X1447800D03*
X1458300Y364479D03*
X1449777Y364513D03*
X1453777D03*
X1451780Y407439D03*
X1456777Y421088D03*
X1446645Y936164D03*
Y944489D03*
Y959272D03*
Y973773D03*
Y988184D03*
Y1002666D03*
Y1017126D03*
X1457395Y1329927D03*
X1453509Y1404487D03*
X1448842D03*
X1457609D03*
X1452422Y1416010D03*
X1456393D03*
X1454167Y1640932D03*
X1459127D03*
X1448507Y1640842D03*
X1463000Y155879D03*
X1466777Y364513D03*
X1470777D03*
X1472460Y1335535D03*
X1461803Y1422024D03*
X1472565Y1628119D03*
X1463767Y1640932D03*
X1493384Y413805D03*
X1481384D03*
X1489523Y1343910D03*
X1504602Y295274D03*
X1504278Y284972D03*
X1504602Y307273D03*
X1498184Y364215D03*
X1497384Y413805D03*
X1504588Y1358333D03*
X1524654Y54632D03*
X1517263Y193354D03*
X1521828Y299292D03*
X1521651Y1366708D03*
X1528654Y54632D03*
X1537746Y1303435D03*
X1547697Y121295D03*
X1543720Y584379D03*
X1548720D03*
X1557287Y628952D03*
X1563994Y581234D03*
X1567994D03*
X1624353Y1433808D03*
X1644360Y202757D03*
X1648400Y202747D03*
X1652610Y397219D03*
X1647110Y428719D03*
X1649291Y549252D03*
X1649220Y615179D03*
X1653220D03*
X1641416Y1442183D03*
X1661110Y428719D03*
X1664040Y564169D03*
X1672040D03*
X1668040D03*
X1657220Y615179D03*
X1662496Y1433808D03*
X1673872Y428162D03*
X1686154Y428702D03*
X1676040Y564169D03*
X1680040D03*
X1679559Y1442183D03*
X1703932Y226536D03*
X1704624Y428192D03*
X1701124D03*
X1703720Y503879D03*
X1698720D03*
X1702320Y536489D03*
X1695443Y713362D03*
X1718608Y105901D03*
X1717418Y125184D03*
X1721418D03*
X1715044Y407062D03*
X1718931Y407054D03*
X1710408Y420462D03*
X1708977Y465321D03*
X1713977D03*
X1708030Y688269D03*
X1713159Y688292D03*
X1714320Y704779D03*
X1714298Y711632D03*
X1709107Y722302D03*
X1722608Y105901D03*
X1736418Y125184D03*
X1729418D03*
X1725418D03*
X1725500Y377879D03*
X1722500Y368879D03*
X1733780Y393287D03*
X1729810D03*
X1737660D03*
X1730290Y417357D03*
X1734290D03*
X1736611Y490784D03*
X1746918Y125184D03*
X1743418Y128684D03*
X1746366Y283549D03*
X1743170Y405317D03*
X1764478Y117144D03*
X1769230Y304934D03*
X1758563D03*
X1765663D03*
X1762163D03*
X1754963D03*
X1772863D03*
X1778810Y452157D03*
X1790738Y82384D03*
X1819461Y150818D03*
X1813700Y1497304D03*
X1826075Y1504858D03*
X1843166Y238863D03*
G54D313*
X1879155Y344948D03*
Y468898D03*
D03*
Y592848D03*
D03*
Y716798D03*
D03*
Y840748D03*
X1900275Y-19342D03*
X1889155Y344948D03*
Y468898D03*
D03*
X1900275Y592858D03*
X1889155Y592848D03*
D03*
X1900275Y716808D03*
X1889155Y716798D03*
D03*
X1900275Y840758D03*
D03*
X1889155Y840748D03*
X1900275Y964708D03*
X1910275Y-19342D03*
Y592858D03*
Y716808D03*
Y840758D03*
D03*
Y964708D03*
X1921395Y-19332D03*
X1931395D03*
Y592868D03*
X1921395D03*
X1931395D03*
X1921395D03*
Y1205068D03*
X1931395D03*
X1952395Y-19152D03*
X1942395D03*
Y593048D03*
X1952395D03*
X1942395D03*
X1952395D03*
Y1205248D03*
X1942395D03*
X1963362Y-19190D03*
Y593010D03*
D03*
Y1205210D03*
X1984482Y-19180D03*
X1973362Y-19190D03*
X1984482Y593020D03*
D03*
X1973362Y593010D03*
D03*
X1984482Y1205220D03*
X1973362Y1205210D03*
X1994482Y-19180D03*
Y593020D03*
D03*
Y1205220D03*
X2005452Y-19180D03*
X2015452D03*
Y593020D03*
X2005452D03*
X2015452D03*
X2005452D03*
Y1205220D03*
X2015452D03*
X2026452Y-19000D03*
Y593200D03*
D03*
Y1205400D03*
X2047419Y-19038D03*
X2036452Y-19000D03*
X2047419Y593162D03*
X2036452Y593200D03*
X2047419Y593162D03*
X2036452Y593200D03*
X2047419Y1205362D03*
X2036452Y1205400D03*
X2057419Y-19038D03*
Y593162D03*
D03*
Y1205362D03*
X2068539Y593172D03*
X2078539D03*
Y1205372D03*
X2068539D03*
G54D304*
X1772468Y284558D03*
G54D31*
X60303Y20354D03*
X174685Y637367D03*
X174393Y668511D03*
X205159Y1430034D03*
X312921Y24291D03*
X393067Y1354446D03*
X422833D03*
X453169D03*
X468443Y1379662D03*
X482543Y1353962D03*
X505185Y41142D03*
X526478Y1439952D03*
X718638Y1429579D03*
X757803Y45079D03*
X922441Y237697D03*
X929331Y160413D03*
X1077638Y133866D03*
X1178470Y1466363D03*
X1369208Y1353946D03*
X1398974D03*
X1429310D03*
X1444043Y1379362D03*
X1459076Y1353946D03*
X1502956Y1439530D03*
X1534712Y20354D03*
X1682882Y618174D03*
Y669109D03*
X1679944Y1463655D03*
X1769790Y194789D03*
X1787330Y24291D03*
X1799350Y194789D03*
X1836248Y269763D03*
Y299056D03*
G54D40*
X70472Y173228D03*
Y236220D03*
G54D14*
X17016Y193362D03*
Y200362D03*
X27736Y232362D03*
Y240362D03*
X33001Y401000D03*
X57123Y421746D03*
X59290Y1524094D03*
Y1532094D03*
Y1528194D03*
Y1548094D03*
Y1552094D03*
Y1544094D03*
Y1556094D03*
X78007Y436519D03*
Y432519D03*
X81890Y391391D03*
Y395865D03*
Y382219D03*
X88317Y428319D03*
Y424319D03*
Y420319D03*
Y450519D03*
Y446519D03*
X87656Y667734D03*
X88551Y718879D03*
X93204Y1593867D03*
Y1585852D03*
Y1589852D03*
X93279Y1611821D03*
Y1605867D03*
Y1623821D03*
X93189Y1634362D03*
Y1638362D03*
X88736Y1690362D03*
X96671Y169263D03*
X107941Y232128D03*
X104936Y493578D03*
X104966Y497374D03*
Y501374D03*
Y505374D03*
Y509374D03*
Y513374D03*
X96030Y512870D03*
X95836Y696262D03*
X107290Y1528594D03*
Y1532694D03*
Y1552594D03*
Y1556594D03*
X96516Y1655800D03*
Y1651800D03*
X123935Y278875D03*
X123916Y274800D03*
X123935Y306236D03*
X127498Y396071D03*
Y388071D03*
Y392071D03*
Y384071D03*
X116998Y404571D03*
X124254Y636153D03*
Y640103D03*
X119574Y1589352D03*
X124354Y1604367D03*
X125074Y1622321D03*
X124074Y1637862D03*
X121736Y1696362D03*
X127573Y1723182D03*
X131466Y525374D03*
X130053Y1535855D03*
X130205Y1541874D03*
X130297Y1547935D03*
X140836Y1708362D03*
X138583Y1720092D03*
X158416Y413362D03*
X144013Y510810D03*
Y514810D03*
Y518810D03*
Y526830D03*
X152824Y519281D03*
X148236Y1716362D03*
X175083Y1723592D03*
X181912Y421383D03*
Y425383D03*
Y443383D03*
Y430883D03*
X191158Y689683D03*
X182083Y1729092D03*
Y1733092D03*
X204907Y567981D03*
X197081Y584791D03*
X204907Y601981D03*
X197081Y618791D03*
X204907Y635981D03*
X197081Y652791D03*
X193686Y675092D03*
X192966Y1535377D03*
X192907Y1539678D03*
X192799Y1548430D03*
X192707Y1552940D03*
X205236Y1709862D03*
X205134Y1714017D03*
X212070Y420735D03*
Y424735D03*
Y428735D03*
Y436735D03*
Y432735D03*
Y440735D03*
Y444735D03*
Y448735D03*
Y457222D03*
Y462235D03*
X222729Y1322859D03*
Y1326859D03*
X234216Y142062D03*
X230536Y159071D03*
X242236Y75862D03*
X247313Y115743D03*
X246524Y565976D03*
X246981Y598632D03*
X246682Y633848D03*
X242534Y703397D03*
X258997Y64455D03*
X258949Y60345D03*
X258952Y56160D03*
X257813Y87543D03*
X267069Y151203D03*
Y147203D03*
X270836Y210822D03*
X266600Y439605D03*
X266570Y451735D03*
Y447735D03*
X283816Y136962D03*
X282549Y229606D03*
X275516Y451862D03*
Y447862D03*
X287036Y569548D03*
Y566022D03*
X289636Y634283D03*
Y630757D03*
X287910Y685071D03*
Y688597D03*
X295433Y67513D03*
X295943Y85983D03*
Y82483D03*
X302173Y91767D03*
X305116Y146702D03*
X290716Y139162D03*
X306235Y599318D03*
X317073Y95803D03*
X317119Y99837D03*
X320916Y161562D03*
X314990Y228258D03*
X320325Y559218D03*
X314741Y595998D03*
X336716Y141862D03*
X347554Y142869D03*
X353236Y225862D03*
X346713Y705779D03*
X385676Y119822D03*
Y132822D03*
X378736Y217362D03*
Y208862D03*
Y212862D03*
Y221362D03*
Y225362D03*
X384856Y1622722D03*
X395448Y1398653D03*
X403415Y1411231D03*
X399437Y1537810D03*
Y1545810D03*
Y1560810D03*
Y1564810D03*
X404566Y1549942D03*
X411216Y1603500D03*
Y1615200D03*
X418716Y1616600D03*
X418666Y1620402D03*
X418631Y1624692D03*
Y1628692D03*
Y1632842D03*
X419226Y1643159D03*
X419246Y1647216D03*
X418631Y1636842D03*
X412736Y1672362D03*
Y1676362D03*
Y1668362D03*
X429937Y1547810D03*
Y1551810D03*
X427061Y1583466D03*
X446872Y145710D03*
X445344Y505483D03*
Y509483D03*
Y513483D03*
Y517483D03*
Y521483D03*
Y525483D03*
Y542519D03*
Y547519D03*
X450536Y1547437D03*
X441399Y1600154D03*
X456655Y120948D03*
X455016Y213362D03*
Y222362D03*
X468363Y1400435D03*
X468332Y1396606D03*
X466429Y1610682D03*
Y1603682D03*
X466386Y1622735D03*
X466476Y1626732D03*
X471376Y1631003D03*
X471316Y1634947D03*
X472446Y1647242D03*
Y1663242D03*
X472376Y1677462D03*
Y1681462D03*
X485689Y66565D03*
X485799Y61205D03*
X485959Y55895D03*
X489352Y309398D03*
X498676Y615612D03*
X490372Y1424033D03*
X517341Y168443D03*
X507016Y223362D03*
X502516Y241862D03*
X516916Y489112D03*
X516102Y500469D03*
Y505969D03*
X516916Y495112D03*
X516102Y511469D03*
Y516969D03*
Y522469D03*
Y527969D03*
Y539819D03*
X515516Y615742D03*
X506187Y1422494D03*
X518826Y455062D03*
X526906Y500222D03*
X536356Y99172D03*
X536416Y112512D03*
X549736Y161362D03*
Y184862D03*
Y171862D03*
X536580Y269472D03*
X535466Y454270D03*
X564516Y102862D03*
Y98862D03*
X552486Y127788D03*
Y137774D03*
Y153878D03*
X566605Y310847D03*
X565341Y424392D03*
X565033Y446706D03*
X570056Y157932D03*
X579366Y157684D03*
X581972Y194378D03*
X581736Y230862D03*
X570736Y225362D03*
Y221362D03*
X577586Y493212D03*
Y488212D03*
Y497212D03*
X567586Y1355247D03*
Y1358777D03*
X592336Y136314D03*
Y125314D03*
X596271Y159480D03*
X588668Y288527D03*
X609851Y184062D03*
X599736Y416362D03*
X601736Y444362D03*
Y449362D03*
X599915Y454600D03*
X600736Y506862D03*
Y510862D03*
X631433Y88039D03*
Y92119D03*
X625552Y208076D03*
Y212076D03*
X627736Y234362D03*
Y230362D03*
X631736Y416362D03*
X617736Y426362D03*
X631736Y472862D03*
Y477862D03*
Y467862D03*
X616736Y472862D03*
Y477862D03*
Y462862D03*
Y467862D03*
X645160Y140699D03*
Y149871D03*
Y154345D03*
X646236Y184862D03*
X639650Y249202D03*
Y260202D03*
X637661Y294327D03*
Y290267D03*
Y306547D03*
X646736Y411362D03*
Y421362D03*
Y426362D03*
Y477862D03*
Y472862D03*
Y482862D03*
X633236Y526362D03*
X642236Y1714362D03*
Y1726362D03*
X680469Y119568D03*
Y123420D03*
X665534Y1647557D03*
X665609Y1659557D03*
X665636Y1664862D03*
Y1676862D03*
X668736Y1712362D03*
Y1728362D03*
X690736Y76962D03*
X690969Y91668D03*
X691738Y1640667D03*
X691663Y1636667D03*
X692136Y1662862D03*
Y1678862D03*
X710236Y221862D03*
X704628Y1567683D03*
Y1579683D03*
Y1571683D03*
Y1575683D03*
Y1587683D03*
Y1595683D03*
Y1591683D03*
X711649Y1680400D03*
X723649Y160788D03*
X720461Y1564088D03*
X719768Y1569493D03*
X726768D03*
X727869Y1614503D03*
X727768Y1609893D03*
X718849Y1680400D03*
X730009Y86998D03*
X730519Y101968D03*
X738249Y111252D03*
X730519Y105468D03*
X745761Y137864D03*
X745171Y1682362D03*
Y1678362D03*
X751649Y115288D03*
X751651Y119172D03*
X748176Y265322D03*
Y269322D03*
X760736Y413212D03*
Y403212D03*
Y408212D03*
Y398212D03*
X759856Y459862D03*
Y454862D03*
Y474862D03*
X759916Y493452D03*
X762036Y1384062D03*
Y1401562D03*
Y1397262D03*
X761936Y1414762D03*
X754628Y1583183D03*
X760731Y1698521D03*
X774936Y163254D03*
X772957Y308755D03*
X773042Y303410D03*
X775736Y393212D03*
X774856Y454862D03*
Y459862D03*
X762136Y1379962D03*
Y1375462D03*
X765655Y1573793D03*
X765668Y1581893D03*
Y1577893D03*
Y1590893D03*
X779676Y274822D03*
X786142Y303410D03*
X786057Y308755D03*
X788016Y385300D03*
X789936Y398212D03*
X789856Y444862D03*
Y439862D03*
Y449862D03*
Y454862D03*
Y459862D03*
Y469862D03*
X805586Y441060D03*
Y445100D03*
X805356Y454862D03*
Y459862D03*
Y449862D03*
Y464862D03*
X807168Y1573793D03*
Y1581793D03*
Y1597793D03*
Y1585793D03*
Y1605793D03*
X817816Y449200D03*
X825016D03*
X819356Y476800D03*
Y464862D03*
Y468900D03*
Y472900D03*
X824286Y511082D03*
Y506082D03*
Y527082D03*
Y519082D03*
X837341Y90451D03*
X839236Y135862D03*
Y129362D03*
X827493Y409260D03*
Y405260D03*
X848736Y129362D03*
Y135862D03*
X858108Y240441D03*
X856319Y265057D03*
X843763Y271049D03*
X856829Y280027D03*
Y283527D03*
X859516Y378362D03*
X849416Y473000D03*
Y469100D03*
X857136Y507162D03*
Y495300D03*
X849168Y1573793D03*
Y1581793D03*
Y1597793D03*
Y1585793D03*
Y1605793D03*
X871236Y171362D03*
Y176862D03*
X866016Y196500D03*
X865409Y227763D03*
Y223763D03*
X864559Y289311D03*
X865002Y386476D03*
Y402581D03*
Y398620D03*
X865054Y414276D03*
X881316Y201150D03*
Y195720D03*
X881241Y192055D03*
X877959Y293347D03*
X877982Y298665D03*
X891838Y874405D03*
X891168Y1573793D03*
Y1581793D03*
Y1597793D03*
Y1585793D03*
Y1605793D03*
X899369Y484913D03*
Y480913D03*
X899164Y493299D03*
Y489299D03*
X899149Y501573D03*
Y497573D03*
X892408Y920325D03*
X905005Y975134D03*
Y971234D03*
Y992834D03*
Y988934D03*
X933168Y1593393D03*
X943431Y184912D03*
X943351Y188852D03*
X948575Y424298D03*
X948498Y428124D03*
X948471Y437844D03*
X948548Y434018D03*
X945826Y997422D03*
X970109Y356896D03*
X982440Y171483D03*
X991516Y148299D03*
X998516D03*
X994428Y213233D03*
X1000826Y363352D03*
X1009892Y167278D03*
Y171278D03*
X1015106Y190176D03*
X1014986Y363222D03*
X1034349Y268264D03*
X1038385Y509606D03*
X1027794Y523628D03*
Y514176D03*
X1036126Y523642D03*
X1036546Y514182D03*
X1070937Y265574D03*
X1069671Y386723D03*
X1084237Y69602D03*
X1079205Y83698D03*
X1080126Y379251D03*
X1080006Y369061D03*
X1080066Y374131D03*
X1088306Y1670963D03*
X1104188Y60028D03*
X1110535Y72803D03*
Y77559D03*
X1134658Y1555301D03*
X1136066Y1597630D03*
Y1601630D03*
X1149053Y73679D03*
X1150596Y363231D03*
X1150526Y368041D03*
X1149198Y1626280D03*
X1168387Y61311D03*
Y65811D03*
X1168407Y57111D03*
X1157536Y211370D03*
X1182316Y111600D03*
X1175761Y194174D03*
Y190174D03*
Y206174D03*
Y210174D03*
Y222174D03*
X1195316Y97400D03*
Y89000D03*
Y101600D03*
X1195504Y212648D03*
X1197491Y240672D03*
Y244692D03*
X1194011Y1359636D03*
Y1363146D03*
X1213117Y53860D03*
X1204277Y61060D03*
X1208716Y93600D03*
X1216516D03*
X1209916Y113200D03*
X1217109Y119462D03*
Y132962D03*
X1217113Y148909D03*
Y144909D03*
X1217109Y153962D03*
Y157962D03*
Y168962D03*
X1208609Y164962D03*
X1217109D03*
Y176962D03*
X1208609D03*
X1217095Y172945D03*
X1210035Y171611D03*
X1217236Y194862D03*
X1207736Y200309D03*
Y195362D03*
X1203601Y1681767D03*
X1232906Y102608D03*
X1223010Y113982D03*
X1232907Y106609D03*
X1228627Y129409D03*
X1228609Y134262D03*
Y153115D03*
Y141110D03*
Y163462D03*
Y156962D03*
Y177962D03*
X1242398Y95008D03*
X1239109Y209462D03*
Y205862D03*
Y213462D03*
Y217462D03*
X1248109Y233462D03*
Y223462D03*
Y227462D03*
Y237462D03*
Y241462D03*
X1234876Y244332D03*
Y248332D03*
X1278807Y102928D03*
X1267270Y92724D03*
X1297527Y85138D03*
X1302550Y68562D03*
X1316316Y261662D03*
X1370132Y1403458D03*
X1370189Y1399053D03*
X1379556Y1411231D03*
X1370132Y1407458D03*
X1381153Y1415495D03*
X1394924Y1565037D03*
X1395098Y1576097D03*
X1394924Y1570037D03*
X1395416Y1609522D03*
X1405949Y1516435D03*
X1406189Y1532255D03*
X1405949Y1521335D03*
X1397116Y1521362D03*
X1406339Y1543475D03*
X1406189Y1537155D03*
X1406339Y1548375D03*
X1397016Y1537162D03*
Y1548362D03*
X1399416Y1582500D03*
Y1594000D03*
X1402516Y1630362D03*
Y1642362D03*
X1421399Y227948D03*
X1414916Y1593700D03*
X1424266Y1612812D03*
X1428516Y1637362D03*
X1441216Y60062D03*
X1441938Y1400204D03*
X1441972Y1396269D03*
X1440916Y1598400D03*
Y1611000D03*
X1436316Y1624500D03*
Y1628700D03*
X1451783Y1526689D03*
X1452023Y1542509D03*
X1452173Y1553729D03*
X1450176Y1590302D03*
X1471083Y64355D03*
X1466513Y1424033D03*
X1484899Y233448D03*
X1484601Y255378D03*
X1482316Y421982D03*
X1482328Y1422494D03*
X1502474Y280056D03*
X1526174Y150651D03*
X1517084Y231116D03*
Y239116D03*
Y249698D03*
Y262616D03*
X1516774Y280956D03*
X1517016Y272362D03*
X1517154Y268214D03*
X1516774Y288956D03*
X1532516Y125362D03*
Y121362D03*
X1537855Y310487D03*
X1546904Y127781D03*
X1550253Y634165D03*
X1560808Y651039D03*
X1589016Y199362D03*
X1588855Y256244D03*
X1597432Y1411169D03*
Y1415669D03*
Y1424669D03*
Y1429169D03*
Y1442669D03*
Y1447153D03*
X1636697Y624475D03*
X1635598Y652601D03*
X1636697Y658475D03*
X1635598Y686601D03*
X1636697Y692475D03*
X1635598Y720601D03*
X1641971Y180460D03*
X1644626Y414202D03*
X1654745Y524071D03*
X1654696Y520540D03*
X1654745Y528071D03*
Y532071D03*
Y540071D03*
Y536071D03*
X1642448Y614845D03*
X1653916Y631703D03*
X1654388Y649681D03*
X1653916Y665703D03*
X1654388Y683681D03*
X1653916Y699703D03*
X1654388Y717681D03*
X1660461Y195935D03*
X1662847Y594959D03*
X1661938Y607291D03*
X1668614Y1497362D03*
Y1512862D03*
Y1505362D03*
Y1524862D03*
Y1537862D03*
Y1541862D03*
Y1553557D03*
X1668689Y1565557D03*
Y1585321D03*
X1687149Y424694D03*
X1686011Y473878D03*
Y469878D03*
X1686036Y465940D03*
X1684447Y478790D03*
Y482790D03*
Y488290D03*
X1680004Y491790D03*
X1683585Y552241D03*
X1692520Y401485D03*
X1693792Y518107D03*
Y513107D03*
Y541507D03*
Y537507D03*
X1704551Y531613D03*
X1693792Y545507D03*
Y553527D03*
X1701983Y723005D03*
X1699264Y1500862D03*
Y1520362D03*
Y1541362D03*
X1699544Y1564057D03*
X1700264Y1583821D03*
X1711796Y165909D03*
X1711845Y161900D03*
Y157892D03*
X1711796Y170326D03*
X1715043Y424340D03*
Y420340D03*
X1719945Y490869D03*
Y486869D03*
Y482869D03*
Y494869D03*
X1710596Y499412D03*
X1707436Y701062D03*
X1720665Y1496270D03*
X1732310Y61639D03*
X1732358Y65749D03*
X1732313Y57454D03*
X1733134Y88787D03*
X1722434Y116867D03*
X1726550Y181234D03*
X1726381Y177072D03*
Y173072D03*
X1727895Y490869D03*
Y486869D03*
Y480669D03*
X1751175Y187509D03*
X1751103Y364048D03*
X1751236Y377452D03*
X1751103Y368048D03*
X1751236Y382952D03*
X1760554Y68637D03*
X1761064Y83607D03*
Y87107D03*
X1768794Y92891D03*
X1764943Y364148D03*
X1764736Y372452D03*
X1764943Y368148D03*
X1764736Y377452D03*
X1770067Y461393D03*
Y465893D03*
Y470193D03*
X1782194Y96927D03*
X1782152Y100939D03*
X1771891Y173903D03*
Y178403D03*
X1799815Y161465D03*
X1788904Y1506538D03*
X1815815Y413432D03*
Y417432D03*
X1822703Y170162D03*
X1829395Y399185D03*
X1823855Y434202D03*
X1832467Y453921D03*
X1832457Y467321D03*
Y463193D03*
X1842976Y172187D03*
X1835821Y192678D03*
G54D260*
X1135748Y1528937D03*
X1133780Y1545551D03*
X1139685Y1528937D03*
X1143622D03*
X1147559D03*
X1151497D03*
X1137717Y1545551D03*
X1141654D03*
X1145591D03*
X1149528D03*
X1155433Y1528937D03*
X1159371D03*
X1163308D03*
X1167245D03*
X1153465Y1545551D03*
X1157402D03*
X1161339D03*
X1165276D03*
X1171182Y1528937D03*
X1169213Y1545551D03*
X1173150D03*
G54D161*
X435262Y55016D03*
Y60016D03*
Y65016D03*
Y70016D03*
X456128Y55016D03*
Y70016D03*
Y65016D03*
Y60016D03*
X1138512Y52926D03*
Y57926D03*
Y62926D03*
Y67926D03*
X1159378Y52926D03*
Y67926D03*
Y62926D03*
Y57926D03*
G54D134*
X306772Y991220D03*
X350099Y811121D03*
X356063Y1171318D03*
X531240Y811121D03*
X525276Y1171318D03*
X574567Y991220D03*
X1282914D03*
X1326240Y811121D03*
X1332205Y1171318D03*
X1507382Y811121D03*
X1501418Y1171318D03*
X1550709Y991220D03*
G54D32*
X61057Y64434D03*
Y62334D03*
X72057Y70434D03*
Y68334D03*
X75657Y70434D03*
Y68334D03*
X64657Y64434D03*
Y62334D03*
X94057Y70434D03*
Y68334D03*
X86657Y64434D03*
Y62334D03*
X83057Y64434D03*
Y62334D03*
X105057Y64434D03*
Y62334D03*
X108657Y64434D03*
Y62334D03*
X97657Y70434D03*
Y68334D03*
X127057Y64434D03*
Y62334D03*
X119657Y70434D03*
Y68334D03*
X116057Y70434D03*
Y68334D03*
X130657Y64434D03*
Y62334D03*
X141657Y70434D03*
Y68334D03*
X138057Y70434D03*
Y68334D03*
X149057Y64434D03*
Y62334D03*
X152657Y64434D03*
Y62334D03*
X172261Y64434D03*
Y62334D03*
X175861Y64434D03*
Y62334D03*
X164861Y70434D03*
Y68334D03*
X161261Y70434D03*
Y68334D03*
X186861Y70434D03*
Y68334D03*
X183261Y70434D03*
Y68334D03*
X188797Y1583088D03*
X192397D03*
X188797Y1585188D03*
X192397D03*
X194261Y64434D03*
Y62334D03*
X197861Y64434D03*
Y62334D03*
X205395Y70434D03*
Y68334D03*
X200857Y1583088D03*
X204457D03*
X200857Y1585188D03*
X204457D03*
X206157Y1607286D03*
Y1609386D03*
X194097Y1607286D03*
Y1609386D03*
X197697Y1607286D03*
Y1609386D03*
X216395Y64434D03*
Y62334D03*
X219995Y64434D03*
Y62334D03*
X208995Y70434D03*
Y68334D03*
X212917Y1583088D03*
X216517D03*
X212917Y1585188D03*
X216517D03*
X218217Y1607286D03*
Y1609386D03*
X221817Y1607286D03*
Y1609386D03*
X209757Y1607286D03*
Y1609386D03*
X230995Y70434D03*
Y68334D03*
X227395Y70434D03*
Y68334D03*
X224977Y1583088D03*
X228577D03*
X237037D03*
X240637D03*
X224977Y1585188D03*
X228577D03*
X237037D03*
X240637D03*
X230277Y1607286D03*
Y1609386D03*
X233877Y1607286D03*
Y1609386D03*
X249097Y1583088D03*
X252697D03*
X249097Y1585188D03*
X252697D03*
X254397Y1607286D03*
Y1609386D03*
X242337Y1607286D03*
Y1609386D03*
X245937Y1607286D03*
Y1609386D03*
X261157Y1583088D03*
X264757D03*
X273217D03*
X261157Y1585188D03*
X264757D03*
X273217D03*
X266457Y1607286D03*
Y1609386D03*
X270057Y1607286D03*
Y1609386D03*
X257997Y1607286D03*
Y1609386D03*
X276817Y1583088D03*
X285277D03*
X288877D03*
X276817Y1585188D03*
X285277D03*
X288877D03*
X278517Y1607286D03*
Y1609386D03*
X282117Y1607286D03*
Y1609386D03*
X297337Y1583088D03*
X300937D03*
X297337Y1585188D03*
X300937D03*
X302637Y1607286D03*
Y1609386D03*
X306237Y1607286D03*
Y1609386D03*
X290577Y1607286D03*
Y1609386D03*
X294177Y1607286D03*
Y1609386D03*
X309397Y1583088D03*
X312997D03*
X321457D03*
X309397Y1585188D03*
X312997D03*
X321457D03*
X314697Y1607286D03*
Y1609386D03*
X318297Y1607286D03*
Y1609386D03*
X325057Y1583088D03*
X333517D03*
X337117D03*
X325057Y1585188D03*
X333517D03*
X337117D03*
X338817Y1607286D03*
Y1609386D03*
X330357Y1607286D03*
Y1609386D03*
X326757Y1607286D03*
Y1609386D03*
X345577Y1583088D03*
X349177D03*
X345577Y1585188D03*
X349177D03*
X350877Y1607286D03*
Y1609386D03*
X354477Y1607286D03*
Y1609386D03*
X342417Y1607286D03*
Y1609386D03*
X357637Y1583088D03*
X361237D03*
X369697D03*
X357637Y1585188D03*
X361237D03*
X369697D03*
X362937Y1607286D03*
Y1609386D03*
X366537Y1607286D03*
Y1609386D03*
X373297Y1583088D03*
Y1585188D03*
X374997Y1607286D03*
Y1609386D03*
X378597Y1607286D03*
Y1609386D03*
X402781Y1613560D03*
Y1611460D03*
X405919Y1613560D03*
Y1611460D03*
X476551Y1583088D03*
X472951D03*
X485011D03*
X476551Y1585188D03*
X472951D03*
X485011D03*
X478251Y1607286D03*
Y1609386D03*
X481851Y1607286D03*
Y1609386D03*
X488611Y1583088D03*
X500671D03*
X497071D03*
X488611Y1585188D03*
X500671D03*
X497071D03*
X490311Y1607286D03*
Y1609386D03*
X493911Y1607286D03*
Y1609386D03*
X512731Y1583088D03*
X509131D03*
X512731Y1585188D03*
X509131D03*
X502371Y1607286D03*
Y1609386D03*
X505971Y1607286D03*
Y1609386D03*
X514431Y1607286D03*
Y1609386D03*
X524791Y1583088D03*
X521191D03*
X533251D03*
X524791Y1585188D03*
X521191D03*
X533251D03*
X518031Y1607286D03*
Y1609386D03*
X526491Y1607286D03*
Y1609386D03*
X530091Y1607286D03*
Y1609386D03*
X536851Y1583088D03*
X548911D03*
X545311D03*
X536851Y1585188D03*
X548911D03*
X545311D03*
X538551Y1607286D03*
Y1609386D03*
X542151Y1607286D03*
Y1609386D03*
X560971Y1583088D03*
X557371D03*
X560971Y1585188D03*
X557371D03*
X550611Y1607286D03*
Y1609386D03*
X554211Y1607286D03*
Y1609386D03*
X562671Y1607286D03*
Y1609386D03*
X566271Y1607286D03*
Y1609386D03*
X573031Y1583088D03*
X569431D03*
X581491D03*
X573031Y1585188D03*
X569431D03*
X581491D03*
X574731Y1607286D03*
Y1609386D03*
X578331Y1607286D03*
Y1609386D03*
X585091Y1583088D03*
X597151D03*
X593551D03*
X585091Y1585188D03*
X597151D03*
X593551D03*
X586791Y1607286D03*
Y1609386D03*
X590391Y1607286D03*
Y1609386D03*
X598851Y1607286D03*
Y1609386D03*
X609211Y1583088D03*
X605611D03*
X609211Y1585188D03*
X605611D03*
X602451Y1607286D03*
Y1609386D03*
X610911Y1607286D03*
Y1609386D03*
X614511Y1607286D03*
Y1609386D03*
X621271Y1583088D03*
X617671D03*
X629731D03*
X621271Y1585188D03*
X617671D03*
X629731D03*
X622971Y1607286D03*
Y1609386D03*
X626571Y1607286D03*
Y1609386D03*
X633331Y1583088D03*
X645391D03*
X641791D03*
X633331Y1585188D03*
X645391D03*
X641791D03*
X635031Y1607286D03*
Y1609386D03*
X638631Y1607286D03*
Y1609386D03*
X647091Y1607286D03*
Y1609386D03*
X657451Y1583088D03*
X653851D03*
X657451Y1585188D03*
X653851D03*
X650691Y1607286D03*
Y1609386D03*
X662751Y1607286D03*
Y1609386D03*
X659151Y1607286D03*
Y1609386D03*
X1196672Y1583088D03*
X1200272D03*
X1196672Y1585188D03*
X1200272D03*
X1212332Y1583088D03*
X1208732D03*
X1212332Y1585188D03*
X1208732D03*
X1201972Y1607286D03*
Y1609386D03*
X1205572Y1607286D03*
Y1609386D03*
X1214032Y1607286D03*
Y1609386D03*
X1232852Y1583088D03*
X1220792D03*
X1224392D03*
X1232852Y1585188D03*
X1220792D03*
X1224392D03*
X1229692Y1607286D03*
Y1609386D03*
X1226092Y1607286D03*
Y1609386D03*
X1217632Y1607286D03*
Y1609386D03*
X1244912Y1583088D03*
X1248512D03*
X1236452D03*
X1244912Y1585188D03*
X1248512D03*
X1236452D03*
X1241752Y1607286D03*
Y1609386D03*
X1238152Y1607286D03*
Y1609386D03*
X1256972Y1583088D03*
X1260572D03*
X1256972Y1585188D03*
X1260572D03*
X1253812Y1607286D03*
Y1609386D03*
X1250212Y1607286D03*
Y1609386D03*
X1265872Y1607286D03*
Y1609386D03*
X1262272Y1607286D03*
Y1609386D03*
X1281092Y1583088D03*
X1269032D03*
X1272632D03*
X1281092Y1585188D03*
X1269032D03*
X1272632D03*
X1277932Y1607286D03*
Y1609386D03*
X1274332Y1607286D03*
Y1609386D03*
X1293152Y1583088D03*
X1296752D03*
X1284692D03*
X1293152Y1585188D03*
X1296752D03*
X1284692D03*
X1289992Y1607286D03*
Y1609386D03*
X1286392Y1607286D03*
Y1609386D03*
X1298452Y1607286D03*
Y1609386D03*
X1305212Y1583088D03*
X1308812D03*
X1305212Y1585188D03*
X1308812D03*
X1310512Y1607286D03*
Y1609386D03*
X1314112Y1607286D03*
Y1609386D03*
X1302052Y1607286D03*
Y1609386D03*
X1329332Y1583088D03*
X1317272D03*
X1320872D03*
X1329332Y1585188D03*
X1317272D03*
X1320872D03*
X1322572Y1607286D03*
Y1609386D03*
X1326172Y1607286D03*
Y1609386D03*
X1344585Y276790D03*
Y274690D03*
X1341392Y1583088D03*
X1344992D03*
X1332932D03*
X1341392Y1585188D03*
X1344992D03*
X1332932D03*
X1338232Y1607286D03*
Y1609386D03*
X1334632Y1607286D03*
Y1609386D03*
X1346692Y1607286D03*
Y1609386D03*
X1353285Y278690D03*
Y276590D03*
X1356885Y278690D03*
Y276590D03*
X1348185Y276790D03*
Y274690D03*
X1361385Y274160D03*
Y272060D03*
X1353452Y1583088D03*
X1357052D03*
X1353452Y1585188D03*
X1357052D03*
X1350292Y1607286D03*
Y1609386D03*
X1358752Y1607286D03*
Y1609386D03*
X1362352Y1607286D03*
Y1609386D03*
X1364985Y274160D03*
Y272060D03*
X1377572Y1583088D03*
X1365512D03*
X1369112D03*
X1377572Y1585188D03*
X1365512D03*
X1369112D03*
X1374412Y1607286D03*
Y1609386D03*
X1370812Y1607286D03*
Y1609386D03*
X1381172Y1583088D03*
Y1585188D03*
X1386472Y1607286D03*
Y1609386D03*
X1382872Y1607286D03*
Y1609386D03*
X1474255Y1583088D03*
X1465795D03*
X1462195D03*
X1474255Y1585188D03*
X1465795D03*
X1462195D03*
X1467495Y1607286D03*
Y1609386D03*
X1471095Y1607286D03*
Y1609386D03*
X1486315Y1583088D03*
X1489915D03*
X1477855D03*
X1486315Y1585188D03*
X1489915D03*
X1477855D03*
X1479555Y1607286D03*
Y1609386D03*
X1483155Y1607286D03*
Y1609386D03*
X1491615Y1607286D03*
Y1609386D03*
X1501975Y1583088D03*
X1498375D03*
X1501975Y1585188D03*
X1498375D03*
X1495215Y1607286D03*
Y1609386D03*
X1503675Y1607286D03*
Y1609386D03*
X1507275Y1607286D03*
Y1609386D03*
X1526095Y1583088D03*
X1522495D03*
X1514035D03*
X1510435D03*
X1526095Y1585188D03*
X1522495D03*
X1514035D03*
X1510435D03*
X1515735Y1607286D03*
Y1609386D03*
X1519335Y1607286D03*
Y1609386D03*
X1535496Y64391D03*
Y62291D03*
X1539096Y64391D03*
Y62291D03*
X1534555Y1583088D03*
X1538155D03*
X1534555Y1585188D03*
X1538155D03*
X1527795Y1607286D03*
Y1609386D03*
X1531395Y1607286D03*
Y1609386D03*
X1539855Y1607286D03*
Y1609386D03*
X1557496Y64391D03*
Y62291D03*
X1546496Y70391D03*
Y68291D03*
X1550096Y70391D03*
Y68291D03*
X1558675Y1583088D03*
X1546615D03*
X1550215D03*
X1558675Y1585188D03*
X1546615D03*
X1550215D03*
X1543455Y1607286D03*
Y1609386D03*
X1551915Y1607286D03*
Y1609386D03*
X1555515Y1607286D03*
Y1609386D03*
X1568496Y70391D03*
Y68291D03*
X1572096Y70391D03*
Y68291D03*
X1561096Y64391D03*
Y62291D03*
X1574335Y1583088D03*
X1570735D03*
X1562275D03*
X1574335Y1585188D03*
X1570735D03*
X1562275D03*
X1563975Y1607286D03*
Y1609386D03*
X1567575Y1607286D03*
Y1609386D03*
X1579496Y64391D03*
Y62291D03*
X1583096Y64391D03*
Y62291D03*
X1590496Y70391D03*
Y68291D03*
X1582795Y1583088D03*
X1586395D03*
X1582795Y1585188D03*
X1586395D03*
X1576035Y1607286D03*
Y1609386D03*
X1579635Y1607286D03*
Y1609386D03*
X1588095Y1607286D03*
Y1609386D03*
X1601496Y64391D03*
Y62291D03*
X1605096Y64391D03*
Y62291D03*
X1594096Y70391D03*
Y68291D03*
X1606915Y1583088D03*
X1598455D03*
X1594855D03*
X1606915Y1585188D03*
X1598455D03*
X1594855D03*
X1591695Y1607286D03*
Y1609386D03*
X1600155Y1607286D03*
Y1609386D03*
X1603755Y1607286D03*
Y1609386D03*
X1623496Y64391D03*
Y62291D03*
X1616096Y70391D03*
Y68291D03*
X1612496Y70391D03*
Y68291D03*
X1618975Y1583088D03*
X1622575D03*
X1610515D03*
X1618975Y1585188D03*
X1622575D03*
X1610515D03*
X1612215Y1607286D03*
Y1609386D03*
X1615815Y1607286D03*
Y1609386D03*
X1627096Y64391D03*
Y62291D03*
X1635700Y70391D03*
Y68291D03*
X1639300Y70391D03*
Y68291D03*
X1634635Y1583088D03*
X1631035D03*
X1634635Y1585188D03*
X1631035D03*
X1624275Y1607286D03*
Y1609386D03*
X1627875Y1607286D03*
Y1609386D03*
X1636335Y1607286D03*
Y1609386D03*
X1639935Y1607286D03*
Y1609386D03*
X1650300Y64391D03*
Y62291D03*
X1646700Y64391D03*
Y62291D03*
X1643095Y1583088D03*
X1646695D03*
X1643095Y1585188D03*
X1646695D03*
X1651995Y1607286D03*
Y1609386D03*
X1648395Y1607286D03*
Y1609386D03*
X1672300Y64391D03*
Y62291D03*
X1668700Y64391D03*
Y62291D03*
X1661300Y70391D03*
Y68291D03*
X1657700Y70391D03*
Y68291D03*
X1679834Y70391D03*
Y68291D03*
X1683434Y70391D03*
Y68291D03*
X1701834Y70391D03*
Y68291D03*
X1694434Y64391D03*
Y62291D03*
X1690834Y64391D03*
Y62291D03*
X1705434Y70391D03*
Y68291D03*
G54D215*
X841742Y105951D03*
Y99651D03*
X850088Y105951D03*
Y99651D03*
X970738Y344659D03*
Y350959D03*
X979084Y344659D03*
Y350959D03*
G54D305*
X1756177Y288494D03*
Y290463D03*
Y292431D03*
Y294400D03*
Y286526D03*
X1774681Y294400D03*
Y292431D03*
Y290463D03*
G54D152*
X400317Y120793D03*
Y129061D03*
X417443Y120793D03*
Y129061D03*
X842562Y168064D03*
Y176332D03*
X859688Y168064D03*
Y176332D03*
X1049186Y509790D03*
Y518058D03*
X1066312Y509790D03*
Y518058D03*
X1742907Y171733D03*
Y180001D03*
X1760033D03*
Y171733D03*
G54D170*
X470654Y303145D03*
X504054Y302445D03*
G54D41*
X75896Y442183D03*
X81696D03*
X114513Y531500D03*
X108613D03*
X180867Y416827D03*
X186667D03*
X251487Y92733D03*
X257287D03*
Y97633D03*
X251487D03*
X407749Y1385910D03*
X401849D03*
X684643Y96858D03*
X690443D03*
Y101758D03*
X684643D03*
X1034669Y373577D03*
X1034569Y367944D03*
X1040469Y373577D03*
X1040369Y367944D03*
X1321537Y255966D03*
X1327337D03*
X1383890Y1385910D03*
X1377990D03*
X1663502Y558097D03*
X1657602D03*
X1711966Y507391D03*
X1717866D03*
X1726608Y93857D03*
X1732408D03*
Y98757D03*
X1726608D03*
G54D107*
X207996Y678369D03*
X206027D03*
X204059D03*
X202090D03*
X209964D03*
X435100Y1618242D03*
Y1636942D03*
X437069Y1618242D03*
X439037D03*
X441006D03*
X442974D03*
X444943D03*
X446911D03*
X448880D03*
X437069Y1636942D03*
X439037D03*
X441006D03*
X442974D03*
X444943D03*
X446911D03*
X448880D03*
X923836Y979352D03*
X921868D03*
Y994116D03*
X923836D03*
X931710Y979352D03*
X929742D03*
X927773D03*
X925805D03*
Y994116D03*
X927773D03*
X929742D03*
X931710D03*
X1647009Y610213D03*
X1648977D03*
X1650946D03*
X1652914D03*
X1654883D03*
G54D242*
X999455Y201049D03*
Y197506D03*
Y193962D03*
Y204592D03*
G54D224*
X900589Y175197D03*
X945077Y155216D03*
G54D233*
X938780Y1714890D03*
G54D23*
X42809Y366396D03*
X39008D03*
X36524Y395255D03*
X54620Y61801D03*
X50308D03*
X59322Y366396D03*
X51114D03*
X56163Y416987D03*
X59833Y1609818D03*
Y1618818D03*
X50333D03*
X54333D03*
X47333Y1659818D03*
X53700Y1677684D03*
X63429Y366396D03*
X67681D03*
X69523Y416987D03*
X77588Y659636D03*
X75274Y1549578D03*
X74100Y1618784D03*
X78000D03*
X73833Y1686718D03*
X77833Y1686618D03*
X69833D03*
X86302Y640089D03*
X89461Y663615D03*
X85565Y663623D03*
X93547Y688629D03*
X82311Y712833D03*
X84048Y1574445D03*
X88048D03*
X92251D03*
X81900Y1618784D03*
X85800D03*
X81833Y1686618D03*
X110987Y544699D03*
X97549Y688549D03*
X100931Y705261D03*
X100914Y712231D03*
X107170Y1520226D03*
X96251Y1574445D03*
X104900Y1611884D03*
X124170Y483297D03*
X120060D03*
X115060Y544706D03*
X127377Y544939D03*
X123257Y544869D03*
X119087Y544779D03*
X114021Y666841D03*
X118021D03*
X135006Y493599D03*
X130006D03*
X141103Y483297D03*
X145213D03*
X149568Y1403154D03*
X155098Y1566149D03*
X159107Y1566077D03*
X158118Y1711501D03*
X166631Y1412429D03*
X191267Y702510D03*
X187711Y1403154D03*
X176793Y1582458D03*
X195888Y578455D03*
X199941Y600557D03*
X195888Y612455D03*
X199941Y634557D03*
X195888Y646455D03*
X193461Y669627D03*
X195467Y702510D03*
X204174Y1411729D03*
X200720Y1713346D03*
X222907Y321740D03*
X247487Y107744D03*
X243487D03*
X254297Y127027D03*
X250297D03*
X246297D03*
X242297D03*
X254756Y159786D03*
X271797Y127027D03*
X261297D03*
X268297Y130527D03*
X259933Y146786D03*
X260100Y156946D03*
X263240Y242266D03*
X289357Y118987D03*
X277240Y242266D03*
X303573Y1361337D03*
X313995Y235233D03*
X306956Y562851D03*
X320614Y1369675D03*
X325617Y84227D03*
X332700Y141846D03*
X328700D03*
X338249Y226993D03*
X328965Y234723D03*
X332465D03*
X324106Y602357D03*
X328106D03*
X335673Y1339037D03*
X339811Y126161D03*
X342285Y213593D03*
X346203Y213611D03*
X346249Y226993D03*
X342249D03*
X352742Y1346877D03*
X367807Y1325076D03*
X386004Y1332902D03*
X385123Y1646233D03*
X378547Y1646239D03*
X374391Y1653935D03*
X374509Y1685643D03*
X399935Y1325076D03*
X391563Y1645703D03*
X414595Y947457D03*
X418595D03*
X410795D03*
X414616Y939132D03*
X414626Y962240D03*
X410826D03*
X418626D03*
X418671Y976741D03*
X414626D03*
X410871D03*
X410800Y991152D03*
X414600D03*
X418600D03*
X414550Y1005634D03*
X410838D03*
X418550D03*
X418591Y1020094D03*
X410816D03*
X414591D03*
X417104Y1332902D03*
X407125Y1422487D03*
X407557Y1658369D03*
X422395Y947457D03*
X422426Y962240D03*
X422471Y976741D03*
X422400Y991152D03*
X422350Y1005634D03*
X422391Y1020094D03*
X432063Y1325076D03*
X429383Y1600138D03*
X433383D03*
X437840Y125255D03*
X452071Y263973D03*
X445720Y402246D03*
X451720Y411246D03*
X451520Y482321D03*
X442520D03*
X437520D03*
X447520D03*
X448873Y1332902D03*
X446258Y1439115D03*
X449778D03*
X438020Y1567921D03*
X450020D03*
X437990Y1647261D03*
X441990D03*
X468323Y264055D03*
X455720Y411246D03*
X462720Y402246D03*
X466520Y473321D03*
X456520Y482321D03*
X461520D03*
X462704Y947457D03*
X466704Y939132D03*
X462704D03*
X458904D03*
X466704Y947457D03*
X458904D03*
X466704Y962240D03*
X458904D03*
X462704D03*
X466704Y976741D03*
X458904D03*
X462704D03*
X466704Y991152D03*
X462704D03*
X458904D03*
X466704Y1005634D03*
X458904D03*
X462704D03*
X466704Y1020094D03*
X458904D03*
X462704D03*
X464191Y1325076D03*
X468620Y1407446D03*
X459520Y1552421D03*
X456020Y1577921D03*
X464020D03*
X457220Y1589479D03*
X464930Y1654716D03*
X473500Y237846D03*
X475252Y263994D03*
X481500Y296846D03*
X478720Y366346D03*
X482720D03*
X479169Y482180D03*
X474169D03*
X484169D03*
X470504Y939132D03*
Y947457D03*
Y962240D03*
Y976741D03*
Y991152D03*
Y1005634D03*
Y1020094D03*
X481254Y1332894D03*
X476281Y1418977D03*
X477368Y1407454D03*
X480252Y1418977D03*
X472701Y1407454D03*
X481468D03*
X499096Y264698D03*
X492936Y264741D03*
X485500Y296846D03*
X494720Y366346D03*
X488169Y482180D03*
X498169D03*
X493169D03*
X496319Y1338502D03*
X485712Y1424961D03*
X517020Y86346D03*
X512220D03*
X515804Y264947D03*
X509496Y265023D03*
X514720Y366346D03*
X510720D03*
X502720D03*
X513720Y395846D03*
X504040Y381386D03*
X509720Y395846D03*
X503169Y473180D03*
X513382Y1346877D03*
X525720Y293846D03*
X527720Y366346D03*
X529720Y395846D03*
X520830Y383866D03*
X525720Y395846D03*
X528447Y1361300D03*
X535720Y366346D03*
X545510Y1369675D03*
X552720Y167846D03*
X559300Y420241D03*
X552000Y1459846D03*
X569300Y411391D03*
X597220Y91346D03*
X589330Y91004D03*
X593240D03*
X598724Y153355D03*
X593220Y182346D03*
Y190346D03*
X596800Y505016D03*
X614384Y124876D03*
X610104D03*
X602278D03*
X599720Y182346D03*
Y190346D03*
X614095Y278114D03*
X608895D03*
X611609Y323904D03*
X603822Y323854D03*
X622000Y91346D03*
X630951Y124876D03*
X626699D03*
X622592D03*
X627064Y256186D03*
X619496Y323954D03*
X627236Y323935D03*
X647725Y1649178D03*
X643725D03*
X653820Y87246D03*
X655000Y94846D03*
X661865Y511538D03*
X659039Y521075D03*
X654927Y528164D03*
X663187Y1403179D03*
X650225Y1705678D03*
X676643Y111869D03*
X680623D03*
X670220Y501346D03*
X675220D03*
X680220D03*
X675220Y514346D03*
X680250Y1411554D03*
X694453Y131152D03*
X687453D03*
X683453D03*
X688290Y385406D03*
X690220Y514346D03*
X685220D03*
X704000Y79346D03*
X704953Y131152D03*
X700963Y131212D03*
X713220Y383846D03*
X711220Y514346D03*
X705220D03*
X701330Y1403179D03*
X711780Y1620414D03*
X723933Y138472D03*
X727000Y371209D03*
X722500D03*
X718393Y1411554D03*
X725552Y1605577D03*
X719612Y1605667D03*
X726720Y1647424D03*
X722630Y1652954D03*
X735800Y371209D03*
X731400D03*
X745220Y501346D03*
Y527846D03*
X730680Y1647424D03*
X760193Y103712D03*
X758220Y444846D03*
X761700Y514946D03*
X751220Y527846D03*
X759859Y1692079D03*
X765160Y284306D03*
X776000Y366846D03*
X764000D03*
X771960Y366966D03*
X767960D03*
X777220Y448346D03*
X772952Y1587177D03*
X763359Y1726579D03*
X789720Y428346D03*
X787520Y519966D03*
X798400Y366184D03*
X806000D03*
X796546Y416110D03*
X819114Y120682D03*
X827114D03*
X823114D03*
X826614Y150182D03*
X813800Y386084D03*
X818000D03*
X824220Y428346D03*
X816670Y505406D03*
X812810Y519866D03*
X815252Y1588077D03*
X839360Y120566D03*
X831114Y120682D03*
X840220Y200846D03*
Y187846D03*
X836300Y424384D03*
X844935Y93235D03*
X844220Y200846D03*
Y187846D03*
X856190Y190094D03*
X845505Y287475D03*
Y297761D03*
X849000Y441184D03*
X857252Y1588077D03*
X886503Y281771D03*
X891747Y870838D03*
X887897D03*
X881372Y917939D03*
X899252Y1588077D03*
X921757Y967671D03*
X916974D03*
X926823Y967636D03*
X957027Y198881D03*
X947348Y988561D03*
X961137Y198833D03*
X981445Y178567D03*
X977195Y206907D03*
X981789Y363944D03*
X987139Y427440D03*
X1005699Y170327D03*
X996415Y178057D03*
X999915D03*
X1005395Y217407D03*
X991140Y427440D03*
X1009735Y156927D03*
X1015275Y156933D03*
X1016506Y427288D03*
X1012506D03*
X1023220Y185083D03*
X1034835Y299194D03*
X1031025D03*
X1025958Y365648D03*
X1029922Y365653D03*
X1043424Y285982D03*
X1038606Y299194D03*
X1091457Y1644334D03*
X1103457D03*
X1113140Y1672975D03*
X1105457Y1672934D03*
X1122879Y1439483D03*
X1124862Y1620734D03*
X1124762Y1628394D03*
X1139942Y1447858D03*
X1152720Y186346D03*
X1156720D03*
X1161022Y1439483D03*
X1164830Y1660599D03*
X1159930D03*
X1173374Y173115D03*
X1178085Y1447858D03*
X1181930Y1660599D03*
X1175830D03*
X1170930D03*
X1191206Y139033D03*
X1185030Y1630445D03*
X1192500Y1660909D03*
X1197400D03*
X1186830Y1660599D03*
X1197240Y1706389D03*
X1192340D03*
X1211720Y210346D03*
X1207220D03*
X1215720D03*
X1212610Y222136D03*
X1207530Y222036D03*
X1216610Y222136D03*
X1209900Y247057D03*
X1216656D03*
X1203267Y1655969D03*
X1208010Y1706434D03*
X1203110D03*
X1213910Y1706699D03*
X1218810D03*
X1263150Y303000D03*
X1251150D03*
X1281940Y90756D03*
X1274864Y110196D03*
X1267322Y106648D03*
X1267150Y303000D03*
X1279834Y1361573D03*
X1286013Y82383D03*
X1297342Y290891D03*
X1293398D03*
X1290437Y752449D03*
X1296875Y1369911D03*
X1313788Y65284D03*
X1303264Y77774D03*
X1307542Y301301D03*
X1303542D03*
X1311820Y1338502D03*
X1328883Y1346877D03*
X1343948Y1325076D03*
X1362145Y1332902D03*
X1366001Y98579D03*
X1366369Y89554D03*
X1376076Y1325076D03*
X1394736Y947456D03*
X1390736D03*
X1390719Y939122D03*
X1386936Y947456D03*
X1386967Y962239D03*
X1390767D03*
X1394767D03*
X1390812Y976740D03*
X1394812D03*
X1387012D03*
X1394741Y991151D03*
X1390741D03*
X1386941D03*
X1390691Y1005633D03*
X1394691D03*
X1386891D03*
X1394732Y1020093D03*
X1386869D03*
X1390732D03*
X1393245Y1332902D03*
X1382347Y1397087D03*
X1385066Y1422487D03*
X1398536Y947456D03*
X1398567Y962239D03*
X1398612Y976740D03*
X1398541Y991151D03*
X1398491Y1005633D03*
X1398532Y1020093D03*
X1408204Y1325076D03*
X1402680Y1603256D03*
X1425014Y1332902D03*
X1427349Y1439625D03*
X1423519Y1439635D03*
X1422680Y1587884D03*
X1438845Y947456D03*
X1435045D03*
X1438845Y939131D03*
X1442845Y947456D03*
Y939131D03*
X1435045D03*
X1442845Y962239D03*
X1438845D03*
X1435045D03*
X1438845Y976740D03*
X1442845D03*
X1435045D03*
X1442845Y991151D03*
X1438845D03*
X1435045D03*
X1438845Y1005633D03*
X1435045D03*
X1442845D03*
X1438845Y1020093D03*
X1442845D03*
X1435045D03*
X1440332Y1325076D03*
X1444720Y1407446D03*
X1438547Y1643819D03*
X1443617Y1643799D03*
X1455600Y294184D03*
X1447800D03*
X1458300Y367446D03*
X1449777Y367480D03*
X1453777D03*
X1451780Y410406D03*
X1456777Y424055D03*
X1446645Y939131D03*
Y947456D03*
Y962239D03*
Y976740D03*
Y991151D03*
Y1005633D03*
Y1020093D03*
X1457395Y1332894D03*
X1453509Y1407454D03*
X1452422Y1418977D03*
X1448842Y1407454D03*
X1457609D03*
X1456393Y1418977D03*
X1454167Y1643899D03*
X1459127D03*
X1448507Y1643809D03*
X1463000Y158846D03*
X1466777Y367480D03*
X1470777D03*
X1472460Y1338502D03*
X1461803Y1424991D03*
X1472565Y1631086D03*
X1463767Y1643899D03*
X1493384Y416772D03*
X1481384D03*
X1489523Y1346877D03*
X1504602Y298241D03*
X1504278Y287939D03*
X1504602Y310240D03*
X1498184Y367182D03*
X1497384Y416772D03*
X1504588Y1361300D03*
X1524654Y57599D03*
X1517263Y196321D03*
X1521828Y302259D03*
X1521651Y1369675D03*
X1528654Y57599D03*
X1537746Y1306402D03*
X1547697Y124262D03*
X1543720Y587346D03*
X1548720D03*
X1557287Y631919D03*
X1563994Y584201D03*
X1567994D03*
X1624353Y1436775D03*
X1644360Y205724D03*
X1648400Y205714D03*
X1652610Y400186D03*
X1647110Y431686D03*
X1649291Y552219D03*
X1649220Y618146D03*
X1653220D03*
X1641416Y1445150D03*
X1661110Y431686D03*
X1664040Y567136D03*
X1672040D03*
X1668040D03*
X1657220Y618146D03*
X1662496Y1436775D03*
X1673872Y431129D03*
X1686154Y431669D03*
X1676040Y567136D03*
X1680040D03*
X1679559Y1445150D03*
X1703932Y229503D03*
X1704624Y431159D03*
X1701124D03*
X1703720Y506846D03*
X1698720D03*
X1702320Y539456D03*
X1695443Y716329D03*
X1718608Y108868D03*
X1717418Y128151D03*
X1721418D03*
X1715044Y410029D03*
X1718931Y410021D03*
X1710408Y423429D03*
X1708977Y468288D03*
X1713977D03*
X1708030Y691236D03*
X1713159Y691259D03*
X1714298Y714599D03*
X1714320Y707746D03*
X1709107Y725269D03*
X1722608Y108868D03*
X1736418Y128151D03*
X1729418D03*
X1725418D03*
X1725500Y380846D03*
X1722500Y371846D03*
X1733780Y396254D03*
X1729810D03*
X1737660D03*
X1730290Y420324D03*
X1734290D03*
X1736611Y493751D03*
X1746918Y128151D03*
X1743418Y131651D03*
X1746366Y286516D03*
X1743170Y408284D03*
X1764478Y120111D03*
X1769230Y307901D03*
X1758563D03*
X1765663D03*
X1762163D03*
X1754963D03*
X1772863D03*
X1778810Y455124D03*
X1790738Y85351D03*
X1819461Y153785D03*
X1813700Y1500271D03*
X1826075Y1507825D03*
X1843166Y241830D03*
G54D50*
X89981Y702670D03*
X1703413Y706796D03*
G54D314*
X1879155Y354948D03*
Y458898D03*
Y478898D03*
Y582848D03*
Y602848D03*
Y706798D03*
Y726798D03*
Y830748D03*
X1900275Y-9342D03*
X1889155Y354948D03*
Y458898D03*
Y478898D03*
X1900275Y582858D03*
X1889155Y582848D03*
Y602848D03*
Y706798D03*
X1900275Y726808D03*
X1889155Y726798D03*
X1900275Y830758D03*
X1889155Y830748D03*
X1900275Y850758D03*
Y954708D03*
X1910275Y-9342D03*
Y582858D03*
Y726808D03*
Y830758D03*
Y850758D03*
Y954708D03*
X1921395Y-9332D03*
X1931395D03*
Y582868D03*
X1921395D03*
X1931395Y602868D03*
X1921395D03*
Y1195068D03*
X1931395D03*
X1942395Y-9152D03*
Y583048D03*
Y603048D03*
Y1195248D03*
X1963362Y-9190D03*
X1952395Y-9152D03*
X1963362Y583010D03*
X1952395Y583048D03*
X1963362Y603010D03*
X1952395Y603048D03*
X1963362Y1195210D03*
X1952395Y1195248D03*
X1973362Y-9190D03*
Y583010D03*
Y603010D03*
Y1195210D03*
X1994482Y-9180D03*
X1984482D03*
Y583020D03*
X1994482D03*
X1984482Y603020D03*
X1994482D03*
Y1195220D03*
X1984482D03*
X2005452Y-9180D03*
X2015452D03*
Y583020D03*
X2005452D03*
X2015452Y603020D03*
X2005452D03*
Y1195220D03*
X2015452D03*
X2026452Y-9000D03*
Y583200D03*
Y603200D03*
Y1195400D03*
X2047419Y-9038D03*
X2036452Y-9000D03*
X2047419Y583162D03*
X2036452Y583200D03*
X2047419Y603162D03*
X2036452Y603200D03*
X2047419Y1195362D03*
X2036452Y1195400D03*
X2057419Y-9038D03*
Y583162D03*
Y603162D03*
Y1195362D03*
X2068539Y603172D03*
X2078539D03*
Y1195372D03*
X2068539D03*
G54D206*
X777283Y317392D03*
X771377D03*
X808793Y264580D03*
X802887D03*
G54D143*
X335928Y859899D03*
Y866307D03*
X337779Y856694D03*
Y863103D03*
X334079Y869511D03*
X335928Y872716D03*
X337779Y869511D03*
X334079Y875920D03*
Y882329D03*
Y888737D03*
Y895146D03*
Y901555D03*
Y907963D03*
Y914372D03*
Y920780D03*
Y927189D03*
Y933598D03*
Y940006D03*
Y946414D03*
Y952823D03*
Y959232D03*
Y965640D03*
Y972049D03*
Y978457D03*
X335928Y981662D03*
X337779Y984866D03*
X334512Y1007187D03*
Y1013595D03*
X336361Y1003983D03*
X338211Y1000778D03*
X334512Y1020004D03*
Y1026413D03*
Y1032821D03*
Y1039230D03*
Y1045639D03*
Y1052047D03*
X336361Y1055251D03*
Y1061660D03*
Y1068068D03*
Y1074477D03*
Y1080885D03*
Y1087294D03*
Y1093703D03*
Y1100111D03*
Y1106520D03*
Y1112929D03*
Y1119337D03*
Y1125746D03*
X338211Y1116133D03*
Y1122541D03*
Y1128950D03*
X347029Y847081D03*
X348879Y850286D03*
X350728Y847081D03*
X354428D03*
X345179Y850286D03*
X347029Y853490D03*
X339629D03*
Y859899D03*
Y866307D03*
X341479Y856694D03*
Y863103D03*
X343328Y853490D03*
Y859899D03*
X345179Y856694D03*
X340061Y997574D03*
Y1119337D03*
Y1125746D03*
X341912Y1122541D03*
Y1128950D03*
X343761Y1125746D03*
X345611Y1128950D03*
X347461Y1132154D03*
X349312Y1135359D03*
X353011D03*
X343761Y1132154D03*
X345611Y1135359D03*
X371079Y843877D03*
X356279D03*
X359979D03*
X363679D03*
X367379D03*
X356712Y1135359D03*
X358561Y1138563D03*
X362261D03*
X365961D03*
X369661D03*
X378479Y843877D03*
X382179D03*
X385879D03*
X374779D03*
X377061Y1138563D03*
X380761D03*
X384461D03*
X373361D03*
X389579Y843877D03*
X393279D03*
X396979D03*
X400679D03*
X388161Y1138563D03*
X391861D03*
X395561D03*
X399261D03*
X402961D03*
X408079Y843877D03*
X411779D03*
X415479D03*
X419179D03*
X404379D03*
X406661Y1138563D03*
X410361D03*
X414061D03*
X417761D03*
X422879Y843877D03*
X426579D03*
X428428Y847081D03*
X432128D03*
X435829D03*
X421461Y1138563D03*
X425161D03*
X428861D03*
X430711Y1135359D03*
X434412D03*
X452479Y843877D03*
X439528Y847081D03*
X443228D03*
X446928D03*
X450629D03*
X438112Y1135359D03*
X441812D03*
X445511D03*
X449212D03*
X467279Y843877D03*
X456179D03*
X459879D03*
X463579D03*
X452912Y1135359D03*
X454761Y1138563D03*
X458461D03*
X462161D03*
X465861D03*
X470979Y843877D03*
X474679D03*
X478379D03*
X482079D03*
X469561Y1138563D03*
X473261D03*
X476961D03*
X480661D03*
X484361D03*
X496879Y843877D03*
X500579D03*
X485779D03*
X489479D03*
X493179D03*
X499161Y1138563D03*
X488061D03*
X491761D03*
X495461D03*
X504279Y843877D03*
X507979D03*
X511679D03*
X515379D03*
X502861Y1138563D03*
X506561D03*
X510261D03*
X513961D03*
X517661D03*
X519079Y843877D03*
X522779D03*
X528329Y847081D03*
X532028D03*
X533879Y850286D03*
X524628Y847081D03*
X534311Y1128950D03*
X526912Y1135359D03*
X530612D03*
X532461Y1132154D03*
X534311Y1135359D03*
X521361Y1138563D03*
X525061D03*
X535729Y847081D03*
X537579Y850286D03*
X535729Y853490D03*
X537579Y856694D03*
X539428Y853490D03*
Y859899D03*
X541279Y856694D03*
Y863103D03*
X543129Y853490D03*
Y859899D03*
Y866307D03*
X544979Y856694D03*
Y863103D03*
X546828Y866307D03*
X544979Y869511D03*
X546828Y872716D03*
Y879124D03*
Y885533D03*
Y891942D03*
Y898350D03*
Y904759D03*
Y911167D03*
Y917576D03*
Y923985D03*
Y930393D03*
Y936801D03*
Y943210D03*
Y949619D03*
Y956027D03*
Y962436D03*
X543129Y981662D03*
X544979Y978457D03*
X546828Y968845D03*
Y975253D03*
X541279Y984866D03*
X543561Y997574D03*
X545412Y1000778D03*
X547261Y1003983D03*
Y1010391D03*
Y1016800D03*
Y1023208D03*
Y1029617D03*
X545412Y1045639D03*
X547261Y1036026D03*
Y1042434D03*
X545412Y1052047D03*
Y1058455D03*
Y1064864D03*
Y1071273D03*
Y1077681D03*
Y1084090D03*
Y1090498D03*
Y1096907D03*
Y1103316D03*
Y1109724D03*
X543561Y1112929D03*
X536161Y1125746D03*
X538012Y1122541D03*
Y1128950D03*
X539861Y1119337D03*
Y1125746D03*
X541711Y1116133D03*
Y1122541D03*
Y1128950D03*
X543561Y1119337D03*
Y1125746D03*
X545412Y1116133D03*
Y1122541D03*
X536161Y1132154D03*
X1312070Y859899D03*
Y866307D03*
X1313921Y856694D03*
Y863103D03*
X1310221Y869511D03*
X1312070Y872716D03*
X1313921Y869511D03*
X1310221Y875920D03*
Y882329D03*
Y888737D03*
Y895146D03*
Y901555D03*
Y907963D03*
Y914372D03*
Y920780D03*
Y927189D03*
Y933598D03*
Y940006D03*
Y946414D03*
Y952823D03*
Y959232D03*
Y965640D03*
Y972049D03*
Y978457D03*
X1312070Y981662D03*
X1313921Y984866D03*
X1310654Y1007187D03*
Y1013595D03*
X1312503Y1003983D03*
X1314353Y1000778D03*
X1310654Y1020004D03*
Y1026413D03*
Y1032821D03*
Y1039230D03*
Y1045639D03*
Y1052047D03*
X1312503Y1055251D03*
Y1061660D03*
Y1068068D03*
Y1074477D03*
Y1080885D03*
Y1087294D03*
Y1093703D03*
Y1100111D03*
Y1106520D03*
Y1112929D03*
Y1119337D03*
Y1125746D03*
X1314353Y1116133D03*
Y1122541D03*
Y1128950D03*
X1323171Y847081D03*
X1325021Y850286D03*
X1326870Y847081D03*
X1330570D03*
X1321321Y850286D03*
X1323171Y853490D03*
X1315771D03*
Y859899D03*
Y866307D03*
X1317621Y856694D03*
Y863103D03*
X1319470Y853490D03*
Y859899D03*
X1321321Y856694D03*
X1316203Y997574D03*
Y1119337D03*
Y1125746D03*
X1318054Y1122541D03*
Y1128950D03*
X1319903Y1125746D03*
X1321753Y1128950D03*
X1323603Y1132154D03*
X1325454Y1135359D03*
X1329153D03*
X1319903Y1132154D03*
X1321753Y1135359D03*
X1347221Y843877D03*
X1332421D03*
X1336121D03*
X1339821D03*
X1343521D03*
X1332854Y1135359D03*
X1334703Y1138563D03*
X1338403D03*
X1342103D03*
X1345803D03*
X1354621Y843877D03*
X1358321D03*
X1362021D03*
X1350921D03*
X1353203Y1138563D03*
X1356903D03*
X1360603D03*
X1349503D03*
X1365721Y843877D03*
X1369421D03*
X1373121D03*
X1376821D03*
X1364303Y1138563D03*
X1368003D03*
X1371703D03*
X1375403D03*
X1379103D03*
X1384221Y843877D03*
X1387921D03*
X1391621D03*
X1395321D03*
X1380521D03*
X1382803Y1138563D03*
X1386503D03*
X1390203D03*
X1393903D03*
X1399021Y843877D03*
X1402721D03*
X1404570Y847081D03*
X1408270D03*
X1411971D03*
X1397603Y1138563D03*
X1401303D03*
X1405003D03*
X1406853Y1135359D03*
X1410554D03*
X1428621Y843877D03*
X1415670Y847081D03*
X1419370D03*
X1423070D03*
X1426771D03*
X1414254Y1135359D03*
X1417954D03*
X1421653D03*
X1425354D03*
X1443421Y843877D03*
X1432321D03*
X1436021D03*
X1439721D03*
X1429054Y1135359D03*
X1430903Y1138563D03*
X1434603D03*
X1438303D03*
X1442003D03*
X1447121Y843877D03*
X1450821D03*
X1454521D03*
X1458221D03*
X1445703Y1138563D03*
X1449403D03*
X1453103D03*
X1456803D03*
X1460503D03*
X1473021Y843877D03*
X1476721D03*
X1461921D03*
X1465621D03*
X1469321D03*
X1475303Y1138563D03*
X1464203D03*
X1467903D03*
X1471603D03*
X1480421Y843877D03*
X1484121D03*
X1487821D03*
X1491521D03*
X1479003Y1138563D03*
X1482703D03*
X1486403D03*
X1490103D03*
X1493803D03*
X1495221Y843877D03*
X1498921D03*
X1504471Y847081D03*
X1508170D03*
X1510021Y850286D03*
X1500770Y847081D03*
X1510453Y1128950D03*
X1503054Y1135359D03*
X1506754D03*
X1508603Y1132154D03*
X1510453Y1135359D03*
X1497503Y1138563D03*
X1501203D03*
X1511871Y847081D03*
X1513721Y850286D03*
X1511871Y853490D03*
X1513721Y856694D03*
X1515570Y853490D03*
Y859899D03*
X1517421Y856694D03*
Y863103D03*
X1519271Y853490D03*
Y859899D03*
Y866307D03*
X1521121Y856694D03*
Y863103D03*
X1522970Y866307D03*
X1521121Y869511D03*
X1522970Y872716D03*
Y879124D03*
Y885533D03*
Y891942D03*
Y898350D03*
Y904759D03*
Y911167D03*
Y917576D03*
Y923985D03*
Y930393D03*
Y936801D03*
Y943210D03*
Y949619D03*
Y956027D03*
Y962436D03*
X1519271Y981662D03*
X1521121Y978457D03*
X1522970Y968845D03*
Y975253D03*
X1517421Y984866D03*
X1519703Y997574D03*
X1521554Y1000778D03*
X1523403Y1003983D03*
Y1010391D03*
Y1016800D03*
Y1023208D03*
Y1029617D03*
X1521554Y1045639D03*
X1523403Y1036026D03*
Y1042434D03*
X1521554Y1052047D03*
Y1058455D03*
Y1064864D03*
Y1071273D03*
Y1077681D03*
Y1084090D03*
Y1090498D03*
Y1096907D03*
Y1103316D03*
Y1109724D03*
X1519703Y1112929D03*
X1512303Y1125746D03*
X1514154Y1122541D03*
Y1128950D03*
X1516003Y1119337D03*
Y1125746D03*
X1517853Y1116133D03*
Y1122541D03*
Y1128950D03*
X1519703Y1119337D03*
Y1125746D03*
X1521554Y1116133D03*
Y1122541D03*
X1512303Y1132154D03*
G54D116*
X227557Y582055D03*
Y616055D03*
Y650055D03*
X1626416Y638527D03*
Y672527D03*
Y706527D03*
G54D125*
X274299Y224782D03*
X1658169Y414202D03*
G54D251*
X1029250Y275752D03*
G54D315*
G01X43709Y46878D02*
X7874D01*
G02X500Y54252I0J7374D01*
G01Y305794D01*
G02X2660Y311007I7371J0D01*
G01X5922Y314269D01*
G03X8374Y320190I-5920J5920D01*
G01Y1588078D01*
G02X10534Y1593291I7371J0D01*
G01X23638Y1606395D01*
G03X26091Y1612316I-5922J5922D01*
G01Y1732244D01*
G02X33465Y1739618I7374J0D01*
G01X43709Y46878D02*
G02X52083Y38504I0J-8374D01*
G01X321161Y2264D02*
Y38504D01*
G02X329535Y46878I8374J0D01*
G01X488591D01*
G02X496965Y38504I0J-8374D01*
G01Y22753D01*
G03X498431Y21287I1466J0D01*
G01X764577D01*
G03X766043Y22753I0J1466D01*
G01Y38504D01*
G02X774417Y46878I8374J0D01*
G01X871260D01*
G03X878634Y54252I0J7374D01*
G01Y131004D01*
G02X887008Y139378I8374J0D01*
G01X1011024D01*
G02X1019398Y131004I0J-8374D01*
G01Y54252D01*
G03X1026772Y46878I7374J0D01*
G01X1518118D01*
G02X1526492Y38504I0J-8374D01*
G01Y1966D01*
G03X1527958Y500I1466J0D01*
G01X1794105D01*
G03X1795571Y1966I0J1466D01*
G01Y38504D01*
G02X1803945Y46878I8374J0D01*
G01X1849606D01*
G03X1856980Y54252I0J7374D01*
G01Y305794D01*
G03X1854820Y311007I-7375J-2D01*
G01X1845653Y320174D01*
G02X1843201Y326095I5923J5921D01*
G01Y1593983D01*
G03X1841041Y1599196I-7375J-2D01*
G01X1833842Y1606395D01*
G02X1831390Y1612316I5923J5921D01*
G01Y1732244D01*
G03X1824016Y1739618I-7374J0D01*
G01X1091791D01*
G03X1090323Y1738150I0J-1468D01*
G01Y1736890D01*
G02X1087854Y1734421I-2469J0D01*
G01X769705D01*
G02X767236Y1736890I0J2469D01*
G01Y1738150D01*
G03X765768Y1739618I-1468J0D01*
G01X33465D01*
G01X52083Y38504D02*
Y1966D01*
G01D02*
G03X53549Y500I1466J0D01*
G01D02*
X319696D01*
G01D02*
G03X321162Y1966I0J1466D01*
G01D02*
Y38504D01*
G54D51*
X87225Y704442D03*
X1700657Y708568D03*
G54D15*
X19983Y193362D03*
Y200362D03*
X30703Y232362D03*
Y240362D03*
X35968Y401000D03*
X60090Y421746D03*
X62257Y1524094D03*
Y1532094D03*
Y1528194D03*
Y1548094D03*
Y1552094D03*
Y1544094D03*
Y1556094D03*
X84857Y391391D03*
Y395865D03*
Y382219D03*
X91284Y428319D03*
Y424319D03*
Y420319D03*
X80974Y436519D03*
Y432519D03*
X91284Y450519D03*
Y446519D03*
X90623Y667734D03*
X91518Y718879D03*
X91703Y1690362D03*
X99638Y169263D03*
X110908Y232128D03*
X107903Y493578D03*
X107933Y497374D03*
Y501374D03*
Y505374D03*
Y509374D03*
Y513374D03*
X98997Y512870D03*
X98803Y696262D03*
X110257Y1528594D03*
Y1532694D03*
Y1552594D03*
Y1556594D03*
X96171Y1593867D03*
Y1585852D03*
Y1589852D03*
X96246Y1611821D03*
Y1605867D03*
Y1623821D03*
X96156Y1634362D03*
Y1638362D03*
X99483Y1655800D03*
Y1651800D03*
X126902Y278875D03*
X126883Y274800D03*
X126902Y306236D03*
X119965Y404571D03*
X127221Y636153D03*
Y640103D03*
X122541Y1589352D03*
X127321Y1604367D03*
X127041Y1637862D03*
X124703Y1696362D03*
X130465Y396071D03*
Y388071D03*
Y392071D03*
Y384071D03*
X134433Y525374D03*
X133020Y1535855D03*
X133172Y1541874D03*
X133264Y1547935D03*
X128041Y1622321D03*
X143803Y1708362D03*
X141550Y1720092D03*
X130540Y1723182D03*
X146980Y510810D03*
Y514810D03*
Y518810D03*
Y526830D03*
X155791Y519281D03*
X151203Y1716362D03*
X161383Y413362D03*
X184879Y421383D03*
Y425383D03*
Y443383D03*
Y430883D03*
X178050Y1723592D03*
X185050Y1729092D03*
Y1733092D03*
X207874Y567981D03*
X200048Y584791D03*
X207874Y601981D03*
X200048Y618791D03*
X207874Y635981D03*
X200048Y652791D03*
X194125Y689683D03*
X196653Y675092D03*
X195933Y1535377D03*
X195874Y1539678D03*
X195766Y1548430D03*
X195674Y1552940D03*
X208203Y1709862D03*
X208101Y1714017D03*
X215037Y420735D03*
Y424735D03*
Y428735D03*
Y436735D03*
Y432735D03*
Y440735D03*
Y444735D03*
Y448735D03*
Y457222D03*
Y462235D03*
X237183Y142062D03*
X233503Y159071D03*
X225696Y1322859D03*
Y1326859D03*
X245203Y75862D03*
X250280Y115743D03*
X249491Y565976D03*
X249948Y598632D03*
X249649Y633848D03*
X245501Y703397D03*
X261964Y64455D03*
X261916Y60345D03*
X261919Y56160D03*
X260780Y87543D03*
X270036Y151203D03*
Y147203D03*
X273803Y210822D03*
X269567Y439605D03*
X269537Y451735D03*
Y447735D03*
X286783Y136962D03*
X285516Y229606D03*
X278483Y451862D03*
Y447862D03*
X290003Y569548D03*
Y566022D03*
X298400Y67513D03*
X298910Y85983D03*
Y82483D03*
X305140Y91767D03*
X293683Y139162D03*
X292603Y634283D03*
Y630757D03*
X290877Y685071D03*
Y688597D03*
X320040Y95803D03*
X320086Y99837D03*
X308083Y146702D03*
X317957Y228258D03*
X309202Y599318D03*
X317708Y595998D03*
X323883Y161562D03*
X323292Y559218D03*
X350521Y142869D03*
X339683Y141862D03*
X349680Y705779D03*
X356203Y225862D03*
X381703Y217362D03*
Y208862D03*
Y212862D03*
Y221362D03*
Y225362D03*
X387823Y1622722D03*
X388643Y119822D03*
Y132822D03*
X398415Y1398653D03*
X402404Y1537810D03*
Y1545810D03*
Y1560810D03*
Y1564810D03*
X406382Y1411231D03*
X407533Y1549942D03*
X414183Y1603500D03*
Y1615200D03*
X415703Y1672362D03*
Y1676362D03*
Y1668362D03*
X432904Y1547810D03*
Y1551810D03*
X430028Y1583466D03*
X421683Y1616600D03*
X421633Y1620402D03*
X421598Y1624692D03*
Y1628692D03*
Y1632842D03*
X422193Y1643159D03*
X422213Y1647216D03*
X421598Y1636842D03*
X449839Y145710D03*
X448311Y505483D03*
Y509483D03*
Y513483D03*
Y517483D03*
Y521483D03*
Y525483D03*
Y542519D03*
Y547519D03*
X444366Y1600154D03*
X459622Y120948D03*
X457983Y213362D03*
Y222362D03*
X453503Y1547437D03*
X471330Y1400435D03*
X471299Y1396606D03*
X469396Y1610682D03*
Y1603682D03*
X474343Y1631003D03*
X469353Y1622735D03*
X469443Y1626732D03*
X474283Y1634947D03*
X475413Y1647242D03*
Y1663242D03*
X475343Y1677462D03*
Y1681462D03*
X488656Y66565D03*
X488766Y61205D03*
X488926Y55895D03*
X492319Y309398D03*
X501643Y615612D03*
X493339Y1424033D03*
X509983Y223362D03*
X505483Y241862D03*
X509154Y1422494D03*
X520308Y168443D03*
X521793Y455062D03*
X519883Y489112D03*
X529873Y500222D03*
X519069Y500469D03*
Y505969D03*
X519883Y495112D03*
X519069Y511469D03*
Y516969D03*
Y522469D03*
Y527969D03*
Y539819D03*
X518483Y615742D03*
X539323Y99172D03*
X539383Y112512D03*
X539547Y269472D03*
X538433Y454270D03*
X555453Y127788D03*
Y137774D03*
Y153878D03*
X552703Y161362D03*
Y184862D03*
Y171862D03*
X567483Y102862D03*
Y98862D03*
X573023Y157932D03*
X582333Y157684D03*
X573703Y225362D03*
Y221362D03*
X569572Y310847D03*
X568308Y424392D03*
X568000Y446706D03*
X580553Y493212D03*
Y488212D03*
Y497212D03*
X570553Y1355247D03*
Y1358777D03*
X595303Y136314D03*
Y125314D03*
X599238Y159480D03*
X584939Y194378D03*
X584703Y230862D03*
X591635Y288527D03*
X612818Y184062D03*
X602703Y416362D03*
X604703Y444362D03*
Y449362D03*
X602882Y454600D03*
X603703Y506862D03*
Y510862D03*
X628519Y208076D03*
Y212076D03*
X630703Y234362D03*
Y230362D03*
X620703Y426362D03*
X619703Y472862D03*
Y477862D03*
Y462862D03*
Y467862D03*
X634400Y88039D03*
Y92119D03*
X648127Y140699D03*
Y149871D03*
Y154345D03*
X642617Y249202D03*
Y260202D03*
X640628Y294327D03*
Y290267D03*
Y306547D03*
X634703Y416362D03*
Y472862D03*
Y477862D03*
Y467862D03*
X636203Y526362D03*
X645203Y1714362D03*
Y1726362D03*
X649203Y184862D03*
X649703Y411362D03*
Y421362D03*
Y426362D03*
Y477862D03*
Y472862D03*
Y482862D03*
X668501Y1647557D03*
X668576Y1659557D03*
X668603Y1664862D03*
Y1676862D03*
X671703Y1712362D03*
Y1728362D03*
X693703Y76962D03*
X693936Y91668D03*
X683436Y119568D03*
Y123420D03*
X694705Y1640667D03*
X694630Y1636667D03*
X695103Y1662862D03*
Y1678862D03*
X713203Y221862D03*
X707595Y1567683D03*
Y1579683D03*
Y1571683D03*
Y1575683D03*
Y1587683D03*
Y1595683D03*
Y1591683D03*
X726616Y160788D03*
X723428Y1564088D03*
X722735Y1569493D03*
X721816Y1680400D03*
X714616D03*
X732976Y86998D03*
X733486Y101968D03*
X741216Y111252D03*
X733486Y105468D03*
X729735Y1569493D03*
X730836Y1614503D03*
X730735Y1609893D03*
X754616Y115288D03*
X754618Y119172D03*
X748728Y137864D03*
X751143Y265322D03*
Y269322D03*
X757595Y1583183D03*
X748138Y1682362D03*
Y1678362D03*
X777903Y163254D03*
X775924Y308755D03*
X776009Y303410D03*
X763703Y413212D03*
Y403212D03*
Y408212D03*
Y398212D03*
X777823Y454862D03*
Y459862D03*
X762823D03*
Y454862D03*
Y474862D03*
X762883Y493452D03*
X765103Y1379962D03*
Y1375462D03*
X765003Y1384062D03*
Y1401562D03*
Y1397262D03*
X764903Y1414762D03*
X768622Y1573793D03*
X768635Y1581893D03*
Y1577893D03*
Y1590893D03*
X763698Y1698521D03*
X782643Y274822D03*
X789109Y303410D03*
X789024Y308755D03*
X790983Y385300D03*
X778703Y393212D03*
X792903Y398212D03*
X792823Y444862D03*
Y439862D03*
Y449862D03*
Y454862D03*
Y459862D03*
Y469862D03*
X808553Y441060D03*
Y445100D03*
X808323Y454862D03*
Y459862D03*
Y449862D03*
Y464862D03*
X810135Y1573793D03*
Y1581793D03*
Y1597793D03*
Y1585793D03*
Y1605793D03*
X820783Y449200D03*
X822323Y476800D03*
Y464862D03*
Y468900D03*
Y472900D03*
X840308Y90451D03*
X842203Y135862D03*
Y129362D03*
X830460Y409260D03*
Y405260D03*
X827983Y449200D03*
X827253Y511082D03*
Y506082D03*
Y527082D03*
Y519082D03*
X851703Y129362D03*
Y135862D03*
X859286Y265057D03*
X846730Y271049D03*
X852383Y473000D03*
Y469100D03*
X852135Y1573793D03*
Y1581793D03*
Y1597793D03*
Y1585793D03*
Y1605793D03*
X874203Y171362D03*
Y176862D03*
X868983Y196500D03*
X868376Y227763D03*
Y223763D03*
X861075Y240441D03*
X859796Y280027D03*
X867526Y289311D03*
X859796Y283527D03*
X862483Y378362D03*
X867969Y386476D03*
Y402581D03*
Y398620D03*
X868021Y414276D03*
X860103Y507162D03*
Y495300D03*
X884283Y201150D03*
Y195720D03*
X884208Y192055D03*
X880926Y293347D03*
X880949Y298665D03*
X902336Y484913D03*
Y480913D03*
X902131Y493299D03*
Y489299D03*
X902116Y501573D03*
Y497573D03*
X894805Y874405D03*
X895375Y920325D03*
X907972Y975134D03*
Y971234D03*
Y992834D03*
Y988934D03*
X894135Y1573793D03*
Y1581793D03*
Y1597793D03*
Y1585793D03*
Y1605793D03*
X936135Y1593393D03*
X946398Y184912D03*
X946318Y188852D03*
X951542Y424298D03*
X951465Y428124D03*
X951438Y437844D03*
X951515Y434018D03*
X948793Y997422D03*
X973076Y356896D03*
X985407Y171483D03*
X994483Y148299D03*
X1001483D03*
X997395Y213233D03*
X1003793Y363352D03*
X1012859Y167278D03*
Y171278D03*
X1018073Y190176D03*
X1017953Y363222D03*
X1037316Y268264D03*
X1030761Y523628D03*
Y514176D03*
X1041352Y509606D03*
X1039093Y523642D03*
X1039513Y514182D03*
X1087204Y69602D03*
X1082172Y83698D03*
X1073904Y265574D03*
X1083093Y379251D03*
X1082973Y369061D03*
X1083033Y374131D03*
X1072638Y386723D03*
X1091273Y1670963D03*
X1107155Y60028D03*
X1113502Y72803D03*
Y77559D03*
X1152020Y73679D03*
X1137625Y1555301D03*
X1139033Y1597630D03*
Y1601630D03*
X1152165Y1626280D03*
X1160503Y211370D03*
X1153563Y363231D03*
X1153493Y368041D03*
X1171354Y61311D03*
Y65811D03*
X1171374Y57111D03*
X1178728Y194174D03*
Y190174D03*
Y206174D03*
Y210174D03*
Y222174D03*
X1198283Y97400D03*
Y89000D03*
Y101600D03*
X1185283Y111600D03*
X1198471Y212648D03*
X1200458Y240672D03*
Y244692D03*
X1196978Y1359636D03*
Y1363146D03*
X1216084Y53860D03*
X1207244Y61060D03*
X1211683Y93600D03*
X1212883Y113200D03*
X1211576Y164962D03*
Y176962D03*
X1213002Y171611D03*
X1210703Y200309D03*
Y195362D03*
X1206568Y1681767D03*
X1219483Y93600D03*
X1225977Y113982D03*
X1220076Y119462D03*
X1231594Y129409D03*
X1220076Y132962D03*
X1231576Y134262D03*
Y153115D03*
X1220080Y148909D03*
Y144909D03*
X1231576Y141110D03*
X1220076Y153962D03*
Y157962D03*
Y168962D03*
Y164962D03*
X1231576Y163462D03*
Y156962D03*
X1220076Y176962D03*
X1231576Y177962D03*
X1220062Y172945D03*
X1220203Y194862D03*
X1245365Y95008D03*
X1235873Y102608D03*
X1235874Y106609D03*
X1242076Y209462D03*
Y205862D03*
Y213462D03*
Y217462D03*
X1237843Y244332D03*
Y248332D03*
X1251076Y233462D03*
Y223462D03*
Y227462D03*
Y237462D03*
Y241462D03*
X1281774Y102928D03*
X1270237Y92724D03*
X1305517Y68562D03*
X1300494Y85138D03*
X1319283Y261662D03*
X1373099Y1403458D03*
X1373156Y1399053D03*
X1373099Y1407458D03*
X1382523Y1411231D03*
X1384120Y1415495D03*
X1408916Y1516435D03*
X1409156Y1532255D03*
X1408916Y1521335D03*
X1400083Y1521362D03*
X1409306Y1543475D03*
X1409156Y1537155D03*
X1409306Y1548375D03*
X1399983Y1537162D03*
Y1548362D03*
X1397891Y1565037D03*
X1402383Y1582500D03*
X1398065Y1576097D03*
X1397891Y1570037D03*
X1402383Y1594000D03*
X1398383Y1609522D03*
X1405483Y1630362D03*
Y1642362D03*
X1424366Y227948D03*
X1417883Y1593700D03*
X1427233Y1612812D03*
X1444183Y60062D03*
X1444905Y1400204D03*
X1444939Y1396269D03*
X1443883Y1598400D03*
Y1611000D03*
X1439283Y1624500D03*
Y1628700D03*
X1431483Y1637362D03*
X1454750Y1526689D03*
X1454990Y1542509D03*
X1455140Y1553729D03*
X1453143Y1590302D03*
X1474050Y64355D03*
X1469480Y1424033D03*
X1487866Y233448D03*
X1487568Y255378D03*
X1485283Y421982D03*
X1485295Y1422494D03*
X1505441Y280056D03*
X1520051Y231116D03*
Y239116D03*
Y249698D03*
Y262616D03*
X1519741Y280956D03*
X1519983Y272362D03*
X1520121Y268214D03*
X1519741Y288956D03*
X1535483Y125362D03*
Y121362D03*
X1529141Y150651D03*
X1540822Y310487D03*
X1549871Y127781D03*
X1553220Y634165D03*
X1563775Y651039D03*
X1591983Y199362D03*
X1591822Y256244D03*
X1600399Y1411169D03*
Y1415669D03*
Y1424669D03*
Y1429169D03*
Y1442669D03*
Y1447153D03*
X1639664Y624475D03*
X1638565Y652601D03*
X1639664Y658475D03*
X1638565Y686601D03*
X1639664Y692475D03*
X1638565Y720601D03*
X1644938Y180460D03*
X1647593Y414202D03*
X1645415Y614845D03*
X1663428Y195935D03*
X1657712Y524071D03*
X1657663Y520540D03*
X1657712Y528071D03*
Y532071D03*
Y540071D03*
Y536071D03*
X1665814Y594959D03*
X1664905Y607291D03*
X1656883Y631703D03*
X1657355Y649681D03*
X1656883Y665703D03*
X1657355Y683681D03*
X1656883Y699703D03*
X1657355Y717681D03*
X1671581Y1497362D03*
Y1512862D03*
Y1505362D03*
Y1524862D03*
Y1537862D03*
Y1541862D03*
Y1553557D03*
X1671656Y1565557D03*
Y1585321D03*
X1688978Y473878D03*
Y469878D03*
X1689003Y465940D03*
X1687414Y478790D03*
Y482790D03*
Y488290D03*
X1682971Y491790D03*
X1686552Y552241D03*
X1695487Y401485D03*
X1690116Y424694D03*
X1696759Y518107D03*
Y513107D03*
Y541507D03*
Y537507D03*
Y545507D03*
Y553527D03*
X1704950Y723005D03*
X1702231Y1500862D03*
Y1520362D03*
Y1541362D03*
X1702511Y1564057D03*
X1703231Y1583821D03*
X1714763Y165909D03*
X1714812Y161900D03*
Y157892D03*
X1714763Y170326D03*
X1718010Y424340D03*
Y420340D03*
X1713563Y499412D03*
X1707518Y531613D03*
X1710403Y701062D03*
X1735277Y61639D03*
X1735325Y65749D03*
X1735280Y57454D03*
X1736101Y88787D03*
X1725401Y116867D03*
X1729517Y181234D03*
X1729348Y177072D03*
Y173072D03*
X1722912Y490869D03*
Y486869D03*
Y482869D03*
Y494869D03*
X1730862Y490869D03*
Y486869D03*
Y480669D03*
X1723632Y1496270D03*
X1754142Y187509D03*
X1754070Y364048D03*
X1754203Y377452D03*
X1754070Y368048D03*
X1754203Y382952D03*
X1763521Y68637D03*
X1764031Y83607D03*
Y87107D03*
X1767910Y364148D03*
X1767703Y372452D03*
X1767910Y368148D03*
X1767703Y377452D03*
X1771761Y92891D03*
X1785161Y96927D03*
X1785119Y100939D03*
X1774858Y173903D03*
Y178403D03*
X1773034Y461393D03*
Y465893D03*
Y470193D03*
X1802782Y161465D03*
X1791871Y1506538D03*
X1818782Y413432D03*
Y417432D03*
X1825670Y170162D03*
X1832362Y399185D03*
X1826822Y434202D03*
X1835434Y453921D03*
X1835424Y467321D03*
Y463193D03*
X1845943Y172187D03*
X1838788Y192678D03*
G54D135*
X318333Y78520D03*
X316364D03*
X314395D03*
X312427D03*
X310459D03*
X308490D03*
X306521D03*
X318333Y80489D03*
X316364D03*
X314395D03*
X312427D03*
X310459D03*
X308490D03*
X306521D03*
X318333Y82457D03*
X316364D03*
X314395D03*
X312427D03*
X310459D03*
X308490D03*
X306521D03*
X318333Y84426D03*
X316364D03*
X314395D03*
X312427D03*
X310459D03*
X308490D03*
X306521D03*
X325002Y212333D03*
Y214302D03*
Y216271D03*
X326971Y212333D03*
Y214302D03*
Y216271D03*
X328939Y212333D03*
Y214302D03*
Y216271D03*
X330908Y212333D03*
Y214302D03*
Y216271D03*
X325002Y218239D03*
Y220207D03*
Y222176D03*
Y224145D03*
X326971Y218239D03*
Y220207D03*
Y222176D03*
Y224145D03*
X328939Y218239D03*
Y220207D03*
Y222176D03*
Y224145D03*
X330908Y218239D03*
Y220207D03*
Y222176D03*
Y224145D03*
X745035Y98005D03*
X743066D03*
X741097D03*
X745035Y99974D03*
X743066D03*
X741097D03*
X745035Y101942D03*
X743066D03*
X741097D03*
X745035Y103911D03*
X743066D03*
X741097D03*
X752909Y98005D03*
X750940D03*
X748971D03*
X747003D03*
X752909Y99974D03*
X750940D03*
X748971D03*
X747003D03*
X752909Y101942D03*
X750940D03*
X748971D03*
X747003D03*
X752909Y103911D03*
X750940D03*
X748971D03*
X747003D03*
X873313Y276064D03*
X871345D03*
X869376D03*
X867407D03*
X873313Y278033D03*
X871345D03*
X869376D03*
X867407D03*
X873313Y280001D03*
X871345D03*
X869376D03*
X867407D03*
X873313Y281970D03*
X871345D03*
X869376D03*
X867407D03*
X879219Y276064D03*
X877250D03*
X875281D03*
X879219Y278033D03*
X877250D03*
X875281D03*
X879219Y280001D03*
X877250D03*
X875281D03*
X879219Y281970D03*
X877250D03*
X875281D03*
X992452Y155667D03*
Y157636D03*
Y159605D03*
Y161573D03*
Y163541D03*
Y165510D03*
Y167479D03*
X994421Y155667D03*
Y157636D03*
Y159605D03*
Y161573D03*
Y163541D03*
Y165510D03*
Y167479D03*
X996389Y155667D03*
Y157636D03*
Y159605D03*
Y161573D03*
Y163541D03*
Y165510D03*
Y167479D03*
X998358Y155667D03*
Y157636D03*
Y159605D03*
Y161573D03*
Y163541D03*
Y165510D03*
Y167479D03*
X1697161Y408769D03*
Y410738D03*
Y412707D03*
X1699130Y408769D03*
Y410738D03*
Y412707D03*
X1701098Y408769D03*
Y410738D03*
Y412707D03*
X1703067Y408769D03*
Y410738D03*
Y412707D03*
X1697161Y414675D03*
Y416643D03*
Y418612D03*
Y420581D03*
X1699130Y414675D03*
Y416643D03*
Y418612D03*
Y420581D03*
X1701098Y414675D03*
Y416643D03*
Y418612D03*
Y420581D03*
X1703067Y414675D03*
Y416643D03*
Y418612D03*
Y420581D03*
X1783454Y79644D03*
X1781485D03*
X1779516D03*
X1777548D03*
X1775580D03*
X1773611D03*
X1771642D03*
X1783454Y81613D03*
X1781485D03*
X1779516D03*
X1777548D03*
X1775580D03*
X1773611D03*
X1771642D03*
X1783454Y83581D03*
X1781485D03*
X1779516D03*
X1777548D03*
X1775580D03*
X1773611D03*
X1771642D03*
X1783454Y85550D03*
X1781485D03*
X1779516D03*
X1777548D03*
X1775580D03*
X1773611D03*
X1771642D03*
G54D171*
X485673Y375319D03*
X479767D03*
Y382405D03*
X485673D03*
X499073Y375426D03*
X493167D03*
Y382512D03*
X499073D03*
X515173Y375319D03*
X509267D03*
Y382405D03*
X515173D03*
X513173Y404819D03*
X507267D03*
Y411905D03*
X513173D03*
X532173Y375819D03*
X526267D03*
Y382905D03*
X532173D03*
X529173Y404819D03*
X523267D03*
Y411905D03*
X529173D03*
G54D216*
X842684Y389140D03*
Y392880D03*
Y396620D03*
X852998D03*
Y392880D03*
Y389140D03*
G54D42*
X68365Y707219D03*
X76265D03*
X68365Y714219D03*
X76265D03*
X185667Y704526D03*
Y697526D03*
X282640Y217602D03*
Y224602D03*
X531220Y295862D03*
Y288862D03*
X764850Y253292D03*
Y260292D03*
X958452Y157603D03*
Y164603D03*
X969390Y212089D03*
Y205089D03*
X979708Y150885D03*
Y157885D03*
X1000582Y273824D03*
Y280824D03*
X1016175Y273690D03*
Y280690D03*
X1008445Y273690D03*
Y280690D03*
X1527618Y296386D03*
Y303386D03*
X1535048Y296386D03*
Y303386D03*
X1667570Y414332D03*
Y421332D03*
X1671306Y584056D03*
Y591056D03*
X1679850Y428172D03*
Y435172D03*
X1689697Y718205D03*
Y711205D03*
X1681797Y718205D03*
Y711205D03*
X1698170Y231982D03*
Y224982D03*
X1747050Y197522D03*
X1740120Y197592D03*
X1747050Y204522D03*
X1740120Y204592D03*
X1784826Y276996D03*
Y283996D03*
X1798926Y273096D03*
Y280096D03*
X1791826Y276996D03*
Y283996D03*
X1790326Y298028D03*
X1797326D03*
X1804326D03*
X1790326Y305028D03*
X1797326D03*
X1804326D03*
X1805986Y273159D03*
Y280159D03*
X1813086Y273159D03*
Y280159D03*
X1811386Y297965D03*
Y304965D03*
X1816784Y1515171D03*
Y1522171D03*
X1823684Y1515171D03*
X1830584D03*
X1823684Y1522171D03*
X1830584D03*
G54D162*
X441043Y1698268D03*
X1416437Y1698267D03*
G54D234*
X953235Y977250D03*
Y985596D03*
X959535Y977250D03*
Y985596D03*
G54D252*
X1037026Y275752D03*
X1023640Y286776D03*
X1795857Y1521592D03*
X1809243Y1510568D03*
G54D207*
X771066Y440803D03*
X764374D03*
Y445921D03*
X771066D03*
G54D306*
X1756127Y296368D03*
X1774731D03*
G54D270*
X1281262Y125396D03*
X1277160Y129498D03*
G54D180*
X536127Y250962D03*
X544001Y254702D03*
X536127Y258442D03*
X642563Y495000D03*
X650437Y491260D03*
Y498740D03*
X755505Y1674823D03*
Y1682303D03*
X763379Y1678563D03*
X793693Y505972D03*
X793673Y516142D03*
Y523622D03*
X806961Y393924D03*
Y408524D03*
Y401404D03*
Y416004D03*
X801567Y509712D03*
Y502232D03*
X801547Y519882D03*
X814835Y397664D03*
Y412264D03*
X1084394Y1650210D03*
X1076520Y1653950D03*
X1084394Y1657690D03*
G54D108*
X217124Y576051D03*
Y610051D03*
Y644051D03*
X1636849Y644531D03*
Y678531D03*
Y712531D03*
G54D24*
X45876Y384395D03*
Y386364D03*
Y388333D03*
Y390301D03*
Y392269D03*
Y394238D03*
Y396207D03*
X64872D03*
Y394238D03*
Y392269D03*
Y390301D03*
Y388333D03*
Y386364D03*
Y384395D03*
X609146Y142875D03*
Y144844D03*
Y146813D03*
Y148781D03*
Y150749D03*
Y152718D03*
Y154687D03*
X628142Y152718D03*
Y150749D03*
Y148781D03*
Y146813D03*
Y144844D03*
Y142875D03*
Y154687D03*
G54D153*
X400317Y123647D03*
Y126207D03*
X417443D03*
Y123647D03*
X842562Y170918D03*
Y173478D03*
X859688D03*
Y170918D03*
X1049186Y512644D03*
Y515204D03*
X1066312D03*
Y512644D03*
X1742907Y174587D03*
Y177147D03*
X1760033D03*
Y174587D03*
G54D60*
X84430Y1334666D03*
X1093936Y1616149D03*
X1769097Y1332916D03*
G54D126*
X269181Y224782D03*
X1653051Y414202D03*
G54D261*
X1127008Y1537244D03*
G54D243*
X1004868Y190419D03*
G54D117*
X236435Y582055D03*
Y616055D03*
Y650055D03*
X254545Y582055D03*
Y616055D03*
Y650055D03*
X1599428Y638527D03*
Y672527D03*
Y706527D03*
X1617538Y638527D03*
Y672527D03*
Y706527D03*
G54D144*
X335928Y879124D03*
X337779Y875920D03*
Y882329D03*
X335928Y885533D03*
Y891942D03*
Y898350D03*
X337779Y888737D03*
Y895146D03*
Y901555D03*
X335928Y904759D03*
Y911167D03*
Y917576D03*
X337779Y907963D03*
Y914372D03*
X335928Y923985D03*
Y930393D03*
X337779Y920780D03*
Y927189D03*
Y933598D03*
X335928Y936801D03*
Y943210D03*
Y949619D03*
X337779Y940006D03*
Y946414D03*
X335928Y956027D03*
Y962436D03*
X337779Y952823D03*
Y959232D03*
Y965640D03*
X335928Y968845D03*
Y975253D03*
X337779Y972049D03*
Y978457D03*
X336361Y1010391D03*
X338211Y1007187D03*
Y1013595D03*
X336361Y1016800D03*
Y1023208D03*
X338211Y1020004D03*
X336361Y1029617D03*
X338211Y1026413D03*
X336361Y1036026D03*
Y1042434D03*
X338211Y1032821D03*
Y1039230D03*
Y1045639D03*
X336361Y1048842D03*
X338211Y1052047D03*
Y1058455D03*
Y1064864D03*
Y1071273D03*
Y1077681D03*
Y1084090D03*
Y1090498D03*
Y1096907D03*
Y1103316D03*
Y1109724D03*
X352579Y850286D03*
X347029Y859899D03*
Y866307D03*
X348879Y856694D03*
Y863103D03*
X350728Y853490D03*
Y859899D03*
Y866307D03*
X352579Y856694D03*
Y863103D03*
X354428Y853490D03*
Y859899D03*
Y866307D03*
X343328D03*
X345179Y863103D03*
X347029Y872716D03*
X348879Y869511D03*
X350728Y872716D03*
X352579Y869511D03*
X354428Y872716D03*
X339629D03*
X341479Y869511D03*
X343328Y872716D03*
X345179Y869511D03*
X347029Y879124D03*
X348879Y875920D03*
Y882329D03*
X350728Y879124D03*
X352579Y875920D03*
Y882329D03*
X354428Y879124D03*
X339629D03*
X341479Y875920D03*
Y882329D03*
X343328Y879124D03*
X345179Y875920D03*
Y882329D03*
X347029Y885533D03*
Y891942D03*
Y898350D03*
X348879Y888737D03*
Y895146D03*
Y901555D03*
X350728Y885533D03*
Y891942D03*
Y898350D03*
X352579Y888737D03*
Y895146D03*
Y901555D03*
X354428Y885533D03*
Y891942D03*
Y898350D03*
X339629Y885533D03*
Y891942D03*
Y898350D03*
X341479Y888737D03*
Y895146D03*
Y901555D03*
X343328Y885533D03*
Y891942D03*
Y898350D03*
X345179Y888737D03*
Y895146D03*
Y901555D03*
X347029Y904759D03*
Y911167D03*
Y917576D03*
X348879Y907963D03*
Y914372D03*
X350728Y904759D03*
Y911167D03*
Y917576D03*
X352579Y907963D03*
Y914372D03*
X354428Y904759D03*
Y911167D03*
Y917576D03*
X339629Y904759D03*
Y911167D03*
Y917576D03*
X341479Y907963D03*
Y914372D03*
X343328Y904759D03*
Y911167D03*
Y917576D03*
X345179Y907963D03*
Y914372D03*
X347029Y923985D03*
Y930393D03*
X348879Y920780D03*
Y927189D03*
Y933598D03*
X350728Y923985D03*
Y930393D03*
X352579Y920780D03*
Y927189D03*
Y933598D03*
X354428Y923985D03*
Y930393D03*
X339629Y923985D03*
Y930393D03*
X341479Y920780D03*
Y927189D03*
Y933598D03*
X343328Y923985D03*
Y930393D03*
X345179Y920780D03*
Y927189D03*
Y933598D03*
X347029Y936801D03*
Y943210D03*
Y949619D03*
X348879Y940006D03*
Y946414D03*
X350728Y936801D03*
Y943210D03*
Y949619D03*
X352579Y940006D03*
Y946414D03*
X354428Y936801D03*
Y943210D03*
Y949619D03*
X339629Y936801D03*
Y943210D03*
Y949619D03*
X341479Y940006D03*
Y946414D03*
X343328Y936801D03*
Y943210D03*
Y949619D03*
X345179Y940006D03*
Y946414D03*
X347029Y956027D03*
Y962436D03*
X348879Y952823D03*
Y959232D03*
X350728Y956027D03*
Y962436D03*
X352579Y952823D03*
Y959232D03*
X354428Y956027D03*
Y962436D03*
X339629Y956027D03*
Y962436D03*
X341479Y952823D03*
Y959232D03*
X343328Y956027D03*
Y962436D03*
X345179Y952823D03*
Y959232D03*
X348879Y965640D03*
X352579D03*
X341479D03*
X345179D03*
X347029Y968845D03*
Y975253D03*
Y981662D03*
X348879Y972049D03*
Y978457D03*
X350728Y968845D03*
Y975253D03*
Y981662D03*
X352579Y972049D03*
Y978457D03*
X354428Y968845D03*
Y975253D03*
Y981662D03*
X339629Y968845D03*
Y975253D03*
Y981662D03*
X341479Y972049D03*
Y978457D03*
X343328Y968845D03*
Y975253D03*
Y981662D03*
X345179Y972049D03*
Y978457D03*
X348879Y984866D03*
X352579D03*
X341479D03*
X345179D03*
X347461Y997574D03*
X351161D03*
X354861D03*
X343761D03*
X347461Y1003983D03*
Y1010391D03*
X349312Y1000778D03*
Y1007187D03*
Y1013595D03*
X351161Y1003983D03*
Y1010391D03*
X353011Y1000778D03*
Y1007187D03*
Y1013595D03*
X354861Y1003983D03*
Y1010391D03*
X340061Y1003983D03*
Y1010391D03*
X341912Y1000778D03*
Y1007187D03*
Y1013595D03*
X343761Y1003983D03*
Y1010391D03*
X345611Y1000778D03*
Y1007187D03*
Y1013595D03*
X347461Y1016800D03*
Y1023208D03*
X349312Y1020004D03*
X351161Y1016800D03*
Y1023208D03*
X353011Y1020004D03*
X354861Y1016800D03*
Y1023208D03*
X340061Y1016800D03*
Y1023208D03*
X341912Y1020004D03*
X343761Y1016800D03*
Y1023208D03*
X345611Y1020004D03*
X347461Y1029617D03*
X349312Y1026413D03*
X351161Y1029617D03*
X353011Y1026413D03*
X354861Y1029617D03*
X340061D03*
X341912Y1026413D03*
X343761Y1029617D03*
X345611Y1026413D03*
X347461Y1036026D03*
Y1042434D03*
X349312Y1032821D03*
Y1039230D03*
Y1045639D03*
X351161Y1036026D03*
Y1042434D03*
X353011Y1032821D03*
Y1039230D03*
Y1045639D03*
X354861Y1036026D03*
Y1042434D03*
X340061Y1036026D03*
Y1042434D03*
X341912Y1032821D03*
Y1039230D03*
Y1045639D03*
X343761Y1036026D03*
Y1042434D03*
X345611Y1032821D03*
Y1039230D03*
Y1045639D03*
X347461Y1048842D03*
X349312Y1052047D03*
X351161Y1048842D03*
X353011Y1052047D03*
X354861Y1048842D03*
X340061D03*
X341912Y1052047D03*
X343761Y1048842D03*
X345611Y1052047D03*
X347461Y1055251D03*
Y1061660D03*
X349312Y1058455D03*
X351161Y1055251D03*
Y1061660D03*
X353011Y1058455D03*
X354861Y1055251D03*
Y1061660D03*
X340061Y1055251D03*
Y1061660D03*
X341912Y1058455D03*
X343761Y1055251D03*
Y1061660D03*
X345611Y1058455D03*
X347461Y1068068D03*
Y1074477D03*
X349312Y1064864D03*
Y1071273D03*
Y1077681D03*
X351161Y1068068D03*
Y1074477D03*
X353011Y1064864D03*
Y1071273D03*
Y1077681D03*
X354861Y1068068D03*
Y1074477D03*
X340061Y1068068D03*
Y1074477D03*
X341912Y1064864D03*
Y1071273D03*
Y1077681D03*
X343761Y1068068D03*
Y1074477D03*
X345611Y1064864D03*
Y1071273D03*
Y1077681D03*
X347461Y1080885D03*
X351161D03*
X354861D03*
X340061D03*
X343761D03*
X347461Y1087294D03*
Y1093703D03*
X349312Y1084090D03*
Y1090498D03*
X351161Y1087294D03*
Y1093703D03*
X353011Y1084090D03*
Y1090498D03*
X354861Y1087294D03*
Y1093703D03*
X340061Y1087294D03*
Y1093703D03*
X341912Y1084090D03*
Y1090498D03*
X343761Y1087294D03*
Y1093703D03*
X345611Y1084090D03*
Y1090498D03*
X347461Y1100111D03*
Y1106520D03*
Y1112929D03*
X349312Y1096907D03*
Y1103316D03*
Y1109724D03*
X351161Y1100111D03*
Y1106520D03*
Y1112929D03*
X353011Y1096907D03*
Y1103316D03*
Y1109724D03*
X354861Y1100111D03*
Y1106520D03*
Y1112929D03*
X340061Y1100111D03*
Y1106520D03*
Y1112929D03*
X341912Y1096907D03*
Y1103316D03*
Y1109724D03*
X343761Y1100111D03*
Y1106520D03*
Y1112929D03*
X345611Y1096907D03*
Y1103316D03*
Y1109724D03*
X347461Y1119337D03*
Y1125746D03*
X349312Y1116133D03*
Y1122541D03*
Y1128950D03*
X351161Y1119337D03*
Y1125746D03*
X353011Y1116133D03*
Y1122541D03*
Y1128950D03*
X354861Y1119337D03*
Y1125746D03*
X341912Y1116133D03*
X343761Y1119337D03*
X345611Y1116133D03*
Y1122541D03*
X351161Y1132154D03*
X354861D03*
X371079Y850286D03*
X356279D03*
X358128Y847081D03*
X359979Y850286D03*
X361828Y847081D03*
X363679Y850286D03*
X365528Y847081D03*
X367379Y850286D03*
X369228Y847081D03*
X371079Y856694D03*
Y863103D03*
X356279Y856694D03*
Y863103D03*
X358128Y853490D03*
Y859899D03*
Y866307D03*
X359979Y856694D03*
Y863103D03*
X361828Y853490D03*
Y859899D03*
Y866307D03*
X363679Y856694D03*
Y863103D03*
X365528Y853490D03*
Y859899D03*
Y866307D03*
X367379Y856694D03*
Y863103D03*
X369228Y853490D03*
Y859899D03*
Y866307D03*
X371079Y869511D03*
X356279D03*
X358128Y872716D03*
X359979Y869511D03*
X361828Y872716D03*
X363679Y869511D03*
X365528Y872716D03*
X367379Y869511D03*
X369228Y872716D03*
X371079Y875920D03*
Y882329D03*
X356279Y875920D03*
Y882329D03*
X358128Y879124D03*
X359979Y875920D03*
Y882329D03*
X361828Y879124D03*
X363679Y875920D03*
Y882329D03*
X365528Y879124D03*
X367379Y875920D03*
Y882329D03*
X369228Y879124D03*
X371079Y888737D03*
Y895146D03*
Y901555D03*
X356279Y888737D03*
Y895146D03*
Y901555D03*
X358128Y885533D03*
Y891942D03*
Y898350D03*
X359979Y888737D03*
Y895146D03*
Y901555D03*
X361828Y885533D03*
Y891942D03*
Y898350D03*
X363679Y888737D03*
Y895146D03*
Y901555D03*
X365528Y885533D03*
Y891942D03*
Y898350D03*
X367379Y888737D03*
Y895146D03*
Y901555D03*
X369228Y885533D03*
Y891942D03*
Y898350D03*
X371079Y907963D03*
Y914372D03*
X356279Y907963D03*
Y914372D03*
X358128Y904759D03*
Y911167D03*
Y917576D03*
X359979Y907963D03*
Y914372D03*
X361828Y904759D03*
Y911167D03*
Y917576D03*
X363679Y907963D03*
Y914372D03*
X365528Y904759D03*
Y911167D03*
Y917576D03*
X367379Y907963D03*
Y914372D03*
X369228Y904759D03*
Y911167D03*
Y917576D03*
X371079Y920780D03*
Y927189D03*
X356279Y920780D03*
Y927189D03*
Y933598D03*
X358128Y923985D03*
Y930393D03*
X359979Y920780D03*
Y927189D03*
Y933598D03*
X361828Y923985D03*
Y930393D03*
X363679Y920780D03*
Y927189D03*
Y933598D03*
X365528Y923985D03*
Y930393D03*
X367379Y920780D03*
Y927189D03*
Y933598D03*
X369228Y923985D03*
Y930393D03*
X371079Y933598D03*
Y940006D03*
Y946414D03*
X356279Y940006D03*
Y946414D03*
X358128Y936801D03*
Y943210D03*
Y949619D03*
X359979Y940006D03*
Y946414D03*
X361828Y936801D03*
Y943210D03*
Y949619D03*
X363679Y940006D03*
Y946414D03*
X365528Y936801D03*
Y943210D03*
Y949619D03*
X367379Y940006D03*
Y946414D03*
X369228Y936801D03*
Y943210D03*
Y949619D03*
X371079Y952823D03*
Y959232D03*
X356279Y952823D03*
Y959232D03*
X358128Y956027D03*
Y962436D03*
X359979Y952823D03*
Y959232D03*
X361828Y956027D03*
Y962436D03*
X363679Y952823D03*
Y959232D03*
X365528Y956027D03*
Y962436D03*
X367379Y952823D03*
Y959232D03*
X369228Y956027D03*
Y962436D03*
X371079Y965640D03*
X356279D03*
X359979D03*
X363679D03*
X367379D03*
X371079Y972049D03*
Y978457D03*
X356279Y972049D03*
Y978457D03*
X358128Y968845D03*
Y975253D03*
Y981662D03*
X359979Y972049D03*
Y978457D03*
X361828Y968845D03*
Y975253D03*
Y981662D03*
X363679Y972049D03*
Y978457D03*
X365528Y968845D03*
Y975253D03*
Y981662D03*
X367379Y972049D03*
Y978457D03*
X369228Y968845D03*
Y975253D03*
Y981662D03*
X371079Y984866D03*
X356279D03*
X359979D03*
X363679D03*
X367379D03*
X358561Y997574D03*
X362261D03*
X365961D03*
X369661D03*
X356712Y1000778D03*
Y1007187D03*
Y1013595D03*
X358561Y1003983D03*
Y1010391D03*
X360412Y1000778D03*
Y1007187D03*
Y1013595D03*
X362261Y1003983D03*
Y1010391D03*
X364112Y1000778D03*
Y1007187D03*
Y1013595D03*
X365961Y1003983D03*
Y1010391D03*
X367812Y1000778D03*
Y1007187D03*
Y1013595D03*
X369661Y1003983D03*
Y1010391D03*
X356712Y1020004D03*
X358561Y1016800D03*
Y1023208D03*
X360412Y1020004D03*
X362261Y1016800D03*
Y1023208D03*
X364112Y1020004D03*
X365961Y1016800D03*
Y1023208D03*
X367812Y1020004D03*
X369661Y1016800D03*
Y1023208D03*
X356712Y1026413D03*
X358561Y1029617D03*
X360412Y1026413D03*
X362261Y1029617D03*
X364112Y1026413D03*
X365961Y1029617D03*
X367812Y1026413D03*
X369661Y1029617D03*
X356712Y1032821D03*
Y1039230D03*
Y1045639D03*
X358561Y1036026D03*
Y1042434D03*
X360412Y1032821D03*
Y1039230D03*
Y1045639D03*
X362261Y1036026D03*
Y1042434D03*
X364112Y1032821D03*
Y1039230D03*
Y1045639D03*
X365961Y1036026D03*
Y1042434D03*
X367812Y1032821D03*
Y1039230D03*
Y1045639D03*
X369661Y1036026D03*
Y1042434D03*
X356712Y1052047D03*
X358561Y1048842D03*
X360412Y1052047D03*
X362261Y1048842D03*
X364112Y1052047D03*
X365961Y1048842D03*
X367812Y1052047D03*
X369661Y1048842D03*
X356712Y1058455D03*
X358561Y1055251D03*
Y1061660D03*
X360412Y1058455D03*
X362261Y1055251D03*
Y1061660D03*
X364112Y1058455D03*
X365961Y1055251D03*
Y1061660D03*
X367812Y1058455D03*
X369661Y1055251D03*
Y1061660D03*
X356712Y1064864D03*
Y1071273D03*
Y1077681D03*
X358561Y1068068D03*
Y1074477D03*
X360412Y1064864D03*
Y1071273D03*
Y1077681D03*
X362261Y1068068D03*
Y1074477D03*
X364112Y1064864D03*
Y1071273D03*
Y1077681D03*
X365961Y1068068D03*
Y1074477D03*
X367812Y1064864D03*
Y1071273D03*
Y1077681D03*
X369661Y1068068D03*
Y1074477D03*
X358561Y1080885D03*
X362261D03*
X365961D03*
X369661D03*
X356712Y1084090D03*
Y1090498D03*
X358561Y1087294D03*
Y1093703D03*
X360412Y1084090D03*
Y1090498D03*
X362261Y1087294D03*
Y1093703D03*
X364112Y1084090D03*
Y1090498D03*
X365961Y1087294D03*
Y1093703D03*
X367812Y1084090D03*
Y1090498D03*
X369661Y1087294D03*
Y1093703D03*
X356712Y1096907D03*
Y1103316D03*
Y1109724D03*
X358561Y1100111D03*
Y1106520D03*
Y1112929D03*
X360412Y1096907D03*
Y1103316D03*
Y1109724D03*
X362261Y1100111D03*
Y1106520D03*
Y1112929D03*
X364112Y1096907D03*
Y1103316D03*
Y1109724D03*
X365961Y1100111D03*
Y1106520D03*
Y1112929D03*
X367812Y1096907D03*
Y1103316D03*
Y1109724D03*
X369661Y1100111D03*
Y1106520D03*
Y1112929D03*
X356712Y1116133D03*
Y1122541D03*
Y1128950D03*
X358561Y1119337D03*
Y1125746D03*
X360412Y1116133D03*
Y1122541D03*
Y1128950D03*
X362261Y1119337D03*
Y1125746D03*
X364112Y1116133D03*
Y1122541D03*
Y1128950D03*
X365961Y1119337D03*
Y1125746D03*
X367812Y1116133D03*
Y1122541D03*
Y1128950D03*
X369661Y1119337D03*
Y1125746D03*
X358561Y1132154D03*
X360412Y1135359D03*
X362261Y1132154D03*
X364112Y1135359D03*
X365961Y1132154D03*
X367812Y1135359D03*
X369661Y1132154D03*
X376628Y847081D03*
X378479Y850286D03*
X380328Y847081D03*
X382179Y850286D03*
X384028Y847081D03*
X385879Y850286D03*
X387728Y847081D03*
X372928D03*
X374779Y850286D03*
X376628Y853490D03*
Y859899D03*
Y866307D03*
X378479Y856694D03*
Y863103D03*
X380328Y853490D03*
Y859899D03*
Y866307D03*
X382179Y856694D03*
Y863103D03*
X384028Y853490D03*
Y859899D03*
Y866307D03*
X385879Y856694D03*
Y863103D03*
X387728Y853490D03*
Y859899D03*
Y866307D03*
X372928Y853490D03*
Y859899D03*
Y866307D03*
X374779Y856694D03*
Y863103D03*
X376628Y872716D03*
X378479Y869511D03*
X380328Y872716D03*
X382179Y869511D03*
X384028Y872716D03*
X385879Y869511D03*
X387728Y872716D03*
X372928D03*
X374779Y869511D03*
X376628Y879124D03*
X378479Y875920D03*
Y882329D03*
X380328Y879124D03*
X382179Y875920D03*
Y882329D03*
X384028Y879124D03*
X385879Y875920D03*
Y882329D03*
X387728Y879124D03*
X372928D03*
X374779Y875920D03*
Y882329D03*
X376628Y885533D03*
Y891942D03*
Y898350D03*
X378479Y888737D03*
Y895146D03*
Y901555D03*
X380328Y885533D03*
Y891942D03*
Y898350D03*
X382179Y888737D03*
Y895146D03*
Y901555D03*
X384028Y885533D03*
Y891942D03*
Y898350D03*
X385879Y888737D03*
Y895146D03*
Y901555D03*
X387728Y885533D03*
Y891942D03*
Y898350D03*
X372928Y885533D03*
Y891942D03*
Y898350D03*
X374779Y888737D03*
Y895146D03*
Y901555D03*
X376628Y904759D03*
Y911167D03*
Y917576D03*
X378479Y907963D03*
Y914372D03*
X380328Y904759D03*
Y911167D03*
Y917576D03*
X382179Y907963D03*
Y914372D03*
X384028Y904759D03*
Y911167D03*
Y917576D03*
X385879Y907963D03*
Y914372D03*
X387728Y904759D03*
Y911167D03*
Y917576D03*
X372928Y904759D03*
Y911167D03*
Y917576D03*
X374779Y907963D03*
Y914372D03*
X376628Y923985D03*
Y930393D03*
X378479Y920780D03*
Y927189D03*
X380328Y923985D03*
Y930393D03*
X382179Y920780D03*
Y927189D03*
X384028Y923985D03*
Y930393D03*
X385879Y920780D03*
Y927189D03*
X387728Y923985D03*
Y930393D03*
X372928Y923985D03*
Y930393D03*
X374779Y920780D03*
Y927189D03*
X378479Y933598D03*
X382179D03*
X385879D03*
X374779D03*
X376628Y936801D03*
Y943210D03*
Y949619D03*
X378479Y940006D03*
Y946414D03*
X380328Y936801D03*
Y943210D03*
Y949619D03*
X382179Y940006D03*
Y946414D03*
X384028Y936801D03*
Y943210D03*
Y949619D03*
X385879Y940006D03*
Y946414D03*
X387728Y936801D03*
Y943210D03*
Y949619D03*
X372928Y936801D03*
Y943210D03*
Y949619D03*
X374779Y940006D03*
Y946414D03*
X376628Y956027D03*
Y962436D03*
X378479Y952823D03*
Y959232D03*
X380328Y956027D03*
Y962436D03*
X382179Y952823D03*
Y959232D03*
X384028Y956027D03*
Y962436D03*
X385879Y952823D03*
Y959232D03*
X387728Y956027D03*
Y962436D03*
X372928Y956027D03*
Y962436D03*
X374779Y952823D03*
Y959232D03*
X378479Y965640D03*
X382179D03*
X385879D03*
X374779D03*
X376628Y968845D03*
Y975253D03*
Y981662D03*
X378479Y972049D03*
Y978457D03*
X380328Y968845D03*
Y975253D03*
Y981662D03*
X382179Y972049D03*
Y978457D03*
X384028Y968845D03*
Y975253D03*
Y981662D03*
X385879Y972049D03*
Y978457D03*
X387728Y968845D03*
Y975253D03*
Y981662D03*
X372928Y968845D03*
Y975253D03*
Y981662D03*
X374779Y972049D03*
Y978457D03*
X378479Y984866D03*
X382179D03*
X385879D03*
X374779D03*
X377061Y997574D03*
X380761D03*
X384461D03*
X373361D03*
X377061Y1003983D03*
Y1010391D03*
X378912Y1000778D03*
Y1007187D03*
Y1013595D03*
X380761Y1003983D03*
Y1010391D03*
X382612Y1000778D03*
Y1007187D03*
Y1013595D03*
X384461Y1003983D03*
Y1010391D03*
X386312Y1000778D03*
Y1007187D03*
Y1013595D03*
X371512Y1000778D03*
Y1007187D03*
Y1013595D03*
X373361Y1003983D03*
Y1010391D03*
X375212Y1000778D03*
Y1007187D03*
Y1013595D03*
X377061Y1016800D03*
X378912Y1020004D03*
X380761Y1016800D03*
X382612Y1020004D03*
X384461Y1016800D03*
X386312Y1020004D03*
X371512D03*
X373361Y1016800D03*
X375212Y1020004D03*
X377061Y1023208D03*
Y1029617D03*
X378912Y1026413D03*
X380761Y1023208D03*
Y1029617D03*
X382612Y1026413D03*
X384461Y1023208D03*
Y1029617D03*
X386312Y1026413D03*
X371512D03*
X373361Y1023208D03*
Y1029617D03*
X375212Y1026413D03*
X377061Y1036026D03*
Y1042434D03*
X378912Y1032821D03*
Y1039230D03*
Y1045639D03*
X380761Y1036026D03*
Y1042434D03*
X382612Y1032821D03*
Y1039230D03*
Y1045639D03*
X384461Y1036026D03*
Y1042434D03*
X386312Y1032821D03*
Y1039230D03*
Y1045639D03*
X371512Y1032821D03*
Y1039230D03*
Y1045639D03*
X373361Y1036026D03*
Y1042434D03*
X375212Y1032821D03*
Y1039230D03*
Y1045639D03*
X377061Y1048842D03*
X378912Y1052047D03*
X380761Y1048842D03*
X382612Y1052047D03*
X384461Y1048842D03*
X386312Y1052047D03*
X371512D03*
X373361Y1048842D03*
X375212Y1052047D03*
X377061Y1055251D03*
Y1061660D03*
X378912Y1058455D03*
X380761Y1055251D03*
Y1061660D03*
X382612Y1058455D03*
X384461Y1055251D03*
Y1061660D03*
X386312Y1058455D03*
X371512D03*
X373361Y1055251D03*
Y1061660D03*
X375212Y1058455D03*
X377061Y1068068D03*
Y1074477D03*
X378912Y1064864D03*
Y1071273D03*
Y1077681D03*
X380761Y1068068D03*
Y1074477D03*
X382612Y1064864D03*
Y1071273D03*
Y1077681D03*
X384461Y1068068D03*
Y1074477D03*
X386312Y1064864D03*
Y1071273D03*
Y1077681D03*
X371512Y1064864D03*
Y1071273D03*
Y1077681D03*
X373361Y1068068D03*
Y1074477D03*
X375212Y1064864D03*
Y1071273D03*
Y1077681D03*
X377061Y1080885D03*
X380761D03*
X384461D03*
X373361D03*
X377061Y1087294D03*
Y1093703D03*
X378912Y1084090D03*
Y1090498D03*
X380761Y1087294D03*
Y1093703D03*
X382612Y1084090D03*
Y1090498D03*
X384461Y1087294D03*
Y1093703D03*
X386312Y1084090D03*
Y1090498D03*
X371512Y1084090D03*
Y1090498D03*
X373361Y1087294D03*
Y1093703D03*
X375212Y1084090D03*
Y1090498D03*
X377061Y1100111D03*
Y1106520D03*
X378912Y1096907D03*
Y1103316D03*
Y1109724D03*
X380761Y1100111D03*
Y1106520D03*
X382612Y1096907D03*
Y1103316D03*
Y1109724D03*
X384461Y1100111D03*
Y1106520D03*
X386312Y1096907D03*
Y1103316D03*
Y1109724D03*
X371512Y1096907D03*
Y1103316D03*
Y1109724D03*
X373361Y1100111D03*
Y1106520D03*
X375212Y1096907D03*
Y1103316D03*
Y1109724D03*
X377061Y1112929D03*
X380761D03*
X384461D03*
X373361D03*
X377061Y1119337D03*
Y1125746D03*
X378912Y1116133D03*
Y1122541D03*
Y1128950D03*
X380761Y1119337D03*
Y1125746D03*
X382612Y1116133D03*
Y1122541D03*
Y1128950D03*
X384461Y1119337D03*
Y1125746D03*
X386312Y1116133D03*
Y1122541D03*
Y1128950D03*
X371512Y1116133D03*
Y1122541D03*
Y1128950D03*
X373361Y1119337D03*
Y1125746D03*
X375212Y1116133D03*
Y1122541D03*
Y1128950D03*
X377061Y1132154D03*
X378912Y1135359D03*
X380761Y1132154D03*
X382612Y1135359D03*
X384461Y1132154D03*
X386312Y1135359D03*
X371512D03*
X373361Y1132154D03*
X375212Y1135359D03*
X389579Y850286D03*
X391428Y847081D03*
X393279Y850286D03*
X395128Y847081D03*
X396979Y850286D03*
X398828Y847081D03*
X400679Y850286D03*
X402528Y847081D03*
X389579Y856694D03*
Y863103D03*
X391428Y853490D03*
Y859899D03*
Y866307D03*
X393279Y856694D03*
Y863103D03*
X395128Y853490D03*
Y859899D03*
Y866307D03*
X396979Y856694D03*
Y863103D03*
X398828Y853490D03*
Y859899D03*
Y866307D03*
X400679Y856694D03*
Y863103D03*
X402528Y853490D03*
Y859899D03*
Y866307D03*
X389579Y869511D03*
X391428Y872716D03*
X393279Y869511D03*
X395128Y872716D03*
X396979Y869511D03*
X398828Y872716D03*
X400679Y869511D03*
X402528Y872716D03*
X389579Y875920D03*
Y882329D03*
X391428Y879124D03*
X393279Y875920D03*
Y882329D03*
X395128Y879124D03*
X396979Y875920D03*
Y882329D03*
X398828Y879124D03*
X400679Y875920D03*
Y882329D03*
X402528Y879124D03*
X389579Y888737D03*
Y895146D03*
Y901555D03*
X391428Y885533D03*
Y891942D03*
Y898350D03*
X393279Y888737D03*
Y895146D03*
Y901555D03*
X395128Y885533D03*
Y891942D03*
Y898350D03*
X396979Y888737D03*
Y895146D03*
Y901555D03*
X398828Y885533D03*
Y891942D03*
Y898350D03*
X400679Y888737D03*
Y895146D03*
Y901555D03*
X402528Y885533D03*
Y891942D03*
Y898350D03*
X389579Y907963D03*
Y914372D03*
X391428Y904759D03*
Y911167D03*
Y917576D03*
X393279Y907963D03*
Y914372D03*
X395128Y904759D03*
Y911167D03*
Y917576D03*
X396979Y907963D03*
Y914372D03*
X398828Y904759D03*
Y911167D03*
Y917576D03*
X400679Y907963D03*
Y914372D03*
X402528Y904759D03*
Y911167D03*
Y917576D03*
X389579Y920780D03*
Y927189D03*
X391428Y923985D03*
Y930393D03*
X393279Y920780D03*
Y927189D03*
X395128Y923985D03*
Y930393D03*
X396979Y920780D03*
Y927189D03*
X398828Y923985D03*
Y930393D03*
X400679Y920780D03*
Y927189D03*
X402528Y923985D03*
Y930393D03*
X389579Y933598D03*
X393279D03*
X396979D03*
X400679D03*
X389579Y940006D03*
Y946414D03*
X391428Y936801D03*
Y943210D03*
Y949619D03*
X393279Y940006D03*
Y946414D03*
X395128Y936801D03*
Y943210D03*
Y949619D03*
X396979Y940006D03*
Y946414D03*
X398828Y936801D03*
Y943210D03*
Y949619D03*
X400679Y940006D03*
Y946414D03*
X402528Y936801D03*
Y943210D03*
Y949619D03*
X389579Y952823D03*
Y959232D03*
X391428Y956027D03*
Y962436D03*
X393279Y952823D03*
Y959232D03*
X395128Y956027D03*
Y962436D03*
X396979Y952823D03*
Y959232D03*
X398828Y956027D03*
Y962436D03*
X400679Y952823D03*
Y959232D03*
X402528Y956027D03*
Y962436D03*
X389579Y965640D03*
X393279D03*
X396979D03*
X400679D03*
X389579Y972049D03*
Y978457D03*
X391428Y968845D03*
Y975253D03*
Y981662D03*
X393279Y972049D03*
Y978457D03*
X395128Y968845D03*
Y975253D03*
Y981662D03*
X396979Y972049D03*
Y978457D03*
X398828Y968845D03*
Y975253D03*
Y981662D03*
X400679Y972049D03*
Y978457D03*
X402528Y968845D03*
Y975253D03*
Y981662D03*
X389579Y984866D03*
X393279D03*
X396979D03*
X400679D03*
X388161Y997574D03*
X391861D03*
X395561D03*
X399261D03*
X402961D03*
X388161Y1003983D03*
Y1010391D03*
X390012Y1000778D03*
Y1007187D03*
Y1013595D03*
X391861Y1003983D03*
Y1010391D03*
X393712Y1000778D03*
Y1007187D03*
Y1013595D03*
X395561Y1003983D03*
Y1010391D03*
X397412Y1000778D03*
Y1007187D03*
Y1013595D03*
X399261Y1003983D03*
Y1010391D03*
X401112Y1000778D03*
Y1007187D03*
Y1013595D03*
X402961Y1003983D03*
Y1010391D03*
X388161Y1016800D03*
X390012Y1020004D03*
X391861Y1016800D03*
X393712Y1020004D03*
X395561Y1016800D03*
X397412Y1020004D03*
X399261Y1016800D03*
X401112Y1020004D03*
X402961Y1016800D03*
X388161Y1023208D03*
Y1029617D03*
X390012Y1026413D03*
X391861Y1023208D03*
Y1029617D03*
X393712Y1026413D03*
X395561Y1023208D03*
Y1029617D03*
X397412Y1026413D03*
X399261Y1023208D03*
Y1029617D03*
X401112Y1026413D03*
X402961Y1023208D03*
Y1029617D03*
X388161Y1036026D03*
Y1042434D03*
X390012Y1032821D03*
Y1039230D03*
Y1045639D03*
X391861Y1036026D03*
Y1042434D03*
X393712Y1032821D03*
Y1039230D03*
Y1045639D03*
X395561Y1036026D03*
Y1042434D03*
X397412Y1032821D03*
Y1039230D03*
Y1045639D03*
X399261Y1036026D03*
Y1042434D03*
X401112Y1032821D03*
Y1039230D03*
Y1045639D03*
X402961Y1036026D03*
Y1042434D03*
X388161Y1048842D03*
X390012Y1052047D03*
X391861Y1048842D03*
X393712Y1052047D03*
X395561Y1048842D03*
X397412Y1052047D03*
X399261Y1048842D03*
X401112Y1052047D03*
X402961Y1048842D03*
X388161Y1055251D03*
Y1061660D03*
X390012Y1058455D03*
X391861Y1055251D03*
Y1061660D03*
X393712Y1058455D03*
X395561Y1055251D03*
Y1061660D03*
X397412Y1058455D03*
X399261Y1055251D03*
Y1061660D03*
X401112Y1058455D03*
X402961Y1055251D03*
Y1061660D03*
X388161Y1068068D03*
Y1074477D03*
X390012Y1064864D03*
Y1071273D03*
Y1077681D03*
X391861Y1068068D03*
Y1074477D03*
X393712Y1064864D03*
Y1071273D03*
Y1077681D03*
X395561Y1068068D03*
Y1074477D03*
X397412Y1064864D03*
Y1071273D03*
Y1077681D03*
X399261Y1068068D03*
Y1074477D03*
X401112Y1064864D03*
Y1071273D03*
Y1077681D03*
X402961Y1068068D03*
Y1074477D03*
X388161Y1080885D03*
X391861D03*
X395561D03*
X399261D03*
X402961D03*
X388161Y1087294D03*
Y1093703D03*
X390012Y1084090D03*
Y1090498D03*
X391861Y1087294D03*
Y1093703D03*
X393712Y1084090D03*
Y1090498D03*
X395561Y1087294D03*
Y1093703D03*
X397412Y1084090D03*
Y1090498D03*
X399261Y1087294D03*
Y1093703D03*
X401112Y1084090D03*
Y1090498D03*
X402961Y1087294D03*
Y1093703D03*
X388161Y1100111D03*
Y1106520D03*
X390012Y1096907D03*
Y1103316D03*
Y1109724D03*
X391861Y1100111D03*
Y1106520D03*
X393712Y1096907D03*
Y1103316D03*
Y1109724D03*
X395561Y1100111D03*
Y1106520D03*
X397412Y1096907D03*
Y1103316D03*
Y1109724D03*
X399261Y1100111D03*
Y1106520D03*
X401112Y1096907D03*
Y1103316D03*
Y1109724D03*
X402961Y1100111D03*
Y1106520D03*
X388161Y1112929D03*
X391861D03*
X395561D03*
X399261D03*
X402961D03*
X388161Y1119337D03*
Y1125746D03*
X390012Y1116133D03*
Y1122541D03*
Y1128950D03*
X391861Y1119337D03*
Y1125746D03*
X393712Y1116133D03*
Y1122541D03*
Y1128950D03*
X395561Y1119337D03*
Y1125746D03*
X397412Y1116133D03*
Y1122541D03*
Y1128950D03*
X399261Y1119337D03*
Y1125746D03*
X401112Y1116133D03*
Y1122541D03*
Y1128950D03*
X402961Y1119337D03*
Y1125746D03*
X388161Y1132154D03*
X390012Y1135359D03*
X391861Y1132154D03*
X393712Y1135359D03*
X395561Y1132154D03*
X397412Y1135359D03*
X399261Y1132154D03*
X401112Y1135359D03*
X402961Y1132154D03*
X406228Y847081D03*
X408079Y850286D03*
X409928Y847081D03*
X411779Y850286D03*
X413628Y847081D03*
X415479Y850286D03*
X417328Y847081D03*
X419179Y850286D03*
X404379D03*
X406228Y853490D03*
Y859899D03*
Y866307D03*
X408079Y856694D03*
Y863103D03*
X409928Y853490D03*
Y859899D03*
Y866307D03*
X411779Y856694D03*
Y863103D03*
X413628Y853490D03*
Y859899D03*
Y866307D03*
X415479Y856694D03*
Y863103D03*
X417328Y853490D03*
Y859899D03*
Y866307D03*
X419179Y856694D03*
Y863103D03*
X404379Y856694D03*
Y863103D03*
X406228Y872716D03*
X408079Y869511D03*
X409928Y872716D03*
X411779Y869511D03*
X413628Y872716D03*
X415479Y869511D03*
X417328Y872716D03*
X419179Y869511D03*
X404379D03*
X406228Y879124D03*
X408079Y875920D03*
Y882329D03*
X409928Y879124D03*
X411779Y875920D03*
Y882329D03*
X413628Y879124D03*
X415479Y875920D03*
Y882329D03*
X417328Y879124D03*
X419179Y875920D03*
Y882329D03*
X404379Y875920D03*
Y882329D03*
X406228Y885533D03*
Y891942D03*
Y898350D03*
X408079Y888737D03*
Y895146D03*
Y901555D03*
X409928Y885533D03*
Y891942D03*
Y898350D03*
X411779Y888737D03*
Y895146D03*
Y901555D03*
X413628Y885533D03*
Y891942D03*
Y898350D03*
X415479Y888737D03*
Y895146D03*
Y901555D03*
X417328Y885533D03*
Y891942D03*
Y898350D03*
X419179Y888737D03*
Y895146D03*
Y901555D03*
X404379Y888737D03*
Y895146D03*
Y901555D03*
X406228Y904759D03*
Y911167D03*
Y917576D03*
X408079Y907963D03*
Y914372D03*
X409928Y904759D03*
Y911167D03*
Y917576D03*
X411779Y907963D03*
Y914372D03*
X413628Y904759D03*
Y911167D03*
Y917576D03*
X415479Y907963D03*
Y914372D03*
X417328Y904759D03*
Y911167D03*
Y917576D03*
X419179Y907963D03*
Y914372D03*
X404379Y907963D03*
Y914372D03*
X406228Y923985D03*
X408079Y920780D03*
X409928Y923985D03*
X411779Y920780D03*
X413628Y923985D03*
X415479Y920780D03*
X417328Y923985D03*
X419179Y920780D03*
X404379D03*
X406661Y1042434D03*
X408512Y1039230D03*
Y1045639D03*
X410361Y1042434D03*
X412212Y1039230D03*
Y1045639D03*
X414061Y1042434D03*
X415912Y1039230D03*
Y1045639D03*
X417761Y1042434D03*
X419612Y1039230D03*
Y1045639D03*
X404812Y1039230D03*
Y1045639D03*
X406661Y1048842D03*
X408512Y1052047D03*
X410361Y1048842D03*
X412212Y1052047D03*
X414061Y1048842D03*
X415912Y1052047D03*
X417761Y1048842D03*
X419612Y1052047D03*
X404812D03*
X406661Y1055251D03*
Y1061660D03*
X408512Y1058455D03*
X410361Y1055251D03*
Y1061660D03*
X412212Y1058455D03*
X414061Y1055251D03*
Y1061660D03*
X415912Y1058455D03*
X417761Y1055251D03*
Y1061660D03*
X419612Y1058455D03*
X404812D03*
X406661Y1068068D03*
Y1074477D03*
X408512Y1064864D03*
Y1071273D03*
Y1077681D03*
X410361Y1068068D03*
Y1074477D03*
X412212Y1064864D03*
Y1071273D03*
Y1077681D03*
X414061Y1068068D03*
Y1074477D03*
X415912Y1064864D03*
Y1071273D03*
Y1077681D03*
X417761Y1068068D03*
Y1074477D03*
X419612Y1064864D03*
Y1071273D03*
Y1077681D03*
X404812Y1064864D03*
Y1071273D03*
Y1077681D03*
X406661Y1080885D03*
X410361D03*
X414061D03*
X417761D03*
X406661Y1087294D03*
Y1093703D03*
X408512Y1084090D03*
Y1090498D03*
X410361Y1087294D03*
Y1093703D03*
X412212Y1084090D03*
Y1090498D03*
X414061Y1087294D03*
Y1093703D03*
X415912Y1084090D03*
Y1090498D03*
X417761Y1087294D03*
Y1093703D03*
X419612Y1084090D03*
Y1090498D03*
X404812Y1084090D03*
Y1090498D03*
X406661Y1100111D03*
Y1106520D03*
X408512Y1096907D03*
Y1103316D03*
Y1109724D03*
X410361Y1100111D03*
Y1106520D03*
X412212Y1096907D03*
Y1103316D03*
Y1109724D03*
X414061Y1100111D03*
Y1106520D03*
X415912Y1096907D03*
Y1103316D03*
Y1109724D03*
X417761Y1100111D03*
Y1106520D03*
X419612Y1096907D03*
Y1103316D03*
Y1109724D03*
X404812Y1096907D03*
Y1103316D03*
Y1109724D03*
X406661Y1112929D03*
X410361D03*
X414061D03*
X417761D03*
X406661Y1119337D03*
Y1125746D03*
X408512Y1116133D03*
Y1122541D03*
Y1128950D03*
X410361Y1119337D03*
Y1125746D03*
X412212Y1116133D03*
Y1122541D03*
Y1128950D03*
X414061Y1119337D03*
Y1125746D03*
X415912Y1116133D03*
Y1122541D03*
Y1128950D03*
X417761Y1119337D03*
Y1125746D03*
X419612Y1116133D03*
Y1122541D03*
Y1128950D03*
X404812Y1116133D03*
Y1122541D03*
Y1128950D03*
X406661Y1132154D03*
X408512Y1135359D03*
X410361Y1132154D03*
X412212Y1135359D03*
X414061Y1132154D03*
X415912Y1135359D03*
X417761Y1132154D03*
X419612Y1135359D03*
X404812D03*
X421028Y847081D03*
X422879Y850286D03*
X424728Y847081D03*
X426579Y850286D03*
X430279D03*
X433979D03*
X421028Y853490D03*
Y859899D03*
Y866307D03*
X422879Y856694D03*
Y863103D03*
X424728Y853490D03*
Y859899D03*
Y866307D03*
X426579Y856694D03*
Y863103D03*
X428428Y853490D03*
Y859899D03*
Y866307D03*
X430279Y856694D03*
Y863103D03*
X432128Y853490D03*
Y859899D03*
Y866307D03*
X433979Y856694D03*
Y863103D03*
X435829Y853490D03*
Y859899D03*
Y866307D03*
X421028Y872716D03*
X422879Y869511D03*
X424728Y872716D03*
X426579Y869511D03*
X428428Y872716D03*
X430279Y869511D03*
X432128Y872716D03*
X433979Y869511D03*
X435829Y872716D03*
X421028Y879124D03*
X422879Y875920D03*
Y882329D03*
X424728Y879124D03*
X426579Y875920D03*
Y882329D03*
X428428Y879124D03*
X430279Y875920D03*
Y882329D03*
X432128Y879124D03*
X433979Y875920D03*
Y882329D03*
X435829Y879124D03*
X421028Y885533D03*
Y891942D03*
Y898350D03*
X422879Y888737D03*
Y895146D03*
Y901555D03*
X424728Y885533D03*
Y891942D03*
Y898350D03*
X426579Y888737D03*
Y895146D03*
Y901555D03*
X428428Y885533D03*
Y891942D03*
Y898350D03*
X430279Y888737D03*
Y895146D03*
Y901555D03*
X432128Y885533D03*
Y891942D03*
Y898350D03*
X433979Y888737D03*
Y895146D03*
Y901555D03*
X435829Y885533D03*
Y891942D03*
Y898350D03*
Y904759D03*
X421028D03*
Y911167D03*
Y917576D03*
X422879Y907963D03*
Y914372D03*
X424728Y904759D03*
Y911167D03*
Y917576D03*
X426579Y907963D03*
Y914372D03*
X428428Y904759D03*
Y911167D03*
Y917576D03*
X430279Y907963D03*
Y914372D03*
X432128Y904759D03*
Y911167D03*
Y917576D03*
X433979Y907963D03*
Y914372D03*
X435829Y911167D03*
Y917576D03*
X421028Y923985D03*
X422879Y920780D03*
X424728Y923985D03*
X426579Y920780D03*
X428428Y923985D03*
X430279Y920780D03*
Y927189D03*
X432128Y923985D03*
Y930393D03*
X433979Y920780D03*
Y927189D03*
X435829Y923985D03*
Y930393D03*
X430279Y933598D03*
X433979D03*
X430279Y940006D03*
Y946414D03*
X432128Y936801D03*
Y943210D03*
Y949619D03*
X433979Y940006D03*
Y946414D03*
X435829Y936801D03*
Y943210D03*
Y949619D03*
X430279Y952823D03*
Y959232D03*
X432128Y956027D03*
Y962436D03*
X433979Y952823D03*
Y959232D03*
X435829Y956027D03*
Y962436D03*
X430279Y965640D03*
X433979D03*
X430279Y972049D03*
Y978457D03*
X432128Y968845D03*
Y975253D03*
Y981662D03*
X433979Y972049D03*
Y978457D03*
X435829Y968845D03*
Y975253D03*
Y981662D03*
X430279Y984866D03*
X433979D03*
X436261Y997574D03*
X432561D03*
X436261Y1003983D03*
Y1010391D03*
X430711Y1000778D03*
Y1007187D03*
Y1013595D03*
X432561Y1003983D03*
Y1010391D03*
X434412Y1000778D03*
Y1007187D03*
Y1013595D03*
X436261Y1016800D03*
X430711Y1020004D03*
X432561Y1016800D03*
X434412Y1020004D03*
X436261Y1023208D03*
Y1029617D03*
X430711Y1026413D03*
X432561Y1023208D03*
Y1029617D03*
X434412Y1026413D03*
X436261Y1036026D03*
Y1042434D03*
X421461D03*
X423312Y1039230D03*
Y1045639D03*
X425161Y1042434D03*
X427012Y1039230D03*
Y1045639D03*
X428861Y1042434D03*
X430711Y1032821D03*
Y1039230D03*
Y1045639D03*
X432561Y1036026D03*
Y1042434D03*
X434412Y1032821D03*
Y1039230D03*
Y1045639D03*
X436261Y1048842D03*
X421461D03*
X423312Y1052047D03*
X425161Y1048842D03*
X427012Y1052047D03*
X428861Y1048842D03*
X430711Y1052047D03*
X432561Y1048842D03*
X434412Y1052047D03*
X436261Y1055251D03*
Y1061660D03*
X421461Y1055251D03*
Y1061660D03*
X423312Y1058455D03*
X425161Y1055251D03*
Y1061660D03*
X427012Y1058455D03*
X428861Y1055251D03*
Y1061660D03*
X430711Y1058455D03*
X432561Y1055251D03*
Y1061660D03*
X434412Y1058455D03*
X436261Y1068068D03*
Y1074477D03*
X421461Y1068068D03*
Y1074477D03*
X423312Y1064864D03*
Y1071273D03*
Y1077681D03*
X425161Y1068068D03*
Y1074477D03*
X427012Y1064864D03*
Y1071273D03*
Y1077681D03*
X428861Y1068068D03*
Y1074477D03*
X430711Y1064864D03*
Y1071273D03*
Y1077681D03*
X432561Y1068068D03*
Y1074477D03*
X434412Y1064864D03*
Y1071273D03*
Y1077681D03*
X436261Y1080885D03*
X421461D03*
X425161D03*
X428861D03*
X432561D03*
X436261Y1087294D03*
Y1093703D03*
X421461Y1087294D03*
Y1093703D03*
X423312Y1084090D03*
Y1090498D03*
X425161Y1087294D03*
Y1093703D03*
X427012Y1084090D03*
Y1090498D03*
X428861Y1087294D03*
Y1093703D03*
X430711Y1084090D03*
Y1090498D03*
X432561Y1087294D03*
Y1093703D03*
X434412Y1084090D03*
Y1090498D03*
X436261Y1100111D03*
Y1106520D03*
X421461Y1100111D03*
Y1106520D03*
X423312Y1096907D03*
Y1103316D03*
Y1109724D03*
X425161Y1100111D03*
Y1106520D03*
X427012Y1096907D03*
Y1103316D03*
Y1109724D03*
X428861Y1100111D03*
Y1106520D03*
X430711Y1096907D03*
Y1103316D03*
Y1109724D03*
X432561Y1100111D03*
Y1106520D03*
X434412Y1096907D03*
Y1103316D03*
Y1109724D03*
X436261Y1112929D03*
X421461D03*
X425161D03*
X428861D03*
X432561D03*
X436261Y1119337D03*
Y1125746D03*
X421461Y1119337D03*
Y1125746D03*
X423312Y1116133D03*
Y1122541D03*
Y1128950D03*
X425161Y1119337D03*
Y1125746D03*
X427012Y1116133D03*
Y1122541D03*
Y1128950D03*
X428861Y1119337D03*
Y1125746D03*
X430711Y1116133D03*
Y1122541D03*
Y1128950D03*
X432561Y1119337D03*
Y1125746D03*
X434412Y1116133D03*
Y1122541D03*
Y1128950D03*
X436261Y1132154D03*
X421461D03*
X423312Y1135359D03*
X425161Y1132154D03*
X427012Y1135359D03*
X428861Y1132154D03*
X432561D03*
X437679Y850286D03*
X441379D03*
X445079D03*
X448779D03*
X452479D03*
X437679Y856694D03*
Y863103D03*
X439528Y853490D03*
Y859899D03*
Y866307D03*
X441379Y856694D03*
Y863103D03*
X443228Y853490D03*
Y859899D03*
Y866307D03*
X445079Y856694D03*
Y863103D03*
X446928Y853490D03*
Y859899D03*
Y866307D03*
X448779Y856694D03*
Y863103D03*
X450629Y853490D03*
Y859899D03*
Y866307D03*
X452479Y856694D03*
Y863103D03*
X437679Y869511D03*
X439528Y872716D03*
X441379Y869511D03*
X443228Y872716D03*
X445079Y869511D03*
X446928Y872716D03*
X448779Y869511D03*
X450629Y872716D03*
X452479Y869511D03*
X437679Y875920D03*
Y882329D03*
X439528Y879124D03*
X441379Y875920D03*
Y882329D03*
X443228Y879124D03*
X445079Y875920D03*
Y882329D03*
X446928Y879124D03*
X448779Y875920D03*
Y882329D03*
X450629Y879124D03*
X452479Y875920D03*
Y882329D03*
X437679Y888737D03*
Y895146D03*
Y901555D03*
X439528Y885533D03*
Y891942D03*
Y898350D03*
X441379Y888737D03*
Y895146D03*
Y901555D03*
X443228Y885533D03*
Y891942D03*
Y898350D03*
X445079Y888737D03*
Y895146D03*
Y901555D03*
X446928Y885533D03*
Y891942D03*
Y898350D03*
X448779Y888737D03*
Y895146D03*
Y901555D03*
X450629Y885533D03*
Y891942D03*
Y898350D03*
X452479Y888737D03*
Y895146D03*
Y901555D03*
X437679Y907963D03*
Y914372D03*
X439528Y904759D03*
Y911167D03*
Y917576D03*
X441379Y907963D03*
Y914372D03*
X443228Y904759D03*
Y911167D03*
Y917576D03*
X445079Y907963D03*
Y914372D03*
X446928Y904759D03*
Y911167D03*
Y917576D03*
X448779Y907963D03*
Y914372D03*
X450629Y904759D03*
Y911167D03*
Y917576D03*
X452479Y907963D03*
Y914372D03*
X437679Y920780D03*
Y927189D03*
X439528Y923985D03*
Y930393D03*
X441379Y920780D03*
Y927189D03*
X443228Y923985D03*
Y930393D03*
X445079Y920780D03*
Y927189D03*
X446928Y923985D03*
Y930393D03*
X448779Y920780D03*
Y927189D03*
X450629Y923985D03*
Y930393D03*
X452479Y920780D03*
X437679Y933598D03*
X441379D03*
X445079D03*
X448779D03*
X437679Y940006D03*
Y946414D03*
X439528Y936801D03*
Y943210D03*
Y949619D03*
X441379Y940006D03*
Y946414D03*
X443228Y936801D03*
Y943210D03*
Y949619D03*
X445079Y940006D03*
Y946414D03*
X446928Y936801D03*
Y943210D03*
Y949619D03*
X448779Y940006D03*
Y946414D03*
X450629Y936801D03*
Y943210D03*
Y949619D03*
X437679Y952823D03*
Y959232D03*
X439528Y956027D03*
Y962436D03*
X441379Y952823D03*
Y959232D03*
X443228Y956027D03*
Y962436D03*
X445079Y952823D03*
Y959232D03*
X446928Y956027D03*
Y962436D03*
X448779Y952823D03*
Y959232D03*
X450629Y956027D03*
Y962436D03*
X437679Y965640D03*
X441379D03*
X445079D03*
X448779D03*
X437679Y972049D03*
Y978457D03*
X439528Y968845D03*
Y975253D03*
Y981662D03*
X441379Y972049D03*
Y978457D03*
X443228Y968845D03*
Y975253D03*
Y981662D03*
X445079Y972049D03*
Y978457D03*
X446928Y968845D03*
Y975253D03*
Y981662D03*
X448779Y972049D03*
Y978457D03*
X450629Y968845D03*
Y975253D03*
Y981662D03*
X437679Y984866D03*
X441379D03*
X445079D03*
X448779D03*
X439961Y997574D03*
X443661D03*
X447361D03*
X451061D03*
X438112Y1000778D03*
Y1007187D03*
Y1013595D03*
X439961Y1003983D03*
Y1010391D03*
X441812Y1000778D03*
Y1007187D03*
Y1013595D03*
X443661Y1003983D03*
Y1010391D03*
X445511Y1000778D03*
Y1007187D03*
Y1013595D03*
X447361Y1003983D03*
Y1010391D03*
X449212Y1000778D03*
Y1007187D03*
Y1013595D03*
X451061Y1003983D03*
Y1010391D03*
X438112Y1020004D03*
X439961Y1016800D03*
X441812Y1020004D03*
X443661Y1016800D03*
X445511Y1020004D03*
X447361Y1016800D03*
X449212Y1020004D03*
X451061Y1016800D03*
X438112Y1026413D03*
X439961Y1023208D03*
Y1029617D03*
X441812Y1026413D03*
X443661Y1023208D03*
Y1029617D03*
X445511Y1026413D03*
X447361Y1023208D03*
Y1029617D03*
X449212Y1026413D03*
X451061Y1023208D03*
Y1029617D03*
X438112Y1032821D03*
Y1039230D03*
Y1045639D03*
X439961Y1036026D03*
Y1042434D03*
X441812Y1032821D03*
Y1039230D03*
Y1045639D03*
X443661Y1036026D03*
Y1042434D03*
X445511Y1032821D03*
Y1039230D03*
Y1045639D03*
X447361Y1036026D03*
Y1042434D03*
X449212Y1032821D03*
Y1039230D03*
Y1045639D03*
X451061Y1036026D03*
Y1042434D03*
X438112Y1052047D03*
X439961Y1048842D03*
X441812Y1052047D03*
X443661Y1048842D03*
X445511Y1052047D03*
X447361Y1048842D03*
X449212Y1052047D03*
X451061Y1048842D03*
X438112Y1058455D03*
X439961Y1055251D03*
Y1061660D03*
X441812Y1058455D03*
X443661Y1055251D03*
Y1061660D03*
X445511Y1058455D03*
X447361Y1055251D03*
Y1061660D03*
X449212Y1058455D03*
X451061Y1055251D03*
Y1061660D03*
X438112Y1064864D03*
Y1071273D03*
Y1077681D03*
X439961Y1068068D03*
Y1074477D03*
X441812Y1064864D03*
Y1071273D03*
Y1077681D03*
X443661Y1068068D03*
Y1074477D03*
X445511Y1064864D03*
Y1071273D03*
Y1077681D03*
X447361Y1068068D03*
Y1074477D03*
X449212Y1064864D03*
Y1071273D03*
Y1077681D03*
X451061Y1068068D03*
Y1074477D03*
X439961Y1080885D03*
X443661D03*
X447361D03*
X451061D03*
X438112Y1084090D03*
Y1090498D03*
X439961Y1087294D03*
Y1093703D03*
X441812Y1084090D03*
Y1090498D03*
X443661Y1087294D03*
Y1093703D03*
X445511Y1084090D03*
Y1090498D03*
X447361Y1087294D03*
Y1093703D03*
X449212Y1084090D03*
Y1090498D03*
X451061Y1087294D03*
Y1093703D03*
X438112Y1096907D03*
Y1103316D03*
Y1109724D03*
X439961Y1100111D03*
Y1106520D03*
X441812Y1096907D03*
Y1103316D03*
Y1109724D03*
X443661Y1100111D03*
Y1106520D03*
X445511Y1096907D03*
Y1103316D03*
Y1109724D03*
X447361Y1100111D03*
Y1106520D03*
X449212Y1096907D03*
Y1103316D03*
Y1109724D03*
X451061Y1100111D03*
Y1106520D03*
X439961Y1112929D03*
X443661D03*
X447361D03*
X451061D03*
X438112Y1116133D03*
Y1122541D03*
Y1128950D03*
X439961Y1119337D03*
Y1125746D03*
X441812Y1116133D03*
Y1122541D03*
Y1128950D03*
X443661Y1119337D03*
Y1125746D03*
X445511Y1116133D03*
Y1122541D03*
Y1128950D03*
X447361Y1119337D03*
Y1125746D03*
X449212Y1116133D03*
Y1122541D03*
Y1128950D03*
X451061Y1119337D03*
Y1125746D03*
X439961Y1132154D03*
X443661D03*
X447361D03*
X451061D03*
X467279Y850286D03*
X454328Y847081D03*
X456179Y850286D03*
X458028Y847081D03*
X459879Y850286D03*
X461728Y847081D03*
X463579Y850286D03*
X465428Y847081D03*
X467279Y856694D03*
Y863103D03*
X454328Y853490D03*
Y859899D03*
Y866307D03*
X456179Y856694D03*
Y863103D03*
X458028Y853490D03*
Y859899D03*
Y866307D03*
X459879Y856694D03*
Y863103D03*
X461728Y853490D03*
Y859899D03*
Y866307D03*
X463579Y856694D03*
Y863103D03*
X465428Y853490D03*
Y859899D03*
Y866307D03*
X467279Y869511D03*
X454328Y872716D03*
X456179Y869511D03*
X458028Y872716D03*
X459879Y869511D03*
X461728Y872716D03*
X463579Y869511D03*
X465428Y872716D03*
X467279Y875920D03*
Y882329D03*
X454328Y879124D03*
X456179Y875920D03*
Y882329D03*
X458028Y879124D03*
X459879Y875920D03*
Y882329D03*
X461728Y879124D03*
X463579Y875920D03*
Y882329D03*
X465428Y879124D03*
X467279Y888737D03*
Y895146D03*
Y901555D03*
X454328Y885533D03*
Y891942D03*
Y898350D03*
X456179Y888737D03*
Y895146D03*
Y901555D03*
X458028Y885533D03*
Y891942D03*
Y898350D03*
X459879Y888737D03*
Y895146D03*
Y901555D03*
X461728Y885533D03*
Y891942D03*
Y898350D03*
X463579Y888737D03*
Y895146D03*
Y901555D03*
X465428Y885533D03*
Y891942D03*
Y898350D03*
X467279Y907963D03*
Y914372D03*
X454328Y904759D03*
Y911167D03*
Y917576D03*
X456179Y907963D03*
Y914372D03*
X458028Y904759D03*
Y911167D03*
Y917576D03*
X459879Y907963D03*
Y914372D03*
X461728Y904759D03*
Y911167D03*
Y917576D03*
X463579Y907963D03*
Y914372D03*
X465428Y904759D03*
Y911167D03*
Y917576D03*
X467279Y920780D03*
X454328Y923985D03*
X456179Y920780D03*
X458028Y923985D03*
X459879Y920780D03*
X461728Y923985D03*
X463579Y920780D03*
X465428Y923985D03*
X467712Y1039230D03*
Y1045639D03*
X452912Y1039230D03*
Y1045639D03*
X454761Y1042434D03*
X456612Y1039230D03*
Y1045639D03*
X458461Y1042434D03*
X460312Y1039230D03*
Y1045639D03*
X462161Y1042434D03*
X464012Y1039230D03*
Y1045639D03*
X465861Y1042434D03*
X467712Y1052047D03*
X452912D03*
X454761Y1048842D03*
X456612Y1052047D03*
X458461Y1048842D03*
X460312Y1052047D03*
X462161Y1048842D03*
X464012Y1052047D03*
X465861Y1048842D03*
Y1055251D03*
X467712Y1058455D03*
X452912D03*
X454761Y1055251D03*
Y1061660D03*
X456612Y1058455D03*
X458461Y1055251D03*
Y1061660D03*
X460312Y1058455D03*
X462161Y1055251D03*
Y1061660D03*
X464012Y1058455D03*
X465861Y1061660D03*
X467712Y1064864D03*
Y1071273D03*
Y1077681D03*
X452912Y1064864D03*
Y1071273D03*
Y1077681D03*
X454761Y1068068D03*
Y1074477D03*
X456612Y1064864D03*
Y1071273D03*
Y1077681D03*
X458461Y1068068D03*
Y1074477D03*
X460312Y1064864D03*
Y1071273D03*
Y1077681D03*
X462161Y1068068D03*
Y1074477D03*
X464012Y1064864D03*
Y1071273D03*
Y1077681D03*
X465861Y1068068D03*
Y1074477D03*
X454761Y1080885D03*
X458461D03*
X462161D03*
X465861D03*
X467712Y1084090D03*
Y1090498D03*
X452912Y1084090D03*
Y1090498D03*
X454761Y1087294D03*
Y1093703D03*
X456612Y1084090D03*
Y1090498D03*
X458461Y1087294D03*
Y1093703D03*
X460312Y1084090D03*
Y1090498D03*
X462161Y1087294D03*
Y1093703D03*
X464012Y1084090D03*
Y1090498D03*
X465861Y1087294D03*
Y1093703D03*
X467712Y1096907D03*
Y1103316D03*
Y1109724D03*
X452912Y1096907D03*
Y1103316D03*
Y1109724D03*
X454761Y1100111D03*
Y1106520D03*
X456612Y1096907D03*
Y1103316D03*
Y1109724D03*
X458461Y1100111D03*
Y1106520D03*
X460312Y1096907D03*
Y1103316D03*
Y1109724D03*
X462161Y1100111D03*
Y1106520D03*
X464012Y1096907D03*
Y1103316D03*
Y1109724D03*
X465861Y1100111D03*
Y1106520D03*
Y1112929D03*
X454761D03*
X458461D03*
X462161D03*
X467712Y1116133D03*
Y1122541D03*
Y1128950D03*
X452912Y1116133D03*
Y1122541D03*
Y1128950D03*
X454761Y1119337D03*
Y1125746D03*
X456612Y1116133D03*
Y1122541D03*
Y1128950D03*
X458461Y1119337D03*
Y1125746D03*
X460312Y1116133D03*
Y1122541D03*
Y1128950D03*
X462161Y1119337D03*
Y1125746D03*
X464012Y1116133D03*
Y1122541D03*
Y1128950D03*
X465861Y1119337D03*
Y1125746D03*
X467712Y1135359D03*
X454761Y1132154D03*
X456612Y1135359D03*
X458461Y1132154D03*
X460312Y1135359D03*
X462161Y1132154D03*
X464012Y1135359D03*
X465861Y1132154D03*
X469128Y847081D03*
X470979Y850286D03*
X472828Y847081D03*
X474679Y850286D03*
X476528Y847081D03*
X478379Y850286D03*
X480228Y847081D03*
X482079Y850286D03*
X483928Y847081D03*
X469128Y853490D03*
Y859899D03*
Y866307D03*
X470979Y856694D03*
Y863103D03*
X472828Y853490D03*
Y859899D03*
Y866307D03*
X474679Y856694D03*
Y863103D03*
X476528Y853490D03*
Y859899D03*
Y866307D03*
X478379Y856694D03*
Y863103D03*
X480228Y853490D03*
Y859899D03*
Y866307D03*
X482079Y856694D03*
Y863103D03*
X483928Y853490D03*
Y859899D03*
Y866307D03*
X469128Y872716D03*
X470979Y869511D03*
X472828Y872716D03*
X474679Y869511D03*
X476528Y872716D03*
X478379Y869511D03*
X480228Y872716D03*
X482079Y869511D03*
X483928Y872716D03*
X469128Y879124D03*
X470979Y875920D03*
Y882329D03*
X472828Y879124D03*
X474679Y875920D03*
Y882329D03*
X476528Y879124D03*
X478379Y875920D03*
Y882329D03*
X480228Y879124D03*
X482079Y875920D03*
Y882329D03*
X483928Y879124D03*
X469128Y885533D03*
Y891942D03*
Y898350D03*
X470979Y888737D03*
Y895146D03*
Y901555D03*
X472828Y885533D03*
Y891942D03*
Y898350D03*
X474679Y888737D03*
Y895146D03*
Y901555D03*
X476528Y885533D03*
Y891942D03*
Y898350D03*
X478379Y888737D03*
Y895146D03*
Y901555D03*
X480228Y885533D03*
Y891942D03*
Y898350D03*
X482079Y888737D03*
Y895146D03*
Y901555D03*
X483928Y885533D03*
Y891942D03*
Y898350D03*
X469128Y904759D03*
Y911167D03*
Y917576D03*
X470979Y907963D03*
Y914372D03*
X472828Y904759D03*
Y911167D03*
Y917576D03*
X474679Y907963D03*
Y914372D03*
X476528Y904759D03*
Y911167D03*
Y917576D03*
X478379Y907963D03*
Y914372D03*
X480228Y904759D03*
Y911167D03*
Y917576D03*
X482079Y907963D03*
Y914372D03*
X483928Y904759D03*
Y911167D03*
Y917576D03*
X469128Y923985D03*
X470979Y920780D03*
X472828Y923985D03*
X474679Y920780D03*
X476528Y923985D03*
X478379Y920780D03*
Y927189D03*
X480228Y923985D03*
Y930393D03*
X482079Y920780D03*
Y927189D03*
X483928Y923985D03*
Y930393D03*
X478379Y933598D03*
X482079D03*
X478379Y940006D03*
Y946414D03*
X480228Y936801D03*
Y943210D03*
Y949619D03*
X482079Y940006D03*
Y946414D03*
X483928Y936801D03*
Y943210D03*
Y949619D03*
X478379Y952823D03*
Y959232D03*
X480228Y956027D03*
Y962436D03*
X482079Y952823D03*
Y959232D03*
X483928Y956027D03*
Y962436D03*
X478379Y965640D03*
X482079D03*
X478379Y972049D03*
Y978457D03*
X480228Y968845D03*
Y975253D03*
Y981662D03*
X482079Y972049D03*
Y978457D03*
X483928Y968845D03*
Y975253D03*
Y981662D03*
X478379Y984866D03*
X482079D03*
X480661Y997574D03*
X484361D03*
X478812Y1000778D03*
Y1007187D03*
Y1013595D03*
X480661Y1003983D03*
Y1010391D03*
X482512Y1000778D03*
Y1007187D03*
Y1013595D03*
X484361Y1003983D03*
Y1010391D03*
X478812Y1020004D03*
X480661Y1016800D03*
X482512Y1020004D03*
X484361Y1016800D03*
X478812Y1026413D03*
X480661Y1023208D03*
Y1029617D03*
X482512Y1026413D03*
X484361Y1023208D03*
Y1029617D03*
X469561Y1042434D03*
X471412Y1039230D03*
Y1045639D03*
X473261Y1042434D03*
X475112Y1039230D03*
Y1045639D03*
X476961Y1042434D03*
X478812Y1032821D03*
Y1039230D03*
Y1045639D03*
X480661Y1036026D03*
Y1042434D03*
X482512Y1032821D03*
Y1039230D03*
Y1045639D03*
X484361Y1036026D03*
Y1042434D03*
X469561Y1048842D03*
X471412Y1052047D03*
X473261Y1048842D03*
X475112Y1052047D03*
X476961Y1048842D03*
X478812Y1052047D03*
X480661Y1048842D03*
X482512Y1052047D03*
X484361Y1048842D03*
X469561Y1055251D03*
Y1061660D03*
X471412Y1058455D03*
X473261Y1055251D03*
Y1061660D03*
X475112Y1058455D03*
X476961Y1055251D03*
Y1061660D03*
X478812Y1058455D03*
X480661Y1055251D03*
Y1061660D03*
X482512Y1058455D03*
X484361Y1055251D03*
Y1061660D03*
X469561Y1068068D03*
Y1074477D03*
X471412Y1064864D03*
Y1071273D03*
Y1077681D03*
X473261Y1068068D03*
Y1074477D03*
X475112Y1064864D03*
Y1071273D03*
Y1077681D03*
X476961Y1068068D03*
Y1074477D03*
X478812Y1064864D03*
Y1071273D03*
Y1077681D03*
X480661Y1068068D03*
Y1074477D03*
X482512Y1064864D03*
Y1071273D03*
Y1077681D03*
X484361Y1068068D03*
Y1074477D03*
X469561Y1080885D03*
X473261D03*
X476961D03*
X480661D03*
X484361D03*
X469561Y1087294D03*
Y1093703D03*
X471412Y1084090D03*
Y1090498D03*
X473261Y1087294D03*
Y1093703D03*
X475112Y1084090D03*
Y1090498D03*
X476961Y1087294D03*
Y1093703D03*
X478812Y1084090D03*
Y1090498D03*
X480661Y1087294D03*
Y1093703D03*
X482512Y1084090D03*
Y1090498D03*
X484361Y1087294D03*
Y1093703D03*
X469561Y1100111D03*
Y1106520D03*
X471412Y1096907D03*
Y1103316D03*
Y1109724D03*
X473261Y1100111D03*
Y1106520D03*
X475112Y1096907D03*
Y1103316D03*
Y1109724D03*
X476961Y1100111D03*
Y1106520D03*
X478812Y1096907D03*
Y1103316D03*
Y1109724D03*
X480661Y1100111D03*
Y1106520D03*
X482512Y1096907D03*
Y1103316D03*
Y1109724D03*
X484361Y1100111D03*
Y1106520D03*
X469561Y1112929D03*
X473261D03*
X476961D03*
X480661D03*
X484361D03*
X469561Y1119337D03*
Y1125746D03*
X471412Y1116133D03*
Y1122541D03*
Y1128950D03*
X473261Y1119337D03*
Y1125746D03*
X475112Y1116133D03*
Y1122541D03*
Y1128950D03*
X476961Y1119337D03*
Y1125746D03*
X478812Y1116133D03*
Y1122541D03*
Y1128950D03*
X480661Y1119337D03*
Y1125746D03*
X482512Y1116133D03*
Y1122541D03*
Y1128950D03*
X484361Y1119337D03*
Y1125746D03*
X469561Y1132154D03*
X471412Y1135359D03*
X473261Y1132154D03*
X475112Y1135359D03*
X476961Y1132154D03*
X478812Y1135359D03*
X480661Y1132154D03*
X482512Y1135359D03*
X484361Y1132154D03*
X496879Y850286D03*
X498728Y847081D03*
X500579Y850286D03*
X485779D03*
X487628Y847081D03*
X489479Y850286D03*
X491328Y847081D03*
X493179Y850286D03*
X495028Y847081D03*
X496879Y856694D03*
Y863103D03*
X498728Y853490D03*
Y859899D03*
Y866307D03*
X500579Y856694D03*
Y863103D03*
X485779Y856694D03*
Y863103D03*
X487628Y853490D03*
Y859899D03*
Y866307D03*
X489479Y856694D03*
Y863103D03*
X491328Y853490D03*
Y859899D03*
Y866307D03*
X493179Y856694D03*
Y863103D03*
X495028Y853490D03*
Y859899D03*
Y866307D03*
X496879Y869511D03*
X498728Y872716D03*
X500579Y869511D03*
X485779D03*
X487628Y872716D03*
X489479Y869511D03*
X491328Y872716D03*
X493179Y869511D03*
X495028Y872716D03*
X496879Y875920D03*
Y882329D03*
X498728Y879124D03*
X500579Y875920D03*
Y882329D03*
X485779Y875920D03*
Y882329D03*
X487628Y879124D03*
X489479Y875920D03*
Y882329D03*
X491328Y879124D03*
X493179Y875920D03*
Y882329D03*
X495028Y879124D03*
X496879Y888737D03*
Y895146D03*
Y901555D03*
X498728Y885533D03*
Y891942D03*
Y898350D03*
X500579Y888737D03*
Y895146D03*
Y901555D03*
X485779Y888737D03*
Y895146D03*
Y901555D03*
X487628Y885533D03*
Y891942D03*
Y898350D03*
X489479Y888737D03*
Y895146D03*
Y901555D03*
X491328Y885533D03*
Y891942D03*
Y898350D03*
X493179Y888737D03*
Y895146D03*
Y901555D03*
X495028Y885533D03*
Y891942D03*
Y898350D03*
X496879Y907963D03*
Y914372D03*
X498728Y904759D03*
Y911167D03*
Y917576D03*
X500579Y907963D03*
Y914372D03*
X485779Y907963D03*
Y914372D03*
X487628Y904759D03*
Y911167D03*
Y917576D03*
X489479Y907963D03*
Y914372D03*
X491328Y904759D03*
Y911167D03*
Y917576D03*
X493179Y907963D03*
Y914372D03*
X495028Y904759D03*
Y911167D03*
Y917576D03*
X496879Y920780D03*
Y927189D03*
X498728Y923985D03*
Y930393D03*
X500579Y920780D03*
Y927189D03*
X485779Y920780D03*
Y927189D03*
X487628Y923985D03*
Y930393D03*
X489479Y920780D03*
Y927189D03*
X491328Y923985D03*
Y930393D03*
X493179Y920780D03*
Y927189D03*
X495028Y923985D03*
Y930393D03*
X496879Y933598D03*
X500579D03*
X485779D03*
X489479D03*
X493179D03*
X496879Y940006D03*
Y946414D03*
X498728Y936801D03*
Y943210D03*
Y949619D03*
X500579Y940006D03*
Y946414D03*
X485779Y940006D03*
Y946414D03*
X487628Y936801D03*
Y943210D03*
Y949619D03*
X489479Y940006D03*
Y946414D03*
X491328Y936801D03*
Y943210D03*
Y949619D03*
X493179Y940006D03*
Y946414D03*
X495028Y936801D03*
Y943210D03*
Y949619D03*
X496879Y952823D03*
Y959232D03*
X498728Y956027D03*
Y962436D03*
X500579Y952823D03*
Y959232D03*
X485779Y952823D03*
Y959232D03*
X487628Y956027D03*
Y962436D03*
X489479Y952823D03*
Y959232D03*
X491328Y956027D03*
Y962436D03*
X493179Y952823D03*
Y959232D03*
X495028Y956027D03*
Y962436D03*
X496879Y965640D03*
X500579D03*
X485779D03*
X489479D03*
X493179D03*
X496879Y972049D03*
Y978457D03*
X498728Y968845D03*
Y975253D03*
Y981662D03*
X500579Y972049D03*
Y978457D03*
X485779Y972049D03*
Y978457D03*
X487628Y968845D03*
Y975253D03*
Y981662D03*
X489479Y972049D03*
Y978457D03*
X491328Y968845D03*
Y975253D03*
Y981662D03*
X493179Y972049D03*
Y978457D03*
X495028Y968845D03*
Y975253D03*
Y981662D03*
X496879Y984866D03*
X500579D03*
X485779D03*
X489479D03*
X493179D03*
X499161Y997574D03*
X488061D03*
X491761D03*
X495461D03*
X497312Y1000778D03*
Y1007187D03*
Y1013595D03*
X499161Y1003983D03*
Y1010391D03*
X501012Y1000778D03*
Y1007187D03*
Y1013595D03*
X486212Y1000778D03*
Y1007187D03*
Y1013595D03*
X488061Y1003983D03*
Y1010391D03*
X489912Y1000778D03*
Y1007187D03*
Y1013595D03*
X491761Y1003983D03*
Y1010391D03*
X493612Y1000778D03*
Y1007187D03*
Y1013595D03*
X495461Y1003983D03*
Y1010391D03*
X497312Y1020004D03*
X499161Y1016800D03*
X501012Y1020004D03*
X486212D03*
X488061Y1016800D03*
X489912Y1020004D03*
X491761Y1016800D03*
X493612Y1020004D03*
X495461Y1016800D03*
X497312Y1026413D03*
X499161Y1023208D03*
Y1029617D03*
X501012Y1026413D03*
X486212D03*
X488061Y1023208D03*
Y1029617D03*
X489912Y1026413D03*
X491761Y1023208D03*
Y1029617D03*
X493612Y1026413D03*
X495461Y1023208D03*
Y1029617D03*
X497312Y1032821D03*
Y1039230D03*
Y1045639D03*
X499161Y1036026D03*
Y1042434D03*
X501012Y1032821D03*
Y1039230D03*
Y1045639D03*
X486212Y1032821D03*
Y1039230D03*
Y1045639D03*
X488061Y1036026D03*
Y1042434D03*
X489912Y1032821D03*
Y1039230D03*
Y1045639D03*
X491761Y1036026D03*
Y1042434D03*
X493612Y1032821D03*
Y1039230D03*
Y1045639D03*
X495461Y1036026D03*
Y1042434D03*
X497312Y1052047D03*
X499161Y1048842D03*
X501012Y1052047D03*
X486212D03*
X488061Y1048842D03*
X489912Y1052047D03*
X491761Y1048842D03*
X493612Y1052047D03*
X495461Y1048842D03*
X497312Y1058455D03*
X499161Y1055251D03*
Y1061660D03*
X501012Y1058455D03*
X486212D03*
X488061Y1055251D03*
Y1061660D03*
X489912Y1058455D03*
X491761Y1055251D03*
Y1061660D03*
X493612Y1058455D03*
X495461Y1055251D03*
Y1061660D03*
X497312Y1064864D03*
Y1071273D03*
Y1077681D03*
X499161Y1068068D03*
Y1074477D03*
X501012Y1064864D03*
Y1071273D03*
Y1077681D03*
X486212Y1064864D03*
Y1071273D03*
Y1077681D03*
X488061Y1068068D03*
Y1074477D03*
X489912Y1064864D03*
Y1071273D03*
Y1077681D03*
X491761Y1068068D03*
Y1074477D03*
X493612Y1064864D03*
Y1071273D03*
Y1077681D03*
X495461Y1068068D03*
Y1074477D03*
X499161Y1080885D03*
X488061D03*
X491761D03*
X495461D03*
X497312Y1084090D03*
Y1090498D03*
X499161Y1087294D03*
Y1093703D03*
X501012Y1084090D03*
Y1090498D03*
X486212Y1084090D03*
Y1090498D03*
X488061Y1087294D03*
Y1093703D03*
X489912Y1084090D03*
Y1090498D03*
X491761Y1087294D03*
Y1093703D03*
X493612Y1084090D03*
Y1090498D03*
X495461Y1087294D03*
Y1093703D03*
X497312Y1096907D03*
Y1103316D03*
Y1109724D03*
X499161Y1100111D03*
Y1106520D03*
X501012Y1096907D03*
Y1103316D03*
Y1109724D03*
X486212Y1096907D03*
Y1103316D03*
Y1109724D03*
X488061Y1100111D03*
Y1106520D03*
X489912Y1096907D03*
Y1103316D03*
Y1109724D03*
X491761Y1100111D03*
Y1106520D03*
X493612Y1096907D03*
Y1103316D03*
Y1109724D03*
X495461Y1100111D03*
Y1106520D03*
X499161Y1112929D03*
X488061D03*
X491761D03*
X495461D03*
X497312Y1116133D03*
Y1122541D03*
Y1128950D03*
X499161Y1119337D03*
Y1125746D03*
X501012Y1116133D03*
Y1122541D03*
Y1128950D03*
X486212Y1116133D03*
Y1122541D03*
Y1128950D03*
X488061Y1119337D03*
Y1125746D03*
X489912Y1116133D03*
Y1122541D03*
Y1128950D03*
X491761Y1119337D03*
Y1125746D03*
X493612Y1116133D03*
Y1122541D03*
Y1128950D03*
X495461Y1119337D03*
Y1125746D03*
X497312Y1135359D03*
X499161Y1132154D03*
X501012Y1135359D03*
X486212D03*
X488061Y1132154D03*
X489912Y1135359D03*
X491761Y1132154D03*
X493612Y1135359D03*
X495461Y1132154D03*
X502428Y847081D03*
X504279Y850286D03*
X506128Y847081D03*
X507979Y850286D03*
X509828Y847081D03*
X511679Y850286D03*
X513528Y847081D03*
X515379Y850286D03*
X517228Y847081D03*
X502428Y853490D03*
Y859899D03*
Y866307D03*
X504279Y856694D03*
Y863103D03*
X506128Y853490D03*
Y859899D03*
Y866307D03*
X507979Y856694D03*
Y863103D03*
X509828Y853490D03*
Y859899D03*
Y866307D03*
X511679Y856694D03*
Y863103D03*
X513528Y853490D03*
Y859899D03*
Y866307D03*
X515379Y856694D03*
Y863103D03*
X517228Y853490D03*
Y859899D03*
Y866307D03*
X502428Y872716D03*
X504279Y869511D03*
X506128Y872716D03*
X507979Y869511D03*
X509828Y872716D03*
X511679Y869511D03*
X513528Y872716D03*
X515379Y869511D03*
X517228Y872716D03*
X502428Y879124D03*
X504279Y875920D03*
Y882329D03*
X506128Y879124D03*
X507979Y875920D03*
Y882329D03*
X509828Y879124D03*
X511679Y875920D03*
Y882329D03*
X513528Y879124D03*
X515379Y875920D03*
Y882329D03*
X517228Y879124D03*
X502428Y885533D03*
Y891942D03*
Y898350D03*
X504279Y888737D03*
Y895146D03*
Y901555D03*
X506128Y885533D03*
Y891942D03*
Y898350D03*
X507979Y888737D03*
Y895146D03*
Y901555D03*
X509828Y885533D03*
Y891942D03*
Y898350D03*
X511679Y888737D03*
Y895146D03*
Y901555D03*
X513528Y885533D03*
Y891942D03*
Y898350D03*
X515379Y888737D03*
Y895146D03*
Y901555D03*
X517228Y885533D03*
Y891942D03*
Y898350D03*
X502428Y904759D03*
Y911167D03*
Y917576D03*
X504279Y907963D03*
Y914372D03*
X506128Y904759D03*
Y911167D03*
Y917576D03*
X507979Y907963D03*
Y914372D03*
X509828Y904759D03*
Y911167D03*
Y917576D03*
X511679Y907963D03*
Y914372D03*
X513528Y904759D03*
Y911167D03*
Y917576D03*
X515379Y907963D03*
Y914372D03*
X517228Y904759D03*
Y911167D03*
Y917576D03*
X502428Y923985D03*
Y930393D03*
X504279Y920780D03*
Y927189D03*
X506128Y923985D03*
Y930393D03*
X507979Y920780D03*
Y927189D03*
X509828Y923985D03*
Y930393D03*
X511679Y920780D03*
Y927189D03*
X513528Y923985D03*
Y930393D03*
X515379Y920780D03*
Y927189D03*
X517228Y923985D03*
Y930393D03*
X504279Y933598D03*
X507979D03*
X511679D03*
X515379D03*
X502428Y936801D03*
Y943210D03*
Y949619D03*
X504279Y940006D03*
Y946414D03*
X506128Y936801D03*
Y943210D03*
Y949619D03*
X507979Y940006D03*
Y946414D03*
X509828Y936801D03*
Y943210D03*
Y949619D03*
X511679Y940006D03*
Y946414D03*
X513528Y936801D03*
Y943210D03*
Y949619D03*
X515379Y940006D03*
Y946414D03*
X517228Y936801D03*
Y943210D03*
Y949619D03*
X502428Y956027D03*
Y962436D03*
X504279Y952823D03*
Y959232D03*
X506128Y956027D03*
Y962436D03*
X507979Y952823D03*
Y959232D03*
X509828Y956027D03*
Y962436D03*
X511679Y952823D03*
Y959232D03*
X513528Y956027D03*
Y962436D03*
X515379Y952823D03*
Y959232D03*
X517228Y956027D03*
Y962436D03*
X504279Y965640D03*
X507979D03*
X511679D03*
X515379D03*
X502428Y968845D03*
Y975253D03*
Y981662D03*
X504279Y972049D03*
Y978457D03*
X506128Y968845D03*
Y975253D03*
Y981662D03*
X507979Y972049D03*
Y978457D03*
X509828Y968845D03*
Y975253D03*
Y981662D03*
X511679Y972049D03*
Y978457D03*
X513528Y968845D03*
Y975253D03*
Y981662D03*
X515379Y972049D03*
Y978457D03*
X517228Y968845D03*
Y975253D03*
Y981662D03*
X504279Y984866D03*
X507979D03*
X511679D03*
X515379D03*
X502861Y997574D03*
X506561D03*
X510261D03*
X513961D03*
X517661D03*
X502861Y1003983D03*
Y1010391D03*
X504712Y1000778D03*
Y1007187D03*
Y1013595D03*
X506561Y1003983D03*
Y1010391D03*
X508412Y1000778D03*
Y1007187D03*
Y1013595D03*
X510261Y1003983D03*
Y1010391D03*
X512112Y1000778D03*
Y1007187D03*
Y1013595D03*
X513961Y1003983D03*
Y1010391D03*
X515812Y1000778D03*
Y1007187D03*
Y1013595D03*
X517661Y1003983D03*
Y1010391D03*
X502861Y1016800D03*
X504712Y1020004D03*
X506561Y1016800D03*
X508412Y1020004D03*
X510261Y1016800D03*
X512112Y1020004D03*
X513961Y1016800D03*
X515812Y1020004D03*
X517661Y1016800D03*
X502861Y1023208D03*
Y1029617D03*
X504712Y1026413D03*
X506561Y1023208D03*
Y1029617D03*
X508412Y1026413D03*
X510261Y1023208D03*
Y1029617D03*
X512112Y1026413D03*
X513961Y1023208D03*
Y1029617D03*
X515812Y1026413D03*
X517661Y1023208D03*
Y1029617D03*
X502861Y1036026D03*
Y1042434D03*
X504712Y1032821D03*
Y1039230D03*
Y1045639D03*
X506561Y1036026D03*
Y1042434D03*
X508412Y1032821D03*
Y1039230D03*
Y1045639D03*
X510261Y1036026D03*
Y1042434D03*
X512112Y1032821D03*
Y1039230D03*
Y1045639D03*
X513961Y1036026D03*
Y1042434D03*
X515812Y1032821D03*
Y1039230D03*
Y1045639D03*
X517661Y1036026D03*
Y1042434D03*
X502861Y1048842D03*
X504712Y1052047D03*
X506561Y1048842D03*
X508412Y1052047D03*
X510261Y1048842D03*
X512112Y1052047D03*
X513961Y1048842D03*
X515812Y1052047D03*
X517661Y1048842D03*
X502861Y1055251D03*
Y1061660D03*
X504712Y1058455D03*
X506561Y1055251D03*
Y1061660D03*
X508412Y1058455D03*
X510261Y1055251D03*
Y1061660D03*
X512112Y1058455D03*
X513961Y1055251D03*
Y1061660D03*
X515812Y1058455D03*
X517661Y1055251D03*
Y1061660D03*
X502861Y1068068D03*
Y1074477D03*
X504712Y1064864D03*
Y1071273D03*
Y1077681D03*
X506561Y1068068D03*
Y1074477D03*
X508412Y1064864D03*
Y1071273D03*
Y1077681D03*
X510261Y1068068D03*
Y1074477D03*
X512112Y1064864D03*
Y1071273D03*
Y1077681D03*
X513961Y1068068D03*
Y1074477D03*
X515812Y1064864D03*
Y1071273D03*
Y1077681D03*
X517661Y1068068D03*
Y1074477D03*
X502861Y1080885D03*
X506561D03*
X510261D03*
X513961D03*
X517661D03*
X502861Y1087294D03*
Y1093703D03*
X504712Y1084090D03*
Y1090498D03*
X506561Y1087294D03*
Y1093703D03*
X508412Y1084090D03*
Y1090498D03*
X510261Y1087294D03*
Y1093703D03*
X512112Y1084090D03*
Y1090498D03*
X513961Y1087294D03*
Y1093703D03*
X515812Y1084090D03*
Y1090498D03*
X517661Y1087294D03*
Y1093703D03*
X502861Y1100111D03*
Y1106520D03*
X504712Y1096907D03*
Y1103316D03*
Y1109724D03*
X506561Y1100111D03*
Y1106520D03*
X508412Y1096907D03*
Y1103316D03*
Y1109724D03*
X510261Y1100111D03*
Y1106520D03*
X512112Y1096907D03*
Y1103316D03*
Y1109724D03*
X513961Y1100111D03*
Y1106520D03*
X515812Y1096907D03*
Y1103316D03*
Y1109724D03*
X517661Y1100111D03*
Y1106520D03*
X502861Y1112929D03*
X506561D03*
X510261D03*
X513961D03*
X517661D03*
X502861Y1119337D03*
Y1125746D03*
X504712Y1116133D03*
Y1122541D03*
Y1128950D03*
X506561Y1119337D03*
Y1125746D03*
X508412Y1116133D03*
Y1122541D03*
Y1128950D03*
X510261Y1119337D03*
Y1125746D03*
X512112Y1116133D03*
Y1122541D03*
Y1128950D03*
X513961Y1119337D03*
Y1125746D03*
X515812Y1116133D03*
Y1122541D03*
Y1128950D03*
X517661Y1119337D03*
Y1125746D03*
X502861Y1132154D03*
X504712Y1135359D03*
X506561Y1132154D03*
X508412Y1135359D03*
X510261Y1132154D03*
X512112Y1135359D03*
X513961Y1132154D03*
X515812Y1135359D03*
X517661Y1132154D03*
X526479Y850286D03*
X530179D03*
X519079D03*
X520928Y847081D03*
X522779Y850286D03*
X526479Y856694D03*
Y863103D03*
X528329Y853490D03*
Y859899D03*
Y866307D03*
X530179Y856694D03*
Y863103D03*
X532028Y853490D03*
Y859899D03*
Y866307D03*
X533879Y856694D03*
Y863103D03*
X519079Y856694D03*
Y863103D03*
X520928Y853490D03*
Y859899D03*
Y866307D03*
X522779Y856694D03*
Y863103D03*
X524628Y853490D03*
Y859899D03*
Y866307D03*
X526479Y869511D03*
X528329Y872716D03*
X530179Y869511D03*
X532028Y872716D03*
X533879Y869511D03*
X519079D03*
X520928Y872716D03*
X522779Y869511D03*
X524628Y872716D03*
X526479Y875920D03*
Y882329D03*
X528329Y879124D03*
X530179Y875920D03*
Y882329D03*
X532028Y879124D03*
X533879Y875920D03*
Y882329D03*
X519079Y875920D03*
Y882329D03*
X520928Y879124D03*
X522779Y875920D03*
Y882329D03*
X524628Y879124D03*
X526479Y888737D03*
Y895146D03*
Y901555D03*
X528329Y885533D03*
Y891942D03*
Y898350D03*
X530179Y888737D03*
Y895146D03*
Y901555D03*
X532028Y885533D03*
Y891942D03*
Y898350D03*
X533879Y888737D03*
Y895146D03*
Y901555D03*
X519079Y888737D03*
Y895146D03*
Y901555D03*
X520928Y885533D03*
Y891942D03*
Y898350D03*
X522779Y888737D03*
Y895146D03*
Y901555D03*
X524628Y885533D03*
Y891942D03*
Y898350D03*
X526479Y907963D03*
Y914372D03*
X528329Y904759D03*
Y911167D03*
Y917576D03*
X530179Y907963D03*
Y914372D03*
X532028Y904759D03*
Y911167D03*
Y917576D03*
X533879Y907963D03*
Y914372D03*
X519079Y907963D03*
Y914372D03*
X520928Y904759D03*
Y911167D03*
Y917576D03*
X522779Y907963D03*
Y914372D03*
X524628Y904759D03*
Y911167D03*
Y917576D03*
X526479Y920780D03*
Y927189D03*
X528329Y923985D03*
Y930393D03*
X530179Y920780D03*
Y927189D03*
X532028Y923985D03*
Y930393D03*
X533879Y920780D03*
Y927189D03*
X519079Y920780D03*
Y927189D03*
X520928Y923985D03*
Y930393D03*
X522779Y920780D03*
Y927189D03*
X524628Y923985D03*
Y930393D03*
X526479Y933598D03*
X530179D03*
X533879D03*
X519079D03*
X522779D03*
X526479Y940006D03*
Y946414D03*
X528329Y936801D03*
Y943210D03*
Y949619D03*
X530179Y940006D03*
Y946414D03*
X532028Y936801D03*
Y943210D03*
Y949619D03*
X533879Y940006D03*
Y946414D03*
X519079Y940006D03*
Y946414D03*
X520928Y936801D03*
Y943210D03*
Y949619D03*
X522779Y940006D03*
Y946414D03*
X524628Y936801D03*
Y943210D03*
Y949619D03*
X526479Y952823D03*
Y959232D03*
X528329Y956027D03*
Y962436D03*
X530179Y952823D03*
Y959232D03*
X532028Y956027D03*
Y962436D03*
X533879Y952823D03*
Y959232D03*
X519079Y952823D03*
Y959232D03*
X520928Y956027D03*
Y962436D03*
X522779Y952823D03*
Y959232D03*
X524628Y956027D03*
Y962436D03*
X526479Y965640D03*
X530179D03*
X533879D03*
X519079D03*
X522779D03*
X526479Y972049D03*
Y978457D03*
X528329Y968845D03*
Y975253D03*
Y981662D03*
X530179Y972049D03*
Y978457D03*
X532028Y968845D03*
Y975253D03*
Y981662D03*
X533879Y972049D03*
Y978457D03*
X519079Y972049D03*
Y978457D03*
X520928Y968845D03*
Y975253D03*
Y981662D03*
X522779Y972049D03*
Y978457D03*
X524628Y968845D03*
Y975253D03*
Y981662D03*
X526479Y984866D03*
X530179D03*
X533879D03*
X519079D03*
X522779D03*
X528761Y997574D03*
X532461D03*
X521361D03*
X525061D03*
X526912Y1000778D03*
Y1007187D03*
Y1013595D03*
X528761Y1003983D03*
Y1010391D03*
X530612Y1000778D03*
Y1007187D03*
Y1013595D03*
X532461Y1003983D03*
Y1010391D03*
X519512Y1000778D03*
Y1007187D03*
Y1013595D03*
X521361Y1003983D03*
Y1010391D03*
X523212Y1000778D03*
Y1007187D03*
Y1013595D03*
X525061Y1003983D03*
Y1010391D03*
X526912Y1020004D03*
X528761Y1016800D03*
X530612Y1020004D03*
X532461Y1016800D03*
X519512Y1020004D03*
X521361Y1016800D03*
X523212Y1020004D03*
X525061Y1016800D03*
X526912Y1026413D03*
X528761Y1023208D03*
Y1029617D03*
X530612Y1026413D03*
X532461Y1023208D03*
Y1029617D03*
X519512Y1026413D03*
X521361Y1023208D03*
Y1029617D03*
X523212Y1026413D03*
X525061Y1023208D03*
Y1029617D03*
X526912Y1032821D03*
Y1039230D03*
Y1045639D03*
X528761Y1036026D03*
Y1042434D03*
X530612Y1032821D03*
Y1039230D03*
Y1045639D03*
X532461Y1036026D03*
Y1042434D03*
X519512Y1032821D03*
Y1039230D03*
Y1045639D03*
X521361Y1036026D03*
Y1042434D03*
X523212Y1032821D03*
Y1039230D03*
Y1045639D03*
X525061Y1036026D03*
Y1042434D03*
X526912Y1052047D03*
X528761Y1048842D03*
X530612Y1052047D03*
X532461Y1048842D03*
X519512Y1052047D03*
X521361Y1048842D03*
X523212Y1052047D03*
X525061Y1048842D03*
X526912Y1058455D03*
X528761Y1055251D03*
Y1061660D03*
X530612Y1058455D03*
X532461Y1055251D03*
Y1061660D03*
X519512Y1058455D03*
X521361Y1055251D03*
Y1061660D03*
X523212Y1058455D03*
X525061Y1055251D03*
Y1061660D03*
X526912Y1064864D03*
Y1071273D03*
Y1077681D03*
X528761Y1068068D03*
Y1074477D03*
X530612Y1064864D03*
Y1071273D03*
Y1077681D03*
X532461Y1068068D03*
Y1074477D03*
X519512Y1064864D03*
Y1071273D03*
Y1077681D03*
X521361Y1068068D03*
Y1074477D03*
X523212Y1064864D03*
Y1071273D03*
Y1077681D03*
X525061Y1068068D03*
Y1074477D03*
X528761Y1080885D03*
X532461D03*
X521361D03*
X525061D03*
X526912Y1084090D03*
Y1090498D03*
X528761Y1087294D03*
Y1093703D03*
X530612Y1084090D03*
Y1090498D03*
X532461Y1087294D03*
Y1093703D03*
X519512Y1084090D03*
Y1090498D03*
X521361Y1087294D03*
Y1093703D03*
X523212Y1084090D03*
Y1090498D03*
X525061Y1087294D03*
Y1093703D03*
X526912Y1096907D03*
Y1103316D03*
Y1109724D03*
X528761Y1100111D03*
Y1106520D03*
X530612Y1096907D03*
Y1103316D03*
Y1109724D03*
X532461Y1100111D03*
Y1106520D03*
X519512Y1096907D03*
Y1103316D03*
Y1109724D03*
X521361Y1100111D03*
Y1106520D03*
X523212Y1096907D03*
Y1103316D03*
Y1109724D03*
X525061Y1100111D03*
Y1106520D03*
X528761Y1112929D03*
X532461D03*
X521361D03*
X525061D03*
X526912Y1116133D03*
Y1122541D03*
Y1128950D03*
X528761Y1119337D03*
Y1125746D03*
X530612Y1116133D03*
Y1122541D03*
Y1128950D03*
X532461Y1119337D03*
Y1125746D03*
X519512Y1116133D03*
Y1122541D03*
Y1128950D03*
X521361Y1119337D03*
Y1125746D03*
X523212Y1116133D03*
Y1122541D03*
Y1128950D03*
X525061Y1119337D03*
Y1125746D03*
X528761Y1132154D03*
X519512Y1135359D03*
X521361Y1132154D03*
X523212Y1135359D03*
X525061Y1132154D03*
X535729Y859899D03*
Y866307D03*
X537579Y863103D03*
X539428Y866307D03*
X535729Y872716D03*
X537579Y869511D03*
X539428Y872716D03*
X541279Y869511D03*
X543129Y872716D03*
X535729Y879124D03*
X537579Y875920D03*
Y882329D03*
X539428Y879124D03*
X541279Y875920D03*
Y882329D03*
X543129Y879124D03*
X544979Y875920D03*
Y882329D03*
X535729Y885533D03*
Y891942D03*
Y898350D03*
X537579Y888737D03*
Y895146D03*
Y901555D03*
X539428Y885533D03*
Y891942D03*
Y898350D03*
X541279Y888737D03*
Y895146D03*
Y901555D03*
X543129Y885533D03*
Y891942D03*
Y898350D03*
X544979Y888737D03*
Y895146D03*
Y901555D03*
X535729Y904759D03*
Y911167D03*
Y917576D03*
X537579Y907963D03*
Y914372D03*
X539428Y904759D03*
Y911167D03*
Y917576D03*
X541279Y907963D03*
Y914372D03*
X543129Y904759D03*
Y911167D03*
Y917576D03*
X544979Y907963D03*
Y914372D03*
X535729Y923985D03*
Y930393D03*
X537579Y920780D03*
Y927189D03*
X539428Y923985D03*
Y930393D03*
X541279Y920780D03*
Y927189D03*
X543129Y923985D03*
Y930393D03*
X544979Y920780D03*
Y927189D03*
X537579Y933598D03*
X541279D03*
X544979D03*
X535729Y936801D03*
Y943210D03*
Y949619D03*
X537579Y940006D03*
Y946414D03*
X539428Y936801D03*
Y943210D03*
Y949619D03*
X541279Y940006D03*
Y946414D03*
X543129Y936801D03*
Y943210D03*
Y949619D03*
X544979Y940006D03*
Y946414D03*
X535729Y956027D03*
Y962436D03*
X537579Y952823D03*
Y959232D03*
X539428Y956027D03*
Y962436D03*
X541279Y952823D03*
Y959232D03*
X543129Y956027D03*
Y962436D03*
X544979Y952823D03*
Y959232D03*
X537579Y965640D03*
X541279D03*
X544979D03*
X535729Y968845D03*
Y975253D03*
Y981662D03*
X537579Y972049D03*
Y978457D03*
X539428Y968845D03*
Y975253D03*
Y981662D03*
X541279Y972049D03*
Y978457D03*
X543129Y968845D03*
Y975253D03*
X544979Y972049D03*
X537579Y984866D03*
X536161Y997574D03*
X539861D03*
X534311Y1000778D03*
Y1007187D03*
Y1013595D03*
X536161Y1003983D03*
Y1010391D03*
X538012Y1000778D03*
Y1007187D03*
Y1013595D03*
X539861Y1003983D03*
Y1010391D03*
X541711Y1000778D03*
Y1007187D03*
Y1013595D03*
X543561Y1003983D03*
Y1010391D03*
X545412Y1007187D03*
Y1013595D03*
X534311Y1020004D03*
X536161Y1016800D03*
X538012Y1020004D03*
X539861Y1016800D03*
X541711Y1020004D03*
X543561Y1016800D03*
X545412Y1020004D03*
X534311Y1026413D03*
X536161Y1023208D03*
Y1029617D03*
X538012Y1026413D03*
X539861Y1023208D03*
Y1029617D03*
X541711Y1026413D03*
X543561Y1023208D03*
Y1029617D03*
X545412Y1026413D03*
X534311Y1032821D03*
Y1039230D03*
Y1045639D03*
X536161Y1036026D03*
Y1042434D03*
X538012Y1032821D03*
Y1039230D03*
Y1045639D03*
X539861Y1036026D03*
Y1042434D03*
X541711Y1032821D03*
Y1039230D03*
Y1045639D03*
X543561Y1036026D03*
Y1042434D03*
X545412Y1032821D03*
Y1039230D03*
X534311Y1052047D03*
X536161Y1048842D03*
X538012Y1052047D03*
X539861Y1048842D03*
X541711Y1052047D03*
X543561Y1048842D03*
X534311Y1058455D03*
X536161Y1055251D03*
Y1061660D03*
X538012Y1058455D03*
X539861Y1055251D03*
Y1061660D03*
X541711Y1058455D03*
X543561Y1055251D03*
Y1061660D03*
X534311Y1064864D03*
Y1071273D03*
Y1077681D03*
X536161Y1068068D03*
Y1074477D03*
X538012Y1064864D03*
Y1071273D03*
Y1077681D03*
X539861Y1068068D03*
Y1074477D03*
X541711Y1064864D03*
Y1071273D03*
Y1077681D03*
X543561Y1068068D03*
Y1074477D03*
X536161Y1080885D03*
X539861D03*
X543561D03*
X534311Y1084090D03*
Y1090498D03*
X536161Y1087294D03*
Y1093703D03*
X538012Y1084090D03*
Y1090498D03*
X539861Y1087294D03*
Y1093703D03*
X541711Y1084090D03*
Y1090498D03*
X543561Y1087294D03*
Y1093703D03*
X534311Y1096907D03*
Y1103316D03*
Y1109724D03*
X536161Y1100111D03*
Y1106520D03*
X538012Y1096907D03*
Y1103316D03*
Y1109724D03*
X539861Y1100111D03*
Y1106520D03*
X541711Y1096907D03*
Y1103316D03*
Y1109724D03*
X543561Y1100111D03*
Y1106520D03*
X536161Y1112929D03*
X539861D03*
X534311Y1116133D03*
Y1122541D03*
X536161Y1119337D03*
X538012Y1116133D03*
X1312070Y879124D03*
X1313921Y875920D03*
Y882329D03*
X1312070Y885533D03*
Y891942D03*
Y898350D03*
X1313921Y888737D03*
Y895146D03*
Y901555D03*
X1312070Y904759D03*
Y911167D03*
Y917576D03*
X1313921Y907963D03*
Y914372D03*
X1312070Y923985D03*
Y930393D03*
X1313921Y920780D03*
Y927189D03*
Y933598D03*
X1312070Y936801D03*
Y943210D03*
Y949619D03*
X1313921Y940006D03*
Y946414D03*
X1312070Y956027D03*
Y962436D03*
X1313921Y952823D03*
Y959232D03*
Y965640D03*
X1312070Y968845D03*
Y975253D03*
X1313921Y972049D03*
Y978457D03*
X1312503Y1010391D03*
X1314353Y1007187D03*
Y1013595D03*
X1312503Y1016800D03*
Y1023208D03*
X1314353Y1020004D03*
X1312503Y1029617D03*
X1314353Y1026413D03*
X1312503Y1036026D03*
Y1042434D03*
X1314353Y1032821D03*
Y1039230D03*
Y1045639D03*
X1312503Y1048842D03*
X1314353Y1052047D03*
Y1058455D03*
Y1064864D03*
Y1071273D03*
Y1077681D03*
Y1084090D03*
Y1090498D03*
Y1096907D03*
Y1103316D03*
Y1109724D03*
X1328721Y850286D03*
X1323171Y859899D03*
Y866307D03*
X1325021Y856694D03*
Y863103D03*
X1326870Y853490D03*
Y859899D03*
Y866307D03*
X1328721Y856694D03*
Y863103D03*
X1330570Y853490D03*
Y859899D03*
Y866307D03*
X1319470D03*
X1321321Y863103D03*
X1323171Y872716D03*
X1325021Y869511D03*
X1326870Y872716D03*
X1328721Y869511D03*
X1330570Y872716D03*
X1315771D03*
X1317621Y869511D03*
X1319470Y872716D03*
X1321321Y869511D03*
X1323171Y879124D03*
X1325021Y875920D03*
Y882329D03*
X1326870Y879124D03*
X1328721Y875920D03*
Y882329D03*
X1330570Y879124D03*
X1315771D03*
X1317621Y875920D03*
Y882329D03*
X1319470Y879124D03*
X1321321Y875920D03*
Y882329D03*
X1323171Y885533D03*
Y891942D03*
Y898350D03*
X1325021Y888737D03*
Y895146D03*
Y901555D03*
X1326870Y885533D03*
Y891942D03*
Y898350D03*
X1328721Y888737D03*
Y895146D03*
Y901555D03*
X1330570Y885533D03*
Y891942D03*
Y898350D03*
X1315771Y885533D03*
Y891942D03*
Y898350D03*
X1317621Y888737D03*
Y895146D03*
Y901555D03*
X1319470Y885533D03*
Y891942D03*
Y898350D03*
X1321321Y888737D03*
Y895146D03*
Y901555D03*
X1323171Y904759D03*
Y911167D03*
Y917576D03*
X1325021Y907963D03*
Y914372D03*
X1326870Y904759D03*
Y911167D03*
Y917576D03*
X1328721Y907963D03*
Y914372D03*
X1330570Y904759D03*
Y911167D03*
Y917576D03*
X1315771Y904759D03*
Y911167D03*
Y917576D03*
X1317621Y907963D03*
Y914372D03*
X1319470Y904759D03*
Y911167D03*
Y917576D03*
X1321321Y907963D03*
Y914372D03*
X1323171Y923985D03*
Y930393D03*
X1325021Y920780D03*
Y927189D03*
Y933598D03*
X1326870Y923985D03*
Y930393D03*
X1328721Y920780D03*
Y927189D03*
Y933598D03*
X1330570Y923985D03*
Y930393D03*
X1315771Y923985D03*
Y930393D03*
X1317621Y920780D03*
Y927189D03*
Y933598D03*
X1319470Y923985D03*
Y930393D03*
X1321321Y920780D03*
Y927189D03*
Y933598D03*
X1323171Y936801D03*
Y943210D03*
Y949619D03*
X1325021Y940006D03*
Y946414D03*
X1326870Y936801D03*
Y943210D03*
Y949619D03*
X1328721Y940006D03*
Y946414D03*
X1330570Y936801D03*
Y943210D03*
Y949619D03*
X1315771Y936801D03*
Y943210D03*
Y949619D03*
X1317621Y940006D03*
Y946414D03*
X1319470Y936801D03*
Y943210D03*
Y949619D03*
X1321321Y940006D03*
Y946414D03*
X1323171Y956027D03*
Y962436D03*
X1325021Y952823D03*
Y959232D03*
X1326870Y956027D03*
Y962436D03*
X1328721Y952823D03*
Y959232D03*
X1330570Y956027D03*
Y962436D03*
X1315771Y956027D03*
Y962436D03*
X1317621Y952823D03*
Y959232D03*
X1319470Y956027D03*
Y962436D03*
X1321321Y952823D03*
Y959232D03*
X1325021Y965640D03*
X1328721D03*
X1317621D03*
X1321321D03*
X1323171Y968845D03*
Y975253D03*
Y981662D03*
X1325021Y972049D03*
Y978457D03*
X1326870Y968845D03*
Y975253D03*
Y981662D03*
X1328721Y972049D03*
Y978457D03*
X1330570Y968845D03*
Y975253D03*
Y981662D03*
X1315771Y968845D03*
Y975253D03*
Y981662D03*
X1317621Y972049D03*
Y978457D03*
X1319470Y968845D03*
Y975253D03*
Y981662D03*
X1321321Y972049D03*
Y978457D03*
X1325021Y984866D03*
X1328721D03*
X1317621D03*
X1321321D03*
X1323603Y997574D03*
X1327303D03*
X1331003D03*
X1319903D03*
X1323603Y1003983D03*
Y1010391D03*
X1325454Y1000778D03*
Y1007187D03*
Y1013595D03*
X1327303Y1003983D03*
Y1010391D03*
X1329153Y1000778D03*
Y1007187D03*
Y1013595D03*
X1331003Y1003983D03*
Y1010391D03*
X1316203Y1003983D03*
Y1010391D03*
X1318054Y1000778D03*
Y1007187D03*
Y1013595D03*
X1319903Y1003983D03*
Y1010391D03*
X1321753Y1000778D03*
Y1007187D03*
Y1013595D03*
X1323603Y1016800D03*
Y1023208D03*
X1325454Y1020004D03*
X1327303Y1016800D03*
Y1023208D03*
X1329153Y1020004D03*
X1331003Y1016800D03*
Y1023208D03*
X1316203Y1016800D03*
Y1023208D03*
X1318054Y1020004D03*
X1319903Y1016800D03*
Y1023208D03*
X1321753Y1020004D03*
X1323603Y1029617D03*
X1325454Y1026413D03*
X1327303Y1029617D03*
X1329153Y1026413D03*
X1331003Y1029617D03*
X1316203D03*
X1318054Y1026413D03*
X1319903Y1029617D03*
X1321753Y1026413D03*
X1323603Y1036026D03*
Y1042434D03*
X1325454Y1032821D03*
Y1039230D03*
Y1045639D03*
X1327303Y1036026D03*
Y1042434D03*
X1329153Y1032821D03*
Y1039230D03*
Y1045639D03*
X1331003Y1036026D03*
Y1042434D03*
X1316203Y1036026D03*
Y1042434D03*
X1318054Y1032821D03*
Y1039230D03*
Y1045639D03*
X1319903Y1036026D03*
Y1042434D03*
X1321753Y1032821D03*
Y1039230D03*
Y1045639D03*
X1323603Y1048842D03*
X1325454Y1052047D03*
X1327303Y1048842D03*
X1329153Y1052047D03*
X1331003Y1048842D03*
X1316203D03*
X1318054Y1052047D03*
X1319903Y1048842D03*
X1321753Y1052047D03*
X1323603Y1055251D03*
Y1061660D03*
X1325454Y1058455D03*
X1327303Y1055251D03*
Y1061660D03*
X1329153Y1058455D03*
X1331003Y1055251D03*
Y1061660D03*
X1316203Y1055251D03*
Y1061660D03*
X1318054Y1058455D03*
X1319903Y1055251D03*
Y1061660D03*
X1321753Y1058455D03*
X1323603Y1068068D03*
Y1074477D03*
X1325454Y1064864D03*
Y1071273D03*
Y1077681D03*
X1327303Y1068068D03*
Y1074477D03*
X1329153Y1064864D03*
Y1071273D03*
Y1077681D03*
X1331003Y1068068D03*
Y1074477D03*
X1316203Y1068068D03*
Y1074477D03*
X1318054Y1064864D03*
Y1071273D03*
Y1077681D03*
X1319903Y1068068D03*
Y1074477D03*
X1321753Y1064864D03*
Y1071273D03*
Y1077681D03*
X1323603Y1080885D03*
X1327303D03*
X1331003D03*
X1316203D03*
X1319903D03*
X1323603Y1087294D03*
Y1093703D03*
X1325454Y1084090D03*
Y1090498D03*
X1327303Y1087294D03*
Y1093703D03*
X1329153Y1084090D03*
Y1090498D03*
X1331003Y1087294D03*
Y1093703D03*
X1316203Y1087294D03*
Y1093703D03*
X1318054Y1084090D03*
Y1090498D03*
X1319903Y1087294D03*
Y1093703D03*
X1321753Y1084090D03*
Y1090498D03*
X1323603Y1100111D03*
Y1106520D03*
Y1112929D03*
X1325454Y1096907D03*
Y1103316D03*
Y1109724D03*
X1327303Y1100111D03*
Y1106520D03*
Y1112929D03*
X1329153Y1096907D03*
Y1103316D03*
Y1109724D03*
X1331003Y1100111D03*
Y1106520D03*
Y1112929D03*
X1316203Y1100111D03*
Y1106520D03*
Y1112929D03*
X1318054Y1096907D03*
Y1103316D03*
Y1109724D03*
X1319903Y1100111D03*
Y1106520D03*
Y1112929D03*
X1321753Y1096907D03*
Y1103316D03*
Y1109724D03*
X1323603Y1119337D03*
Y1125746D03*
X1325454Y1116133D03*
Y1122541D03*
Y1128950D03*
X1327303Y1119337D03*
Y1125746D03*
X1329153Y1116133D03*
Y1122541D03*
Y1128950D03*
X1331003Y1119337D03*
Y1125746D03*
X1318054Y1116133D03*
X1319903Y1119337D03*
X1321753Y1116133D03*
Y1122541D03*
X1327303Y1132154D03*
X1331003D03*
X1347221Y850286D03*
X1332421D03*
X1334270Y847081D03*
X1336121Y850286D03*
X1337970Y847081D03*
X1339821Y850286D03*
X1341670Y847081D03*
X1343521Y850286D03*
X1345370Y847081D03*
X1347221Y856694D03*
Y863103D03*
X1332421Y856694D03*
Y863103D03*
X1334270Y853490D03*
Y859899D03*
Y866307D03*
X1336121Y856694D03*
Y863103D03*
X1337970Y853490D03*
Y859899D03*
Y866307D03*
X1339821Y856694D03*
Y863103D03*
X1341670Y853490D03*
Y859899D03*
Y866307D03*
X1343521Y856694D03*
Y863103D03*
X1345370Y853490D03*
Y859899D03*
Y866307D03*
X1347221Y869511D03*
X1332421D03*
X1334270Y872716D03*
X1336121Y869511D03*
X1337970Y872716D03*
X1339821Y869511D03*
X1341670Y872716D03*
X1343521Y869511D03*
X1345370Y872716D03*
X1347221Y875920D03*
Y882329D03*
X1332421Y875920D03*
Y882329D03*
X1334270Y879124D03*
X1336121Y875920D03*
Y882329D03*
X1337970Y879124D03*
X1339821Y875920D03*
Y882329D03*
X1341670Y879124D03*
X1343521Y875920D03*
Y882329D03*
X1345370Y879124D03*
X1347221Y888737D03*
Y895146D03*
Y901555D03*
X1332421Y888737D03*
Y895146D03*
Y901555D03*
X1334270Y885533D03*
Y891942D03*
Y898350D03*
X1336121Y888737D03*
Y895146D03*
Y901555D03*
X1337970Y885533D03*
Y891942D03*
Y898350D03*
X1339821Y888737D03*
Y895146D03*
Y901555D03*
X1341670Y885533D03*
Y891942D03*
Y898350D03*
X1343521Y888737D03*
Y895146D03*
Y901555D03*
X1345370Y885533D03*
Y891942D03*
Y898350D03*
X1347221Y907963D03*
Y914372D03*
X1332421Y907963D03*
Y914372D03*
X1334270Y904759D03*
Y911167D03*
Y917576D03*
X1336121Y907963D03*
Y914372D03*
X1337970Y904759D03*
Y911167D03*
Y917576D03*
X1339821Y907963D03*
Y914372D03*
X1341670Y904759D03*
Y911167D03*
Y917576D03*
X1343521Y907963D03*
Y914372D03*
X1345370Y904759D03*
Y911167D03*
Y917576D03*
X1347221Y920780D03*
Y927189D03*
X1332421Y920780D03*
Y927189D03*
Y933598D03*
X1334270Y923985D03*
Y930393D03*
X1336121Y920780D03*
Y927189D03*
Y933598D03*
X1337970Y923985D03*
Y930393D03*
X1339821Y920780D03*
Y927189D03*
Y933598D03*
X1341670Y923985D03*
Y930393D03*
X1343521Y920780D03*
Y927189D03*
Y933598D03*
X1345370Y923985D03*
Y930393D03*
X1347221Y933598D03*
Y940006D03*
Y946414D03*
X1332421Y940006D03*
Y946414D03*
X1334270Y936801D03*
Y943210D03*
Y949619D03*
X1336121Y940006D03*
Y946414D03*
X1337970Y936801D03*
Y943210D03*
Y949619D03*
X1339821Y940006D03*
Y946414D03*
X1341670Y936801D03*
Y943210D03*
Y949619D03*
X1343521Y940006D03*
Y946414D03*
X1345370Y936801D03*
Y943210D03*
Y949619D03*
X1347221Y952823D03*
Y959232D03*
X1332421Y952823D03*
Y959232D03*
X1334270Y956027D03*
Y962436D03*
X1336121Y952823D03*
Y959232D03*
X1337970Y956027D03*
Y962436D03*
X1339821Y952823D03*
Y959232D03*
X1341670Y956027D03*
Y962436D03*
X1343521Y952823D03*
Y959232D03*
X1345370Y956027D03*
Y962436D03*
X1347221Y965640D03*
X1332421D03*
X1336121D03*
X1339821D03*
X1343521D03*
X1347221Y972049D03*
Y978457D03*
X1332421Y972049D03*
Y978457D03*
X1334270Y968845D03*
Y975253D03*
Y981662D03*
X1336121Y972049D03*
Y978457D03*
X1337970Y968845D03*
Y975253D03*
Y981662D03*
X1339821Y972049D03*
Y978457D03*
X1341670Y968845D03*
Y975253D03*
Y981662D03*
X1343521Y972049D03*
Y978457D03*
X1345370Y968845D03*
Y975253D03*
Y981662D03*
X1347221Y984866D03*
X1332421D03*
X1336121D03*
X1339821D03*
X1343521D03*
X1334703Y997574D03*
X1338403D03*
X1342103D03*
X1345803D03*
X1332854Y1000778D03*
Y1007187D03*
Y1013595D03*
X1334703Y1003983D03*
Y1010391D03*
X1336554Y1000778D03*
Y1007187D03*
Y1013595D03*
X1338403Y1003983D03*
Y1010391D03*
X1340254Y1000778D03*
Y1007187D03*
Y1013595D03*
X1342103Y1003983D03*
Y1010391D03*
X1343954Y1000778D03*
Y1007187D03*
Y1013595D03*
X1345803Y1003983D03*
Y1010391D03*
X1332854Y1020004D03*
X1334703Y1016800D03*
Y1023208D03*
X1336554Y1020004D03*
X1338403Y1016800D03*
Y1023208D03*
X1340254Y1020004D03*
X1342103Y1016800D03*
Y1023208D03*
X1343954Y1020004D03*
X1345803Y1016800D03*
Y1023208D03*
X1332854Y1026413D03*
X1334703Y1029617D03*
X1336554Y1026413D03*
X1338403Y1029617D03*
X1340254Y1026413D03*
X1342103Y1029617D03*
X1343954Y1026413D03*
X1345803Y1029617D03*
X1332854Y1032821D03*
Y1039230D03*
Y1045639D03*
X1334703Y1036026D03*
Y1042434D03*
X1336554Y1032821D03*
Y1039230D03*
Y1045639D03*
X1338403Y1036026D03*
Y1042434D03*
X1340254Y1032821D03*
Y1039230D03*
Y1045639D03*
X1342103Y1036026D03*
Y1042434D03*
X1343954Y1032821D03*
Y1039230D03*
Y1045639D03*
X1345803Y1036026D03*
Y1042434D03*
X1332854Y1052047D03*
X1334703Y1048842D03*
X1336554Y1052047D03*
X1338403Y1048842D03*
X1340254Y1052047D03*
X1342103Y1048842D03*
X1343954Y1052047D03*
X1345803Y1048842D03*
X1332854Y1058455D03*
X1334703Y1055251D03*
Y1061660D03*
X1336554Y1058455D03*
X1338403Y1055251D03*
Y1061660D03*
X1340254Y1058455D03*
X1342103Y1055251D03*
Y1061660D03*
X1343954Y1058455D03*
X1345803Y1055251D03*
Y1061660D03*
X1332854Y1064864D03*
Y1071273D03*
Y1077681D03*
X1334703Y1068068D03*
Y1074477D03*
X1336554Y1064864D03*
Y1071273D03*
Y1077681D03*
X1338403Y1068068D03*
Y1074477D03*
X1340254Y1064864D03*
Y1071273D03*
Y1077681D03*
X1342103Y1068068D03*
Y1074477D03*
X1343954Y1064864D03*
Y1071273D03*
Y1077681D03*
X1345803Y1068068D03*
Y1074477D03*
X1334703Y1080885D03*
X1338403D03*
X1342103D03*
X1345803D03*
X1332854Y1084090D03*
Y1090498D03*
X1334703Y1087294D03*
Y1093703D03*
X1336554Y1084090D03*
Y1090498D03*
X1338403Y1087294D03*
Y1093703D03*
X1340254Y1084090D03*
Y1090498D03*
X1342103Y1087294D03*
Y1093703D03*
X1343954Y1084090D03*
Y1090498D03*
X1345803Y1087294D03*
Y1093703D03*
X1332854Y1096907D03*
Y1103316D03*
Y1109724D03*
X1334703Y1100111D03*
Y1106520D03*
Y1112929D03*
X1336554Y1096907D03*
Y1103316D03*
Y1109724D03*
X1338403Y1100111D03*
Y1106520D03*
Y1112929D03*
X1340254Y1096907D03*
Y1103316D03*
Y1109724D03*
X1342103Y1100111D03*
Y1106520D03*
Y1112929D03*
X1343954Y1096907D03*
Y1103316D03*
Y1109724D03*
X1345803Y1100111D03*
Y1106520D03*
Y1112929D03*
X1332854Y1116133D03*
Y1122541D03*
Y1128950D03*
X1334703Y1119337D03*
Y1125746D03*
X1336554Y1116133D03*
Y1122541D03*
Y1128950D03*
X1338403Y1119337D03*
Y1125746D03*
X1340254Y1116133D03*
Y1122541D03*
Y1128950D03*
X1342103Y1119337D03*
Y1125746D03*
X1343954Y1116133D03*
Y1122541D03*
Y1128950D03*
X1345803Y1119337D03*
Y1125746D03*
X1334703Y1132154D03*
X1336554Y1135359D03*
X1338403Y1132154D03*
X1340254Y1135359D03*
X1342103Y1132154D03*
X1343954Y1135359D03*
X1345803Y1132154D03*
X1352770Y847081D03*
X1354621Y850286D03*
X1356470Y847081D03*
X1358321Y850286D03*
X1360170Y847081D03*
X1362021Y850286D03*
X1349070Y847081D03*
X1350921Y850286D03*
X1352770Y853490D03*
Y859899D03*
Y866307D03*
X1354621Y856694D03*
Y863103D03*
X1356470Y853490D03*
Y859899D03*
Y866307D03*
X1358321Y856694D03*
Y863103D03*
X1360170Y853490D03*
Y859899D03*
Y866307D03*
X1362021Y856694D03*
Y863103D03*
X1349070Y853490D03*
Y859899D03*
Y866307D03*
X1350921Y856694D03*
Y863103D03*
X1352770Y872716D03*
X1354621Y869511D03*
X1356470Y872716D03*
X1358321Y869511D03*
X1360170Y872716D03*
X1362021Y869511D03*
X1349070Y872716D03*
X1350921Y869511D03*
X1352770Y879124D03*
X1354621Y875920D03*
Y882329D03*
X1356470Y879124D03*
X1358321Y875920D03*
Y882329D03*
X1360170Y879124D03*
X1362021Y875920D03*
Y882329D03*
X1349070Y879124D03*
X1350921Y875920D03*
Y882329D03*
X1352770Y885533D03*
Y891942D03*
Y898350D03*
X1354621Y888737D03*
Y895146D03*
Y901555D03*
X1356470Y885533D03*
Y891942D03*
Y898350D03*
X1358321Y888737D03*
Y895146D03*
Y901555D03*
X1360170Y885533D03*
Y891942D03*
Y898350D03*
X1362021Y888737D03*
Y895146D03*
Y901555D03*
X1349070Y885533D03*
Y891942D03*
Y898350D03*
X1350921Y888737D03*
Y895146D03*
Y901555D03*
X1352770Y904759D03*
Y911167D03*
Y917576D03*
X1354621Y907963D03*
Y914372D03*
X1356470Y904759D03*
Y911167D03*
Y917576D03*
X1358321Y907963D03*
Y914372D03*
X1360170Y904759D03*
Y911167D03*
Y917576D03*
X1362021Y907963D03*
Y914372D03*
X1349070Y904759D03*
Y911167D03*
Y917576D03*
X1350921Y907963D03*
Y914372D03*
X1352770Y923985D03*
Y930393D03*
X1354621Y920780D03*
Y927189D03*
X1356470Y923985D03*
Y930393D03*
X1358321Y920780D03*
Y927189D03*
X1360170Y923985D03*
Y930393D03*
X1362021Y920780D03*
Y927189D03*
X1349070Y923985D03*
Y930393D03*
X1350921Y920780D03*
Y927189D03*
X1354621Y933598D03*
X1358321D03*
X1362021D03*
X1350921D03*
X1352770Y936801D03*
Y943210D03*
Y949619D03*
X1354621Y940006D03*
Y946414D03*
X1356470Y936801D03*
Y943210D03*
Y949619D03*
X1358321Y940006D03*
Y946414D03*
X1360170Y936801D03*
Y943210D03*
Y949619D03*
X1362021Y940006D03*
Y946414D03*
X1349070Y936801D03*
Y943210D03*
Y949619D03*
X1350921Y940006D03*
Y946414D03*
X1352770Y956027D03*
Y962436D03*
X1354621Y952823D03*
Y959232D03*
X1356470Y956027D03*
Y962436D03*
X1358321Y952823D03*
Y959232D03*
X1360170Y956027D03*
Y962436D03*
X1362021Y952823D03*
Y959232D03*
X1349070Y956027D03*
Y962436D03*
X1350921Y952823D03*
Y959232D03*
X1354621Y965640D03*
X1358321D03*
X1362021D03*
X1350921D03*
X1352770Y968845D03*
Y975253D03*
Y981662D03*
X1354621Y972049D03*
Y978457D03*
X1356470Y968845D03*
Y975253D03*
Y981662D03*
X1358321Y972049D03*
Y978457D03*
X1360170Y968845D03*
Y975253D03*
Y981662D03*
X1362021Y972049D03*
Y978457D03*
X1349070Y968845D03*
Y975253D03*
Y981662D03*
X1350921Y972049D03*
Y978457D03*
X1354621Y984866D03*
X1358321D03*
X1362021D03*
X1350921D03*
X1353203Y997574D03*
X1356903D03*
X1360603D03*
X1349503D03*
X1353203Y1003983D03*
Y1010391D03*
X1355054Y1000778D03*
Y1007187D03*
Y1013595D03*
X1356903Y1003983D03*
Y1010391D03*
X1358754Y1000778D03*
Y1007187D03*
Y1013595D03*
X1360603Y1003983D03*
Y1010391D03*
X1362454Y1000778D03*
Y1007187D03*
Y1013595D03*
X1347654Y1000778D03*
Y1007187D03*
Y1013595D03*
X1349503Y1003983D03*
Y1010391D03*
X1351354Y1000778D03*
Y1007187D03*
Y1013595D03*
X1353203Y1016800D03*
X1355054Y1020004D03*
X1356903Y1016800D03*
X1358754Y1020004D03*
X1360603Y1016800D03*
X1362454Y1020004D03*
X1347654D03*
X1349503Y1016800D03*
X1351354Y1020004D03*
X1353203Y1023208D03*
Y1029617D03*
X1355054Y1026413D03*
X1356903Y1023208D03*
Y1029617D03*
X1358754Y1026413D03*
X1360603Y1023208D03*
Y1029617D03*
X1362454Y1026413D03*
X1347654D03*
X1349503Y1023208D03*
Y1029617D03*
X1351354Y1026413D03*
X1353203Y1036026D03*
Y1042434D03*
X1355054Y1032821D03*
Y1039230D03*
Y1045639D03*
X1356903Y1036026D03*
Y1042434D03*
X1358754Y1032821D03*
Y1039230D03*
Y1045639D03*
X1360603Y1036026D03*
Y1042434D03*
X1362454Y1032821D03*
Y1039230D03*
Y1045639D03*
X1347654Y1032821D03*
Y1039230D03*
Y1045639D03*
X1349503Y1036026D03*
Y1042434D03*
X1351354Y1032821D03*
Y1039230D03*
Y1045639D03*
X1353203Y1048842D03*
X1355054Y1052047D03*
X1356903Y1048842D03*
X1358754Y1052047D03*
X1360603Y1048842D03*
X1362454Y1052047D03*
X1347654D03*
X1349503Y1048842D03*
X1351354Y1052047D03*
X1353203Y1055251D03*
Y1061660D03*
X1355054Y1058455D03*
X1356903Y1055251D03*
Y1061660D03*
X1358754Y1058455D03*
X1360603Y1055251D03*
Y1061660D03*
X1362454Y1058455D03*
X1347654D03*
X1349503Y1055251D03*
Y1061660D03*
X1351354Y1058455D03*
X1353203Y1068068D03*
Y1074477D03*
X1355054Y1064864D03*
Y1071273D03*
Y1077681D03*
X1356903Y1068068D03*
Y1074477D03*
X1358754Y1064864D03*
Y1071273D03*
Y1077681D03*
X1360603Y1068068D03*
Y1074477D03*
X1362454Y1064864D03*
Y1071273D03*
Y1077681D03*
X1347654Y1064864D03*
Y1071273D03*
Y1077681D03*
X1349503Y1068068D03*
Y1074477D03*
X1351354Y1064864D03*
Y1071273D03*
Y1077681D03*
X1353203Y1080885D03*
X1356903D03*
X1360603D03*
X1349503D03*
X1353203Y1087294D03*
Y1093703D03*
X1355054Y1084090D03*
Y1090498D03*
X1356903Y1087294D03*
Y1093703D03*
X1358754Y1084090D03*
Y1090498D03*
X1360603Y1087294D03*
Y1093703D03*
X1362454Y1084090D03*
Y1090498D03*
X1347654Y1084090D03*
Y1090498D03*
X1349503Y1087294D03*
Y1093703D03*
X1351354Y1084090D03*
Y1090498D03*
X1353203Y1100111D03*
Y1106520D03*
X1355054Y1096907D03*
Y1103316D03*
Y1109724D03*
X1356903Y1100111D03*
Y1106520D03*
X1358754Y1096907D03*
Y1103316D03*
Y1109724D03*
X1360603Y1100111D03*
Y1106520D03*
X1362454Y1096907D03*
Y1103316D03*
Y1109724D03*
X1347654Y1096907D03*
Y1103316D03*
Y1109724D03*
X1349503Y1100111D03*
Y1106520D03*
X1351354Y1096907D03*
Y1103316D03*
Y1109724D03*
X1353203Y1112929D03*
X1356903D03*
X1360603D03*
X1349503D03*
X1353203Y1119337D03*
Y1125746D03*
X1355054Y1116133D03*
Y1122541D03*
Y1128950D03*
X1356903Y1119337D03*
Y1125746D03*
X1358754Y1116133D03*
Y1122541D03*
Y1128950D03*
X1360603Y1119337D03*
Y1125746D03*
X1362454Y1116133D03*
Y1122541D03*
Y1128950D03*
X1347654Y1116133D03*
Y1122541D03*
Y1128950D03*
X1349503Y1119337D03*
Y1125746D03*
X1351354Y1116133D03*
Y1122541D03*
Y1128950D03*
X1353203Y1132154D03*
X1355054Y1135359D03*
X1356903Y1132154D03*
X1358754Y1135359D03*
X1360603Y1132154D03*
X1362454Y1135359D03*
X1347654D03*
X1349503Y1132154D03*
X1351354Y1135359D03*
X1363870Y847081D03*
X1365721Y850286D03*
X1367570Y847081D03*
X1369421Y850286D03*
X1371270Y847081D03*
X1373121Y850286D03*
X1374970Y847081D03*
X1376821Y850286D03*
X1378670Y847081D03*
X1363870Y853490D03*
Y859899D03*
Y866307D03*
X1365721Y856694D03*
Y863103D03*
X1367570Y853490D03*
Y859899D03*
Y866307D03*
X1369421Y856694D03*
Y863103D03*
X1371270Y853490D03*
Y859899D03*
Y866307D03*
X1373121Y856694D03*
Y863103D03*
X1374970Y853490D03*
Y859899D03*
Y866307D03*
X1376821Y856694D03*
Y863103D03*
X1378670Y853490D03*
Y859899D03*
Y866307D03*
X1363870Y872716D03*
X1365721Y869511D03*
X1367570Y872716D03*
X1369421Y869511D03*
X1371270Y872716D03*
X1373121Y869511D03*
X1374970Y872716D03*
X1376821Y869511D03*
X1378670Y872716D03*
X1363870Y879124D03*
X1365721Y875920D03*
Y882329D03*
X1367570Y879124D03*
X1369421Y875920D03*
Y882329D03*
X1371270Y879124D03*
X1373121Y875920D03*
Y882329D03*
X1374970Y879124D03*
X1376821Y875920D03*
Y882329D03*
X1378670Y879124D03*
X1363870Y885533D03*
Y891942D03*
Y898350D03*
X1365721Y888737D03*
Y895146D03*
Y901555D03*
X1367570Y885533D03*
Y891942D03*
Y898350D03*
X1369421Y888737D03*
Y895146D03*
Y901555D03*
X1371270Y885533D03*
Y891942D03*
Y898350D03*
X1373121Y888737D03*
Y895146D03*
Y901555D03*
X1374970Y885533D03*
Y891942D03*
Y898350D03*
X1376821Y888737D03*
Y895146D03*
Y901555D03*
X1378670Y885533D03*
Y891942D03*
Y898350D03*
X1363870Y904759D03*
Y911167D03*
Y917576D03*
X1365721Y907963D03*
Y914372D03*
X1367570Y904759D03*
Y911167D03*
Y917576D03*
X1369421Y907963D03*
Y914372D03*
X1371270Y904759D03*
Y911167D03*
Y917576D03*
X1373121Y907963D03*
Y914372D03*
X1374970Y904759D03*
Y911167D03*
Y917576D03*
X1376821Y907963D03*
Y914372D03*
X1378670Y904759D03*
Y911167D03*
Y917576D03*
X1363870Y923985D03*
Y930393D03*
X1365721Y920780D03*
Y927189D03*
X1367570Y923985D03*
Y930393D03*
X1369421Y920780D03*
Y927189D03*
X1371270Y923985D03*
Y930393D03*
X1373121Y920780D03*
Y927189D03*
X1374970Y923985D03*
Y930393D03*
X1376821Y920780D03*
Y927189D03*
X1378670Y923985D03*
Y930393D03*
X1365721Y933598D03*
X1369421D03*
X1373121D03*
X1376821D03*
X1363870Y936801D03*
Y943210D03*
Y949619D03*
X1365721Y940006D03*
Y946414D03*
X1367570Y936801D03*
Y943210D03*
Y949619D03*
X1369421Y940006D03*
Y946414D03*
X1371270Y936801D03*
Y943210D03*
Y949619D03*
X1373121Y940006D03*
Y946414D03*
X1374970Y936801D03*
Y943210D03*
Y949619D03*
X1376821Y940006D03*
Y946414D03*
X1378670Y936801D03*
Y943210D03*
Y949619D03*
X1363870Y956027D03*
Y962436D03*
X1365721Y952823D03*
Y959232D03*
X1367570Y956027D03*
Y962436D03*
X1369421Y952823D03*
Y959232D03*
X1371270Y956027D03*
Y962436D03*
X1373121Y952823D03*
Y959232D03*
X1374970Y956027D03*
Y962436D03*
X1376821Y952823D03*
Y959232D03*
X1378670Y956027D03*
Y962436D03*
X1365721Y965640D03*
X1369421D03*
X1373121D03*
X1376821D03*
X1363870Y968845D03*
Y975253D03*
Y981662D03*
X1365721Y972049D03*
Y978457D03*
X1367570Y968845D03*
Y975253D03*
Y981662D03*
X1369421Y972049D03*
Y978457D03*
X1371270Y968845D03*
Y975253D03*
Y981662D03*
X1373121Y972049D03*
Y978457D03*
X1374970Y968845D03*
Y975253D03*
Y981662D03*
X1376821Y972049D03*
Y978457D03*
X1378670Y968845D03*
Y975253D03*
Y981662D03*
X1365721Y984866D03*
X1369421D03*
X1373121D03*
X1376821D03*
X1364303Y997574D03*
X1368003D03*
X1371703D03*
X1375403D03*
X1379103D03*
X1364303Y1003983D03*
Y1010391D03*
X1366154Y1000778D03*
Y1007187D03*
Y1013595D03*
X1368003Y1003983D03*
Y1010391D03*
X1369854Y1000778D03*
Y1007187D03*
Y1013595D03*
X1371703Y1003983D03*
Y1010391D03*
X1373554Y1000778D03*
Y1007187D03*
Y1013595D03*
X1375403Y1003983D03*
Y1010391D03*
X1377254Y1000778D03*
Y1007187D03*
Y1013595D03*
X1379103Y1003983D03*
Y1010391D03*
X1364303Y1016800D03*
X1366154Y1020004D03*
X1368003Y1016800D03*
X1369854Y1020004D03*
X1371703Y1016800D03*
X1373554Y1020004D03*
X1375403Y1016800D03*
X1377254Y1020004D03*
X1379103Y1016800D03*
X1364303Y1023208D03*
Y1029617D03*
X1366154Y1026413D03*
X1368003Y1023208D03*
Y1029617D03*
X1369854Y1026413D03*
X1371703Y1023208D03*
Y1029617D03*
X1373554Y1026413D03*
X1375403Y1023208D03*
Y1029617D03*
X1377254Y1026413D03*
X1379103Y1023208D03*
Y1029617D03*
X1364303Y1036026D03*
Y1042434D03*
X1366154Y1032821D03*
Y1039230D03*
Y1045639D03*
X1368003Y1036026D03*
Y1042434D03*
X1369854Y1032821D03*
Y1039230D03*
Y1045639D03*
X1371703Y1036026D03*
Y1042434D03*
X1373554Y1032821D03*
Y1039230D03*
Y1045639D03*
X1375403Y1036026D03*
Y1042434D03*
X1377254Y1032821D03*
Y1039230D03*
Y1045639D03*
X1379103Y1036026D03*
Y1042434D03*
X1364303Y1048842D03*
X1366154Y1052047D03*
X1368003Y1048842D03*
X1369854Y1052047D03*
X1371703Y1048842D03*
X1373554Y1052047D03*
X1375403Y1048842D03*
X1377254Y1052047D03*
X1379103Y1048842D03*
X1364303Y1055251D03*
Y1061660D03*
X1366154Y1058455D03*
X1368003Y1055251D03*
Y1061660D03*
X1369854Y1058455D03*
X1371703Y1055251D03*
Y1061660D03*
X1373554Y1058455D03*
X1375403Y1055251D03*
Y1061660D03*
X1377254Y1058455D03*
X1379103Y1055251D03*
Y1061660D03*
X1364303Y1068068D03*
Y1074477D03*
X1366154Y1064864D03*
Y1071273D03*
Y1077681D03*
X1368003Y1068068D03*
Y1074477D03*
X1369854Y1064864D03*
Y1071273D03*
Y1077681D03*
X1371703Y1068068D03*
Y1074477D03*
X1373554Y1064864D03*
Y1071273D03*
Y1077681D03*
X1375403Y1068068D03*
Y1074477D03*
X1377254Y1064864D03*
Y1071273D03*
Y1077681D03*
X1379103Y1068068D03*
Y1074477D03*
X1364303Y1080885D03*
X1368003D03*
X1371703D03*
X1375403D03*
X1379103D03*
X1364303Y1087294D03*
Y1093703D03*
X1366154Y1084090D03*
Y1090498D03*
X1368003Y1087294D03*
Y1093703D03*
X1369854Y1084090D03*
Y1090498D03*
X1371703Y1087294D03*
Y1093703D03*
X1373554Y1084090D03*
Y1090498D03*
X1375403Y1087294D03*
Y1093703D03*
X1377254Y1084090D03*
Y1090498D03*
X1379103Y1087294D03*
Y1093703D03*
X1364303Y1100111D03*
Y1106520D03*
X1366154Y1096907D03*
Y1103316D03*
Y1109724D03*
X1368003Y1100111D03*
Y1106520D03*
X1369854Y1096907D03*
Y1103316D03*
Y1109724D03*
X1371703Y1100111D03*
Y1106520D03*
X1373554Y1096907D03*
Y1103316D03*
Y1109724D03*
X1375403Y1100111D03*
Y1106520D03*
X1377254Y1096907D03*
Y1103316D03*
Y1109724D03*
X1379103Y1100111D03*
Y1106520D03*
X1364303Y1112929D03*
X1368003D03*
X1371703D03*
X1375403D03*
X1379103D03*
X1364303Y1119337D03*
Y1125746D03*
X1366154Y1116133D03*
Y1122541D03*
Y1128950D03*
X1368003Y1119337D03*
Y1125746D03*
X1369854Y1116133D03*
Y1122541D03*
Y1128950D03*
X1371703Y1119337D03*
Y1125746D03*
X1373554Y1116133D03*
Y1122541D03*
Y1128950D03*
X1375403Y1119337D03*
Y1125746D03*
X1377254Y1116133D03*
Y1122541D03*
Y1128950D03*
X1379103Y1119337D03*
Y1125746D03*
X1364303Y1132154D03*
X1366154Y1135359D03*
X1368003Y1132154D03*
X1369854Y1135359D03*
X1371703Y1132154D03*
X1373554Y1135359D03*
X1375403Y1132154D03*
X1377254Y1135359D03*
X1379103Y1132154D03*
X1382370Y847081D03*
X1384221Y850286D03*
X1386070Y847081D03*
X1387921Y850286D03*
X1389770Y847081D03*
X1391621Y850286D03*
X1393470Y847081D03*
X1395321Y850286D03*
X1380521D03*
X1382370Y853490D03*
Y859899D03*
Y866307D03*
X1384221Y856694D03*
Y863103D03*
X1386070Y853490D03*
Y859899D03*
Y866307D03*
X1387921Y856694D03*
Y863103D03*
X1389770Y853490D03*
Y859899D03*
Y866307D03*
X1391621Y856694D03*
Y863103D03*
X1393470Y853490D03*
Y859899D03*
Y866307D03*
X1395321Y856694D03*
Y863103D03*
X1380521Y856694D03*
Y863103D03*
X1382370Y872716D03*
X1384221Y869511D03*
X1386070Y872716D03*
X1387921Y869511D03*
X1389770Y872716D03*
X1391621Y869511D03*
X1393470Y872716D03*
X1395321Y869511D03*
X1380521D03*
X1382370Y879124D03*
X1384221Y875920D03*
Y882329D03*
X1386070Y879124D03*
X1387921Y875920D03*
Y882329D03*
X1389770Y879124D03*
X1391621Y875920D03*
Y882329D03*
X1393470Y879124D03*
X1395321Y875920D03*
Y882329D03*
X1380521Y875920D03*
Y882329D03*
X1382370Y885533D03*
Y891942D03*
Y898350D03*
X1384221Y888737D03*
Y895146D03*
Y901555D03*
X1386070Y885533D03*
Y891942D03*
Y898350D03*
X1387921Y888737D03*
Y895146D03*
Y901555D03*
X1389770Y885533D03*
Y891942D03*
Y898350D03*
X1391621Y888737D03*
Y895146D03*
Y901555D03*
X1393470Y885533D03*
Y891942D03*
Y898350D03*
X1395321Y888737D03*
Y895146D03*
Y901555D03*
X1380521Y888737D03*
Y895146D03*
Y901555D03*
X1382370Y904759D03*
Y911167D03*
Y917576D03*
X1384221Y907963D03*
Y914372D03*
X1386070Y904759D03*
Y911167D03*
Y917576D03*
X1387921Y907963D03*
Y914372D03*
X1389770Y904759D03*
Y911167D03*
Y917576D03*
X1391621Y907963D03*
Y914372D03*
X1393470Y904759D03*
Y911167D03*
Y917576D03*
X1395321Y907963D03*
Y914372D03*
X1380521Y907963D03*
Y914372D03*
X1382370Y923985D03*
X1384221Y920780D03*
X1386070Y923985D03*
X1387921Y920780D03*
X1389770Y923985D03*
X1391621Y920780D03*
X1393470Y923985D03*
X1395321Y920780D03*
X1380521D03*
X1382803Y1042434D03*
X1384654Y1039230D03*
Y1045639D03*
X1386503Y1042434D03*
X1388354Y1039230D03*
Y1045639D03*
X1390203Y1042434D03*
X1392054Y1039230D03*
Y1045639D03*
X1393903Y1042434D03*
X1395754Y1039230D03*
Y1045639D03*
X1380954Y1039230D03*
Y1045639D03*
X1382803Y1048842D03*
X1384654Y1052047D03*
X1386503Y1048842D03*
X1388354Y1052047D03*
X1390203Y1048842D03*
X1392054Y1052047D03*
X1393903Y1048842D03*
X1395754Y1052047D03*
X1380954D03*
X1382803Y1055251D03*
Y1061660D03*
X1384654Y1058455D03*
X1386503Y1055251D03*
Y1061660D03*
X1388354Y1058455D03*
X1390203Y1055251D03*
Y1061660D03*
X1392054Y1058455D03*
X1393903Y1055251D03*
Y1061660D03*
X1395754Y1058455D03*
X1380954D03*
X1382803Y1068068D03*
Y1074477D03*
X1384654Y1064864D03*
Y1071273D03*
Y1077681D03*
X1386503Y1068068D03*
Y1074477D03*
X1388354Y1064864D03*
Y1071273D03*
Y1077681D03*
X1390203Y1068068D03*
Y1074477D03*
X1392054Y1064864D03*
Y1071273D03*
Y1077681D03*
X1393903Y1068068D03*
Y1074477D03*
X1395754Y1064864D03*
Y1071273D03*
Y1077681D03*
X1380954Y1064864D03*
Y1071273D03*
Y1077681D03*
X1382803Y1080885D03*
X1386503D03*
X1390203D03*
X1393903D03*
X1382803Y1087294D03*
Y1093703D03*
X1384654Y1084090D03*
Y1090498D03*
X1386503Y1087294D03*
Y1093703D03*
X1388354Y1084090D03*
Y1090498D03*
X1390203Y1087294D03*
Y1093703D03*
X1392054Y1084090D03*
Y1090498D03*
X1393903Y1087294D03*
Y1093703D03*
X1395754Y1084090D03*
Y1090498D03*
X1380954Y1084090D03*
Y1090498D03*
X1382803Y1100111D03*
Y1106520D03*
X1384654Y1096907D03*
Y1103316D03*
Y1109724D03*
X1386503Y1100111D03*
Y1106520D03*
X1388354Y1096907D03*
Y1103316D03*
Y1109724D03*
X1390203Y1100111D03*
Y1106520D03*
X1392054Y1096907D03*
Y1103316D03*
Y1109724D03*
X1393903Y1100111D03*
Y1106520D03*
X1395754Y1096907D03*
Y1103316D03*
Y1109724D03*
X1380954Y1096907D03*
Y1103316D03*
Y1109724D03*
X1382803Y1112929D03*
X1386503D03*
X1390203D03*
X1393903D03*
X1382803Y1119337D03*
Y1125746D03*
X1384654Y1116133D03*
Y1122541D03*
Y1128950D03*
X1386503Y1119337D03*
Y1125746D03*
X1388354Y1116133D03*
Y1122541D03*
Y1128950D03*
X1390203Y1119337D03*
Y1125746D03*
X1392054Y1116133D03*
Y1122541D03*
Y1128950D03*
X1393903Y1119337D03*
Y1125746D03*
X1395754Y1116133D03*
Y1122541D03*
Y1128950D03*
X1380954Y1116133D03*
Y1122541D03*
Y1128950D03*
X1382803Y1132154D03*
X1384654Y1135359D03*
X1386503Y1132154D03*
X1388354Y1135359D03*
X1390203Y1132154D03*
X1392054Y1135359D03*
X1393903Y1132154D03*
X1395754Y1135359D03*
X1380954D03*
X1397170Y847081D03*
X1399021Y850286D03*
X1400870Y847081D03*
X1402721Y850286D03*
X1406421D03*
X1410121D03*
X1397170Y853490D03*
Y859899D03*
Y866307D03*
X1399021Y856694D03*
Y863103D03*
X1400870Y853490D03*
Y859899D03*
Y866307D03*
X1402721Y856694D03*
Y863103D03*
X1404570Y853490D03*
Y859899D03*
Y866307D03*
X1406421Y856694D03*
Y863103D03*
X1408270Y853490D03*
Y859899D03*
Y866307D03*
X1410121Y856694D03*
Y863103D03*
X1411971Y853490D03*
Y859899D03*
Y866307D03*
X1397170Y872716D03*
X1399021Y869511D03*
X1400870Y872716D03*
X1402721Y869511D03*
X1404570Y872716D03*
X1406421Y869511D03*
X1408270Y872716D03*
X1410121Y869511D03*
X1411971Y872716D03*
X1397170Y879124D03*
X1399021Y875920D03*
Y882329D03*
X1400870Y879124D03*
X1402721Y875920D03*
Y882329D03*
X1404570Y879124D03*
X1406421Y875920D03*
Y882329D03*
X1408270Y879124D03*
X1410121Y875920D03*
Y882329D03*
X1411971Y879124D03*
X1397170Y885533D03*
Y891942D03*
Y898350D03*
X1399021Y888737D03*
Y895146D03*
Y901555D03*
X1400870Y885533D03*
Y891942D03*
Y898350D03*
X1402721Y888737D03*
Y895146D03*
Y901555D03*
X1404570Y885533D03*
Y891942D03*
Y898350D03*
X1406421Y888737D03*
Y895146D03*
Y901555D03*
X1408270Y885533D03*
Y891942D03*
Y898350D03*
X1410121Y888737D03*
Y895146D03*
Y901555D03*
X1411971Y885533D03*
Y891942D03*
Y898350D03*
Y904759D03*
X1397170D03*
Y911167D03*
Y917576D03*
X1399021Y907963D03*
Y914372D03*
X1400870Y904759D03*
Y911167D03*
Y917576D03*
X1402721Y907963D03*
Y914372D03*
X1404570Y904759D03*
Y911167D03*
Y917576D03*
X1406421Y907963D03*
Y914372D03*
X1408270Y904759D03*
Y911167D03*
Y917576D03*
X1410121Y907963D03*
Y914372D03*
X1411971Y911167D03*
Y917576D03*
X1397170Y923985D03*
X1399021Y920780D03*
X1400870Y923985D03*
X1402721Y920780D03*
X1404570Y923985D03*
X1406421Y920780D03*
Y927189D03*
X1408270Y923985D03*
Y930393D03*
X1410121Y920780D03*
Y927189D03*
X1411971Y923985D03*
Y930393D03*
X1406421Y933598D03*
X1410121D03*
X1406421Y940006D03*
Y946414D03*
X1408270Y936801D03*
Y943210D03*
Y949619D03*
X1410121Y940006D03*
Y946414D03*
X1411971Y936801D03*
Y943210D03*
Y949619D03*
X1406421Y952823D03*
Y959232D03*
X1408270Y956027D03*
Y962436D03*
X1410121Y952823D03*
Y959232D03*
X1411971Y956027D03*
Y962436D03*
X1406421Y965640D03*
X1410121D03*
X1406421Y972049D03*
Y978457D03*
X1408270Y968845D03*
Y975253D03*
Y981662D03*
X1410121Y972049D03*
Y978457D03*
X1411971Y968845D03*
Y975253D03*
Y981662D03*
X1406421Y984866D03*
X1410121D03*
X1412403Y997574D03*
X1408703D03*
X1412403Y1003983D03*
Y1010391D03*
X1406853Y1000778D03*
Y1007187D03*
Y1013595D03*
X1408703Y1003983D03*
Y1010391D03*
X1410554Y1000778D03*
Y1007187D03*
Y1013595D03*
X1412403Y1016800D03*
X1406853Y1020004D03*
X1408703Y1016800D03*
X1410554Y1020004D03*
X1412403Y1023208D03*
Y1029617D03*
X1406853Y1026413D03*
X1408703Y1023208D03*
Y1029617D03*
X1410554Y1026413D03*
X1412403Y1036026D03*
Y1042434D03*
X1397603D03*
X1399454Y1039230D03*
Y1045639D03*
X1401303Y1042434D03*
X1403154Y1039230D03*
Y1045639D03*
X1405003Y1042434D03*
X1406853Y1032821D03*
Y1039230D03*
Y1045639D03*
X1408703Y1036026D03*
Y1042434D03*
X1410554Y1032821D03*
Y1039230D03*
Y1045639D03*
X1412403Y1048842D03*
X1397603D03*
X1399454Y1052047D03*
X1401303Y1048842D03*
X1403154Y1052047D03*
X1405003Y1048842D03*
X1406853Y1052047D03*
X1408703Y1048842D03*
X1410554Y1052047D03*
X1412403Y1055251D03*
Y1061660D03*
X1397603Y1055251D03*
Y1061660D03*
X1399454Y1058455D03*
X1401303Y1055251D03*
Y1061660D03*
X1403154Y1058455D03*
X1405003Y1055251D03*
Y1061660D03*
X1406853Y1058455D03*
X1408703Y1055251D03*
Y1061660D03*
X1410554Y1058455D03*
X1412403Y1068068D03*
Y1074477D03*
X1397603Y1068068D03*
Y1074477D03*
X1399454Y1064864D03*
Y1071273D03*
Y1077681D03*
X1401303Y1068068D03*
Y1074477D03*
X1403154Y1064864D03*
Y1071273D03*
Y1077681D03*
X1405003Y1068068D03*
Y1074477D03*
X1406853Y1064864D03*
Y1071273D03*
Y1077681D03*
X1408703Y1068068D03*
Y1074477D03*
X1410554Y1064864D03*
Y1071273D03*
Y1077681D03*
X1412403Y1080885D03*
X1397603D03*
X1401303D03*
X1405003D03*
X1408703D03*
X1412403Y1087294D03*
Y1093703D03*
X1397603Y1087294D03*
Y1093703D03*
X1399454Y1084090D03*
Y1090498D03*
X1401303Y1087294D03*
Y1093703D03*
X1403154Y1084090D03*
Y1090498D03*
X1405003Y1087294D03*
Y1093703D03*
X1406853Y1084090D03*
Y1090498D03*
X1408703Y1087294D03*
Y1093703D03*
X1410554Y1084090D03*
Y1090498D03*
X1412403Y1100111D03*
Y1106520D03*
X1397603Y1100111D03*
Y1106520D03*
X1399454Y1096907D03*
Y1103316D03*
Y1109724D03*
X1401303Y1100111D03*
Y1106520D03*
X1403154Y1096907D03*
Y1103316D03*
Y1109724D03*
X1405003Y1100111D03*
Y1106520D03*
X1406853Y1096907D03*
Y1103316D03*
Y1109724D03*
X1408703Y1100111D03*
Y1106520D03*
X1410554Y1096907D03*
Y1103316D03*
Y1109724D03*
X1412403Y1112929D03*
X1397603D03*
X1401303D03*
X1405003D03*
X1408703D03*
X1412403Y1119337D03*
Y1125746D03*
X1397603Y1119337D03*
Y1125746D03*
X1399454Y1116133D03*
Y1122541D03*
Y1128950D03*
X1401303Y1119337D03*
Y1125746D03*
X1403154Y1116133D03*
Y1122541D03*
Y1128950D03*
X1405003Y1119337D03*
Y1125746D03*
X1406853Y1116133D03*
Y1122541D03*
Y1128950D03*
X1408703Y1119337D03*
Y1125746D03*
X1410554Y1116133D03*
Y1122541D03*
Y1128950D03*
X1412403Y1132154D03*
X1397603D03*
X1399454Y1135359D03*
X1401303Y1132154D03*
X1403154Y1135359D03*
X1405003Y1132154D03*
X1408703D03*
X1413821Y850286D03*
X1417521D03*
X1421221D03*
X1424921D03*
X1428621D03*
X1413821Y856694D03*
Y863103D03*
X1415670Y853490D03*
Y859899D03*
Y866307D03*
X1417521Y856694D03*
Y863103D03*
X1419370Y853490D03*
Y859899D03*
Y866307D03*
X1421221Y856694D03*
Y863103D03*
X1423070Y853490D03*
Y859899D03*
Y866307D03*
X1424921Y856694D03*
Y863103D03*
X1426771Y853490D03*
Y859899D03*
Y866307D03*
X1428621Y856694D03*
Y863103D03*
X1413821Y869511D03*
X1415670Y872716D03*
X1417521Y869511D03*
X1419370Y872716D03*
X1421221Y869511D03*
X1423070Y872716D03*
X1424921Y869511D03*
X1426771Y872716D03*
X1428621Y869511D03*
X1413821Y875920D03*
Y882329D03*
X1415670Y879124D03*
X1417521Y875920D03*
Y882329D03*
X1419370Y879124D03*
X1421221Y875920D03*
Y882329D03*
X1423070Y879124D03*
X1424921Y875920D03*
Y882329D03*
X1426771Y879124D03*
X1428621Y875920D03*
Y882329D03*
X1413821Y888737D03*
Y895146D03*
Y901555D03*
X1415670Y885533D03*
Y891942D03*
Y898350D03*
X1417521Y888737D03*
Y895146D03*
Y901555D03*
X1419370Y885533D03*
Y891942D03*
Y898350D03*
X1421221Y888737D03*
Y895146D03*
Y901555D03*
X1423070Y885533D03*
Y891942D03*
Y898350D03*
X1424921Y888737D03*
Y895146D03*
Y901555D03*
X1426771Y885533D03*
Y891942D03*
Y898350D03*
X1428621Y888737D03*
Y895146D03*
Y901555D03*
X1413821Y907963D03*
Y914372D03*
X1415670Y904759D03*
Y911167D03*
Y917576D03*
X1417521Y907963D03*
Y914372D03*
X1419370Y904759D03*
Y911167D03*
Y917576D03*
X1421221Y907963D03*
Y914372D03*
X1423070Y904759D03*
Y911167D03*
Y917576D03*
X1424921Y907963D03*
Y914372D03*
X1426771Y904759D03*
Y911167D03*
Y917576D03*
X1428621Y907963D03*
Y914372D03*
X1413821Y920780D03*
Y927189D03*
X1415670Y923985D03*
Y930393D03*
X1417521Y920780D03*
Y927189D03*
X1419370Y923985D03*
Y930393D03*
X1421221Y920780D03*
Y927189D03*
X1423070Y923985D03*
Y930393D03*
X1424921Y920780D03*
Y927189D03*
X1426771Y923985D03*
Y930393D03*
X1428621Y920780D03*
X1413821Y933598D03*
X1417521D03*
X1421221D03*
X1424921D03*
X1413821Y940006D03*
Y946414D03*
X1415670Y936801D03*
Y943210D03*
Y949619D03*
X1417521Y940006D03*
Y946414D03*
X1419370Y936801D03*
Y943210D03*
Y949619D03*
X1421221Y940006D03*
Y946414D03*
X1423070Y936801D03*
Y943210D03*
Y949619D03*
X1424921Y940006D03*
Y946414D03*
X1426771Y936801D03*
Y943210D03*
Y949619D03*
X1413821Y952823D03*
Y959232D03*
X1415670Y956027D03*
Y962436D03*
X1417521Y952823D03*
Y959232D03*
X1419370Y956027D03*
Y962436D03*
X1421221Y952823D03*
Y959232D03*
X1423070Y956027D03*
Y962436D03*
X1424921Y952823D03*
Y959232D03*
X1426771Y956027D03*
Y962436D03*
X1413821Y965640D03*
X1417521D03*
X1421221D03*
X1424921D03*
X1413821Y972049D03*
Y978457D03*
X1415670Y968845D03*
Y975253D03*
Y981662D03*
X1417521Y972049D03*
Y978457D03*
X1419370Y968845D03*
Y975253D03*
Y981662D03*
X1421221Y972049D03*
Y978457D03*
X1423070Y968845D03*
Y975253D03*
Y981662D03*
X1424921Y972049D03*
Y978457D03*
X1426771Y968845D03*
Y975253D03*
Y981662D03*
X1413821Y984866D03*
X1417521D03*
X1421221D03*
X1424921D03*
X1416103Y997574D03*
X1419803D03*
X1423503D03*
X1427203D03*
X1414254Y1000778D03*
Y1007187D03*
Y1013595D03*
X1416103Y1003983D03*
Y1010391D03*
X1417954Y1000778D03*
Y1007187D03*
Y1013595D03*
X1419803Y1003983D03*
Y1010391D03*
X1421653Y1000778D03*
Y1007187D03*
Y1013595D03*
X1423503Y1003983D03*
Y1010391D03*
X1425354Y1000778D03*
Y1007187D03*
Y1013595D03*
X1427203Y1003983D03*
Y1010391D03*
X1414254Y1020004D03*
X1416103Y1016800D03*
X1417954Y1020004D03*
X1419803Y1016800D03*
X1421653Y1020004D03*
X1423503Y1016800D03*
X1425354Y1020004D03*
X1427203Y1016800D03*
X1414254Y1026413D03*
X1416103Y1023208D03*
Y1029617D03*
X1417954Y1026413D03*
X1419803Y1023208D03*
Y1029617D03*
X1421653Y1026413D03*
X1423503Y1023208D03*
Y1029617D03*
X1425354Y1026413D03*
X1427203Y1023208D03*
Y1029617D03*
X1414254Y1032821D03*
Y1039230D03*
Y1045639D03*
X1416103Y1036026D03*
Y1042434D03*
X1417954Y1032821D03*
Y1039230D03*
Y1045639D03*
X1419803Y1036026D03*
Y1042434D03*
X1421653Y1032821D03*
Y1039230D03*
Y1045639D03*
X1423503Y1036026D03*
Y1042434D03*
X1425354Y1032821D03*
Y1039230D03*
Y1045639D03*
X1427203Y1036026D03*
Y1042434D03*
X1414254Y1052047D03*
X1416103Y1048842D03*
X1417954Y1052047D03*
X1419803Y1048842D03*
X1421653Y1052047D03*
X1423503Y1048842D03*
X1425354Y1052047D03*
X1427203Y1048842D03*
X1414254Y1058455D03*
X1416103Y1055251D03*
Y1061660D03*
X1417954Y1058455D03*
X1419803Y1055251D03*
Y1061660D03*
X1421653Y1058455D03*
X1423503Y1055251D03*
Y1061660D03*
X1425354Y1058455D03*
X1427203Y1055251D03*
Y1061660D03*
X1414254Y1064864D03*
Y1071273D03*
Y1077681D03*
X1416103Y1068068D03*
Y1074477D03*
X1417954Y1064864D03*
Y1071273D03*
Y1077681D03*
X1419803Y1068068D03*
Y1074477D03*
X1421653Y1064864D03*
Y1071273D03*
Y1077681D03*
X1423503Y1068068D03*
Y1074477D03*
X1425354Y1064864D03*
Y1071273D03*
Y1077681D03*
X1427203Y1068068D03*
Y1074477D03*
X1416103Y1080885D03*
X1419803D03*
X1423503D03*
X1427203D03*
X1414254Y1084090D03*
Y1090498D03*
X1416103Y1087294D03*
Y1093703D03*
X1417954Y1084090D03*
Y1090498D03*
X1419803Y1087294D03*
Y1093703D03*
X1421653Y1084090D03*
Y1090498D03*
X1423503Y1087294D03*
Y1093703D03*
X1425354Y1084090D03*
Y1090498D03*
X1427203Y1087294D03*
Y1093703D03*
X1414254Y1096907D03*
Y1103316D03*
Y1109724D03*
X1416103Y1100111D03*
Y1106520D03*
X1417954Y1096907D03*
Y1103316D03*
Y1109724D03*
X1419803Y1100111D03*
Y1106520D03*
X1421653Y1096907D03*
Y1103316D03*
Y1109724D03*
X1423503Y1100111D03*
Y1106520D03*
X1425354Y1096907D03*
Y1103316D03*
Y1109724D03*
X1427203Y1100111D03*
Y1106520D03*
X1416103Y1112929D03*
X1419803D03*
X1423503D03*
X1427203D03*
X1414254Y1116133D03*
Y1122541D03*
Y1128950D03*
X1416103Y1119337D03*
Y1125746D03*
X1417954Y1116133D03*
Y1122541D03*
Y1128950D03*
X1419803Y1119337D03*
Y1125746D03*
X1421653Y1116133D03*
Y1122541D03*
Y1128950D03*
X1423503Y1119337D03*
Y1125746D03*
X1425354Y1116133D03*
Y1122541D03*
Y1128950D03*
X1427203Y1119337D03*
Y1125746D03*
X1416103Y1132154D03*
X1419803D03*
X1423503D03*
X1427203D03*
X1443421Y850286D03*
X1430470Y847081D03*
X1432321Y850286D03*
X1434170Y847081D03*
X1436021Y850286D03*
X1437870Y847081D03*
X1439721Y850286D03*
X1441570Y847081D03*
X1443421Y856694D03*
Y863103D03*
X1430470Y853490D03*
Y859899D03*
Y866307D03*
X1432321Y856694D03*
Y863103D03*
X1434170Y853490D03*
Y859899D03*
Y866307D03*
X1436021Y856694D03*
Y863103D03*
X1437870Y853490D03*
Y859899D03*
Y866307D03*
X1439721Y856694D03*
Y863103D03*
X1441570Y853490D03*
Y859899D03*
Y866307D03*
X1443421Y869511D03*
X1430470Y872716D03*
X1432321Y869511D03*
X1434170Y872716D03*
X1436021Y869511D03*
X1437870Y872716D03*
X1439721Y869511D03*
X1441570Y872716D03*
X1443421Y875920D03*
Y882329D03*
X1430470Y879124D03*
X1432321Y875920D03*
Y882329D03*
X1434170Y879124D03*
X1436021Y875920D03*
Y882329D03*
X1437870Y879124D03*
X1439721Y875920D03*
Y882329D03*
X1441570Y879124D03*
X1443421Y888737D03*
Y895146D03*
Y901555D03*
X1430470Y885533D03*
Y891942D03*
Y898350D03*
X1432321Y888737D03*
Y895146D03*
Y901555D03*
X1434170Y885533D03*
Y891942D03*
Y898350D03*
X1436021Y888737D03*
Y895146D03*
Y901555D03*
X1437870Y885533D03*
Y891942D03*
Y898350D03*
X1439721Y888737D03*
Y895146D03*
Y901555D03*
X1441570Y885533D03*
Y891942D03*
Y898350D03*
X1443421Y907963D03*
Y914372D03*
X1430470Y904759D03*
Y911167D03*
Y917576D03*
X1432321Y907963D03*
Y914372D03*
X1434170Y904759D03*
Y911167D03*
Y917576D03*
X1436021Y907963D03*
Y914372D03*
X1437870Y904759D03*
Y911167D03*
Y917576D03*
X1439721Y907963D03*
Y914372D03*
X1441570Y904759D03*
Y911167D03*
Y917576D03*
X1443421Y920780D03*
X1430470Y923985D03*
X1432321Y920780D03*
X1434170Y923985D03*
X1436021Y920780D03*
X1437870Y923985D03*
X1439721Y920780D03*
X1441570Y923985D03*
X1443854Y1039230D03*
Y1045639D03*
X1429054Y1039230D03*
Y1045639D03*
X1430903Y1042434D03*
X1432754Y1039230D03*
Y1045639D03*
X1434603Y1042434D03*
X1436454Y1039230D03*
Y1045639D03*
X1438303Y1042434D03*
X1440154Y1039230D03*
Y1045639D03*
X1442003Y1042434D03*
X1443854Y1052047D03*
X1429054D03*
X1430903Y1048842D03*
X1432754Y1052047D03*
X1434603Y1048842D03*
X1436454Y1052047D03*
X1438303Y1048842D03*
X1440154Y1052047D03*
X1442003Y1048842D03*
Y1055251D03*
X1443854Y1058455D03*
X1429054D03*
X1430903Y1055251D03*
Y1061660D03*
X1432754Y1058455D03*
X1434603Y1055251D03*
Y1061660D03*
X1436454Y1058455D03*
X1438303Y1055251D03*
Y1061660D03*
X1440154Y1058455D03*
X1442003Y1061660D03*
X1443854Y1064864D03*
Y1071273D03*
Y1077681D03*
X1429054Y1064864D03*
Y1071273D03*
Y1077681D03*
X1430903Y1068068D03*
Y1074477D03*
X1432754Y1064864D03*
Y1071273D03*
Y1077681D03*
X1434603Y1068068D03*
Y1074477D03*
X1436454Y1064864D03*
Y1071273D03*
Y1077681D03*
X1438303Y1068068D03*
Y1074477D03*
X1440154Y1064864D03*
Y1071273D03*
Y1077681D03*
X1442003Y1068068D03*
Y1074477D03*
X1430903Y1080885D03*
X1434603D03*
X1438303D03*
X1442003D03*
X1443854Y1084090D03*
Y1090498D03*
X1429054Y1084090D03*
Y1090498D03*
X1430903Y1087294D03*
Y1093703D03*
X1432754Y1084090D03*
Y1090498D03*
X1434603Y1087294D03*
Y1093703D03*
X1436454Y1084090D03*
Y1090498D03*
X1438303Y1087294D03*
Y1093703D03*
X1440154Y1084090D03*
Y1090498D03*
X1442003Y1087294D03*
Y1093703D03*
X1443854Y1096907D03*
Y1103316D03*
Y1109724D03*
X1429054Y1096907D03*
Y1103316D03*
Y1109724D03*
X1430903Y1100111D03*
Y1106520D03*
X1432754Y1096907D03*
Y1103316D03*
Y1109724D03*
X1434603Y1100111D03*
Y1106520D03*
X1436454Y1096907D03*
Y1103316D03*
Y1109724D03*
X1438303Y1100111D03*
Y1106520D03*
X1440154Y1096907D03*
Y1103316D03*
Y1109724D03*
X1442003Y1100111D03*
Y1106520D03*
Y1112929D03*
X1430903D03*
X1434603D03*
X1438303D03*
X1443854Y1116133D03*
Y1122541D03*
Y1128950D03*
X1429054Y1116133D03*
Y1122541D03*
Y1128950D03*
X1430903Y1119337D03*
Y1125746D03*
X1432754Y1116133D03*
Y1122541D03*
Y1128950D03*
X1434603Y1119337D03*
Y1125746D03*
X1436454Y1116133D03*
Y1122541D03*
Y1128950D03*
X1438303Y1119337D03*
Y1125746D03*
X1440154Y1116133D03*
Y1122541D03*
Y1128950D03*
X1442003Y1119337D03*
Y1125746D03*
X1443854Y1135359D03*
X1430903Y1132154D03*
X1432754Y1135359D03*
X1434603Y1132154D03*
X1436454Y1135359D03*
X1438303Y1132154D03*
X1440154Y1135359D03*
X1442003Y1132154D03*
X1445270Y847081D03*
X1447121Y850286D03*
X1448970Y847081D03*
X1450821Y850286D03*
X1452670Y847081D03*
X1454521Y850286D03*
X1456370Y847081D03*
X1458221Y850286D03*
X1460070Y847081D03*
X1445270Y853490D03*
Y859899D03*
Y866307D03*
X1447121Y856694D03*
Y863103D03*
X1448970Y853490D03*
Y859899D03*
Y866307D03*
X1450821Y856694D03*
Y863103D03*
X1452670Y853490D03*
Y859899D03*
Y866307D03*
X1454521Y856694D03*
Y863103D03*
X1456370Y853490D03*
Y859899D03*
Y866307D03*
X1458221Y856694D03*
Y863103D03*
X1460070Y853490D03*
Y859899D03*
Y866307D03*
X1445270Y872716D03*
X1447121Y869511D03*
X1448970Y872716D03*
X1450821Y869511D03*
X1452670Y872716D03*
X1454521Y869511D03*
X1456370Y872716D03*
X1458221Y869511D03*
X1460070Y872716D03*
X1445270Y879124D03*
X1447121Y875920D03*
Y882329D03*
X1448970Y879124D03*
X1450821Y875920D03*
Y882329D03*
X1452670Y879124D03*
X1454521Y875920D03*
Y882329D03*
X1456370Y879124D03*
X1458221Y875920D03*
Y882329D03*
X1460070Y879124D03*
X1445270Y885533D03*
Y891942D03*
Y898350D03*
X1447121Y888737D03*
Y895146D03*
Y901555D03*
X1448970Y885533D03*
Y891942D03*
Y898350D03*
X1450821Y888737D03*
Y895146D03*
Y901555D03*
X1452670Y885533D03*
Y891942D03*
Y898350D03*
X1454521Y888737D03*
Y895146D03*
Y901555D03*
X1456370Y885533D03*
Y891942D03*
Y898350D03*
X1458221Y888737D03*
Y895146D03*
Y901555D03*
X1460070Y885533D03*
Y891942D03*
Y898350D03*
X1445270Y904759D03*
Y911167D03*
Y917576D03*
X1447121Y907963D03*
Y914372D03*
X1448970Y904759D03*
Y911167D03*
Y917576D03*
X1450821Y907963D03*
Y914372D03*
X1452670Y904759D03*
Y911167D03*
Y917576D03*
X1454521Y907963D03*
Y914372D03*
X1456370Y904759D03*
Y911167D03*
Y917576D03*
X1458221Y907963D03*
Y914372D03*
X1460070Y904759D03*
Y911167D03*
Y917576D03*
X1445270Y923985D03*
X1447121Y920780D03*
X1448970Y923985D03*
X1450821Y920780D03*
X1452670Y923985D03*
X1454521Y920780D03*
Y927189D03*
X1456370Y923985D03*
Y930393D03*
X1458221Y920780D03*
Y927189D03*
X1460070Y923985D03*
Y930393D03*
X1454521Y933598D03*
X1458221D03*
X1454521Y940006D03*
Y946414D03*
X1456370Y936801D03*
Y943210D03*
Y949619D03*
X1458221Y940006D03*
Y946414D03*
X1460070Y936801D03*
Y943210D03*
Y949619D03*
X1454521Y952823D03*
Y959232D03*
X1456370Y956027D03*
Y962436D03*
X1458221Y952823D03*
Y959232D03*
X1460070Y956027D03*
Y962436D03*
X1454521Y965640D03*
X1458221D03*
X1454521Y972049D03*
Y978457D03*
X1456370Y968845D03*
Y975253D03*
Y981662D03*
X1458221Y972049D03*
Y978457D03*
X1460070Y968845D03*
Y975253D03*
Y981662D03*
X1454521Y984866D03*
X1458221D03*
X1456803Y997574D03*
X1460503D03*
X1454954Y1000778D03*
Y1007187D03*
Y1013595D03*
X1456803Y1003983D03*
Y1010391D03*
X1458654Y1000778D03*
Y1007187D03*
Y1013595D03*
X1460503Y1003983D03*
Y1010391D03*
X1454954Y1020004D03*
X1456803Y1016800D03*
X1458654Y1020004D03*
X1460503Y1016800D03*
X1454954Y1026413D03*
X1456803Y1023208D03*
Y1029617D03*
X1458654Y1026413D03*
X1460503Y1023208D03*
Y1029617D03*
X1445703Y1042434D03*
X1447554Y1039230D03*
Y1045639D03*
X1449403Y1042434D03*
X1451254Y1039230D03*
Y1045639D03*
X1453103Y1042434D03*
X1454954Y1032821D03*
Y1039230D03*
Y1045639D03*
X1456803Y1036026D03*
Y1042434D03*
X1458654Y1032821D03*
Y1039230D03*
Y1045639D03*
X1460503Y1036026D03*
Y1042434D03*
X1445703Y1048842D03*
X1447554Y1052047D03*
X1449403Y1048842D03*
X1451254Y1052047D03*
X1453103Y1048842D03*
X1454954Y1052047D03*
X1456803Y1048842D03*
X1458654Y1052047D03*
X1460503Y1048842D03*
X1445703Y1055251D03*
Y1061660D03*
X1447554Y1058455D03*
X1449403Y1055251D03*
Y1061660D03*
X1451254Y1058455D03*
X1453103Y1055251D03*
Y1061660D03*
X1454954Y1058455D03*
X1456803Y1055251D03*
Y1061660D03*
X1458654Y1058455D03*
X1460503Y1055251D03*
Y1061660D03*
X1445703Y1068068D03*
Y1074477D03*
X1447554Y1064864D03*
Y1071273D03*
Y1077681D03*
X1449403Y1068068D03*
Y1074477D03*
X1451254Y1064864D03*
Y1071273D03*
Y1077681D03*
X1453103Y1068068D03*
Y1074477D03*
X1454954Y1064864D03*
Y1071273D03*
Y1077681D03*
X1456803Y1068068D03*
Y1074477D03*
X1458654Y1064864D03*
Y1071273D03*
Y1077681D03*
X1460503Y1068068D03*
Y1074477D03*
X1445703Y1080885D03*
X1449403D03*
X1453103D03*
X1456803D03*
X1460503D03*
X1445703Y1087294D03*
Y1093703D03*
X1447554Y1084090D03*
Y1090498D03*
X1449403Y1087294D03*
Y1093703D03*
X1451254Y1084090D03*
Y1090498D03*
X1453103Y1087294D03*
Y1093703D03*
X1454954Y1084090D03*
Y1090498D03*
X1456803Y1087294D03*
Y1093703D03*
X1458654Y1084090D03*
Y1090498D03*
X1460503Y1087294D03*
Y1093703D03*
X1445703Y1100111D03*
Y1106520D03*
X1447554Y1096907D03*
Y1103316D03*
Y1109724D03*
X1449403Y1100111D03*
Y1106520D03*
X1451254Y1096907D03*
Y1103316D03*
Y1109724D03*
X1453103Y1100111D03*
Y1106520D03*
X1454954Y1096907D03*
Y1103316D03*
Y1109724D03*
X1456803Y1100111D03*
Y1106520D03*
X1458654Y1096907D03*
Y1103316D03*
Y1109724D03*
X1460503Y1100111D03*
Y1106520D03*
X1445703Y1112929D03*
X1449403D03*
X1453103D03*
X1456803D03*
X1460503D03*
X1445703Y1119337D03*
Y1125746D03*
X1447554Y1116133D03*
Y1122541D03*
Y1128950D03*
X1449403Y1119337D03*
Y1125746D03*
X1451254Y1116133D03*
Y1122541D03*
Y1128950D03*
X1453103Y1119337D03*
Y1125746D03*
X1454954Y1116133D03*
Y1122541D03*
Y1128950D03*
X1456803Y1119337D03*
Y1125746D03*
X1458654Y1116133D03*
Y1122541D03*
Y1128950D03*
X1460503Y1119337D03*
Y1125746D03*
X1445703Y1132154D03*
X1447554Y1135359D03*
X1449403Y1132154D03*
X1451254Y1135359D03*
X1453103Y1132154D03*
X1454954Y1135359D03*
X1456803Y1132154D03*
X1458654Y1135359D03*
X1460503Y1132154D03*
X1473021Y850286D03*
X1474870Y847081D03*
X1476721Y850286D03*
X1461921D03*
X1463770Y847081D03*
X1465621Y850286D03*
X1467470Y847081D03*
X1469321Y850286D03*
X1471170Y847081D03*
X1473021Y856694D03*
Y863103D03*
X1474870Y853490D03*
Y859899D03*
Y866307D03*
X1476721Y856694D03*
Y863103D03*
X1461921Y856694D03*
Y863103D03*
X1463770Y853490D03*
Y859899D03*
Y866307D03*
X1465621Y856694D03*
Y863103D03*
X1467470Y853490D03*
Y859899D03*
Y866307D03*
X1469321Y856694D03*
Y863103D03*
X1471170Y853490D03*
Y859899D03*
Y866307D03*
X1473021Y869511D03*
X1474870Y872716D03*
X1476721Y869511D03*
X1461921D03*
X1463770Y872716D03*
X1465621Y869511D03*
X1467470Y872716D03*
X1469321Y869511D03*
X1471170Y872716D03*
X1473021Y875920D03*
Y882329D03*
X1474870Y879124D03*
X1476721Y875920D03*
Y882329D03*
X1461921Y875920D03*
Y882329D03*
X1463770Y879124D03*
X1465621Y875920D03*
Y882329D03*
X1467470Y879124D03*
X1469321Y875920D03*
Y882329D03*
X1471170Y879124D03*
X1473021Y888737D03*
Y895146D03*
Y901555D03*
X1474870Y885533D03*
Y891942D03*
Y898350D03*
X1476721Y888737D03*
Y895146D03*
Y901555D03*
X1461921Y888737D03*
Y895146D03*
Y901555D03*
X1463770Y885533D03*
Y891942D03*
Y898350D03*
X1465621Y888737D03*
Y895146D03*
Y901555D03*
X1467470Y885533D03*
Y891942D03*
Y898350D03*
X1469321Y888737D03*
Y895146D03*
Y901555D03*
X1471170Y885533D03*
Y891942D03*
Y898350D03*
X1473021Y907963D03*
Y914372D03*
X1474870Y904759D03*
Y911167D03*
Y917576D03*
X1476721Y907963D03*
Y914372D03*
X1461921Y907963D03*
Y914372D03*
X1463770Y904759D03*
Y911167D03*
Y917576D03*
X1465621Y907963D03*
Y914372D03*
X1467470Y904759D03*
Y911167D03*
Y917576D03*
X1469321Y907963D03*
Y914372D03*
X1471170Y904759D03*
Y911167D03*
Y917576D03*
X1473021Y920780D03*
Y927189D03*
X1474870Y923985D03*
Y930393D03*
X1476721Y920780D03*
Y927189D03*
X1461921Y920780D03*
Y927189D03*
X1463770Y923985D03*
Y930393D03*
X1465621Y920780D03*
Y927189D03*
X1467470Y923985D03*
Y930393D03*
X1469321Y920780D03*
Y927189D03*
X1471170Y923985D03*
Y930393D03*
X1473021Y933598D03*
X1476721D03*
X1461921D03*
X1465621D03*
X1469321D03*
X1473021Y940006D03*
Y946414D03*
X1474870Y936801D03*
Y943210D03*
Y949619D03*
X1476721Y940006D03*
Y946414D03*
X1461921Y940006D03*
Y946414D03*
X1463770Y936801D03*
Y943210D03*
Y949619D03*
X1465621Y940006D03*
Y946414D03*
X1467470Y936801D03*
Y943210D03*
Y949619D03*
X1469321Y940006D03*
Y946414D03*
X1471170Y936801D03*
Y943210D03*
Y949619D03*
X1473021Y952823D03*
Y959232D03*
X1474870Y956027D03*
Y962436D03*
X1476721Y952823D03*
Y959232D03*
X1461921Y952823D03*
Y959232D03*
X1463770Y956027D03*
Y962436D03*
X1465621Y952823D03*
Y959232D03*
X1467470Y956027D03*
Y962436D03*
X1469321Y952823D03*
Y959232D03*
X1471170Y956027D03*
Y962436D03*
X1473021Y965640D03*
X1476721D03*
X1461921D03*
X1465621D03*
X1469321D03*
X1473021Y972049D03*
Y978457D03*
X1474870Y968845D03*
Y975253D03*
Y981662D03*
X1476721Y972049D03*
Y978457D03*
X1461921Y972049D03*
Y978457D03*
X1463770Y968845D03*
Y975253D03*
Y981662D03*
X1465621Y972049D03*
Y978457D03*
X1467470Y968845D03*
Y975253D03*
Y981662D03*
X1469321Y972049D03*
Y978457D03*
X1471170Y968845D03*
Y975253D03*
Y981662D03*
X1473021Y984866D03*
X1476721D03*
X1461921D03*
X1465621D03*
X1469321D03*
X1475303Y997574D03*
X1464203D03*
X1467903D03*
X1471603D03*
X1473454Y1000778D03*
Y1007187D03*
Y1013595D03*
X1475303Y1003983D03*
Y1010391D03*
X1477154Y1000778D03*
Y1007187D03*
Y1013595D03*
X1462354Y1000778D03*
Y1007187D03*
Y1013595D03*
X1464203Y1003983D03*
Y1010391D03*
X1466054Y1000778D03*
Y1007187D03*
Y1013595D03*
X1467903Y1003983D03*
Y1010391D03*
X1469754Y1000778D03*
Y1007187D03*
Y1013595D03*
X1471603Y1003983D03*
Y1010391D03*
X1473454Y1020004D03*
X1475303Y1016800D03*
X1477154Y1020004D03*
X1462354D03*
X1464203Y1016800D03*
X1466054Y1020004D03*
X1467903Y1016800D03*
X1469754Y1020004D03*
X1471603Y1016800D03*
X1473454Y1026413D03*
X1475303Y1023208D03*
Y1029617D03*
X1477154Y1026413D03*
X1462354D03*
X1464203Y1023208D03*
Y1029617D03*
X1466054Y1026413D03*
X1467903Y1023208D03*
Y1029617D03*
X1469754Y1026413D03*
X1471603Y1023208D03*
Y1029617D03*
X1473454Y1032821D03*
Y1039230D03*
Y1045639D03*
X1475303Y1036026D03*
Y1042434D03*
X1477154Y1032821D03*
Y1039230D03*
Y1045639D03*
X1462354Y1032821D03*
Y1039230D03*
Y1045639D03*
X1464203Y1036026D03*
Y1042434D03*
X1466054Y1032821D03*
Y1039230D03*
Y1045639D03*
X1467903Y1036026D03*
Y1042434D03*
X1469754Y1032821D03*
Y1039230D03*
Y1045639D03*
X1471603Y1036026D03*
Y1042434D03*
X1473454Y1052047D03*
X1475303Y1048842D03*
X1477154Y1052047D03*
X1462354D03*
X1464203Y1048842D03*
X1466054Y1052047D03*
X1467903Y1048842D03*
X1469754Y1052047D03*
X1471603Y1048842D03*
X1473454Y1058455D03*
X1475303Y1055251D03*
Y1061660D03*
X1477154Y1058455D03*
X1462354D03*
X1464203Y1055251D03*
Y1061660D03*
X1466054Y1058455D03*
X1467903Y1055251D03*
Y1061660D03*
X1469754Y1058455D03*
X1471603Y1055251D03*
Y1061660D03*
X1473454Y1064864D03*
Y1071273D03*
Y1077681D03*
X1475303Y1068068D03*
Y1074477D03*
X1477154Y1064864D03*
Y1071273D03*
Y1077681D03*
X1462354Y1064864D03*
Y1071273D03*
Y1077681D03*
X1464203Y1068068D03*
Y1074477D03*
X1466054Y1064864D03*
Y1071273D03*
Y1077681D03*
X1467903Y1068068D03*
Y1074477D03*
X1469754Y1064864D03*
Y1071273D03*
Y1077681D03*
X1471603Y1068068D03*
Y1074477D03*
X1475303Y1080885D03*
X1464203D03*
X1467903D03*
X1471603D03*
X1473454Y1084090D03*
Y1090498D03*
X1475303Y1087294D03*
Y1093703D03*
X1477154Y1084090D03*
Y1090498D03*
X1462354Y1084090D03*
Y1090498D03*
X1464203Y1087294D03*
Y1093703D03*
X1466054Y1084090D03*
Y1090498D03*
X1467903Y1087294D03*
Y1093703D03*
X1469754Y1084090D03*
Y1090498D03*
X1471603Y1087294D03*
Y1093703D03*
X1473454Y1096907D03*
Y1103316D03*
Y1109724D03*
X1475303Y1100111D03*
Y1106520D03*
X1477154Y1096907D03*
Y1103316D03*
Y1109724D03*
X1462354Y1096907D03*
Y1103316D03*
Y1109724D03*
X1464203Y1100111D03*
Y1106520D03*
X1466054Y1096907D03*
Y1103316D03*
Y1109724D03*
X1467903Y1100111D03*
Y1106520D03*
X1469754Y1096907D03*
Y1103316D03*
Y1109724D03*
X1471603Y1100111D03*
Y1106520D03*
X1475303Y1112929D03*
X1464203D03*
X1467903D03*
X1471603D03*
X1473454Y1116133D03*
Y1122541D03*
Y1128950D03*
X1475303Y1119337D03*
Y1125746D03*
X1477154Y1116133D03*
Y1122541D03*
Y1128950D03*
X1462354Y1116133D03*
Y1122541D03*
Y1128950D03*
X1464203Y1119337D03*
Y1125746D03*
X1466054Y1116133D03*
Y1122541D03*
Y1128950D03*
X1467903Y1119337D03*
Y1125746D03*
X1469754Y1116133D03*
Y1122541D03*
Y1128950D03*
X1471603Y1119337D03*
Y1125746D03*
X1473454Y1135359D03*
X1475303Y1132154D03*
X1477154Y1135359D03*
X1462354D03*
X1464203Y1132154D03*
X1466054Y1135359D03*
X1467903Y1132154D03*
X1469754Y1135359D03*
X1471603Y1132154D03*
X1478570Y847081D03*
X1480421Y850286D03*
X1482270Y847081D03*
X1484121Y850286D03*
X1485970Y847081D03*
X1487821Y850286D03*
X1489670Y847081D03*
X1491521Y850286D03*
X1493370Y847081D03*
X1478570Y853490D03*
Y859899D03*
Y866307D03*
X1480421Y856694D03*
Y863103D03*
X1482270Y853490D03*
Y859899D03*
Y866307D03*
X1484121Y856694D03*
Y863103D03*
X1485970Y853490D03*
Y859899D03*
Y866307D03*
X1487821Y856694D03*
Y863103D03*
X1489670Y853490D03*
Y859899D03*
Y866307D03*
X1491521Y856694D03*
Y863103D03*
X1493370Y853490D03*
Y859899D03*
Y866307D03*
X1478570Y872716D03*
X1480421Y869511D03*
X1482270Y872716D03*
X1484121Y869511D03*
X1485970Y872716D03*
X1487821Y869511D03*
X1489670Y872716D03*
X1491521Y869511D03*
X1493370Y872716D03*
X1478570Y879124D03*
X1480421Y875920D03*
Y882329D03*
X1482270Y879124D03*
X1484121Y875920D03*
Y882329D03*
X1485970Y879124D03*
X1487821Y875920D03*
Y882329D03*
X1489670Y879124D03*
X1491521Y875920D03*
Y882329D03*
X1493370Y879124D03*
X1478570Y885533D03*
Y891942D03*
Y898350D03*
X1480421Y888737D03*
Y895146D03*
Y901555D03*
X1482270Y885533D03*
Y891942D03*
Y898350D03*
X1484121Y888737D03*
Y895146D03*
Y901555D03*
X1485970Y885533D03*
Y891942D03*
Y898350D03*
X1487821Y888737D03*
Y895146D03*
Y901555D03*
X1489670Y885533D03*
Y891942D03*
Y898350D03*
X1491521Y888737D03*
Y895146D03*
Y901555D03*
X1493370Y885533D03*
Y891942D03*
Y898350D03*
X1478570Y904759D03*
Y911167D03*
Y917576D03*
X1480421Y907963D03*
Y914372D03*
X1482270Y904759D03*
Y911167D03*
Y917576D03*
X1484121Y907963D03*
Y914372D03*
X1485970Y904759D03*
Y911167D03*
Y917576D03*
X1487821Y907963D03*
Y914372D03*
X1489670Y904759D03*
Y911167D03*
Y917576D03*
X1491521Y907963D03*
Y914372D03*
X1493370Y904759D03*
Y911167D03*
Y917576D03*
X1478570Y923985D03*
Y930393D03*
X1480421Y920780D03*
Y927189D03*
X1482270Y923985D03*
Y930393D03*
X1484121Y920780D03*
Y927189D03*
X1485970Y923985D03*
Y930393D03*
X1487821Y920780D03*
Y927189D03*
X1489670Y923985D03*
Y930393D03*
X1491521Y920780D03*
Y927189D03*
X1493370Y923985D03*
Y930393D03*
X1480421Y933598D03*
X1484121D03*
X1487821D03*
X1491521D03*
X1478570Y936801D03*
Y943210D03*
Y949619D03*
X1480421Y940006D03*
Y946414D03*
X1482270Y936801D03*
Y943210D03*
Y949619D03*
X1484121Y940006D03*
Y946414D03*
X1485970Y936801D03*
Y943210D03*
Y949619D03*
X1487821Y940006D03*
Y946414D03*
X1489670Y936801D03*
Y943210D03*
Y949619D03*
X1491521Y940006D03*
Y946414D03*
X1493370Y936801D03*
Y943210D03*
Y949619D03*
X1478570Y956027D03*
Y962436D03*
X1480421Y952823D03*
Y959232D03*
X1482270Y956027D03*
Y962436D03*
X1484121Y952823D03*
Y959232D03*
X1485970Y956027D03*
Y962436D03*
X1487821Y952823D03*
Y959232D03*
X1489670Y956027D03*
Y962436D03*
X1491521Y952823D03*
Y959232D03*
X1493370Y956027D03*
Y962436D03*
X1480421Y965640D03*
X1484121D03*
X1487821D03*
X1491521D03*
X1478570Y968845D03*
Y975253D03*
Y981662D03*
X1480421Y972049D03*
Y978457D03*
X1482270Y968845D03*
Y975253D03*
Y981662D03*
X1484121Y972049D03*
Y978457D03*
X1485970Y968845D03*
Y975253D03*
Y981662D03*
X1487821Y972049D03*
Y978457D03*
X1489670Y968845D03*
Y975253D03*
Y981662D03*
X1491521Y972049D03*
Y978457D03*
X1493370Y968845D03*
Y975253D03*
Y981662D03*
X1480421Y984866D03*
X1484121D03*
X1487821D03*
X1491521D03*
X1479003Y997574D03*
X1482703D03*
X1486403D03*
X1490103D03*
X1493803D03*
X1479003Y1003983D03*
Y1010391D03*
X1480854Y1000778D03*
Y1007187D03*
Y1013595D03*
X1482703Y1003983D03*
Y1010391D03*
X1484554Y1000778D03*
Y1007187D03*
Y1013595D03*
X1486403Y1003983D03*
Y1010391D03*
X1488254Y1000778D03*
Y1007187D03*
Y1013595D03*
X1490103Y1003983D03*
Y1010391D03*
X1491954Y1000778D03*
Y1007187D03*
Y1013595D03*
X1493803Y1003983D03*
Y1010391D03*
X1479003Y1016800D03*
X1480854Y1020004D03*
X1482703Y1016800D03*
X1484554Y1020004D03*
X1486403Y1016800D03*
X1488254Y1020004D03*
X1490103Y1016800D03*
X1491954Y1020004D03*
X1493803Y1016800D03*
X1479003Y1023208D03*
Y1029617D03*
X1480854Y1026413D03*
X1482703Y1023208D03*
Y1029617D03*
X1484554Y1026413D03*
X1486403Y1023208D03*
Y1029617D03*
X1488254Y1026413D03*
X1490103Y1023208D03*
Y1029617D03*
X1491954Y1026413D03*
X1493803Y1023208D03*
Y1029617D03*
X1479003Y1036026D03*
Y1042434D03*
X1480854Y1032821D03*
Y1039230D03*
Y1045639D03*
X1482703Y1036026D03*
Y1042434D03*
X1484554Y1032821D03*
Y1039230D03*
Y1045639D03*
X1486403Y1036026D03*
Y1042434D03*
X1488254Y1032821D03*
Y1039230D03*
Y1045639D03*
X1490103Y1036026D03*
Y1042434D03*
X1491954Y1032821D03*
Y1039230D03*
Y1045639D03*
X1493803Y1036026D03*
Y1042434D03*
X1479003Y1048842D03*
X1480854Y1052047D03*
X1482703Y1048842D03*
X1484554Y1052047D03*
X1486403Y1048842D03*
X1488254Y1052047D03*
X1490103Y1048842D03*
X1491954Y1052047D03*
X1493803Y1048842D03*
X1479003Y1055251D03*
Y1061660D03*
X1480854Y1058455D03*
X1482703Y1055251D03*
Y1061660D03*
X1484554Y1058455D03*
X1486403Y1055251D03*
Y1061660D03*
X1488254Y1058455D03*
X1490103Y1055251D03*
Y1061660D03*
X1491954Y1058455D03*
X1493803Y1055251D03*
Y1061660D03*
X1479003Y1068068D03*
Y1074477D03*
X1480854Y1064864D03*
Y1071273D03*
Y1077681D03*
X1482703Y1068068D03*
Y1074477D03*
X1484554Y1064864D03*
Y1071273D03*
Y1077681D03*
X1486403Y1068068D03*
Y1074477D03*
X1488254Y1064864D03*
Y1071273D03*
Y1077681D03*
X1490103Y1068068D03*
Y1074477D03*
X1491954Y1064864D03*
Y1071273D03*
Y1077681D03*
X1493803Y1068068D03*
Y1074477D03*
X1479003Y1080885D03*
X1482703D03*
X1486403D03*
X1490103D03*
X1493803D03*
X1479003Y1087294D03*
Y1093703D03*
X1480854Y1084090D03*
Y1090498D03*
X1482703Y1087294D03*
Y1093703D03*
X1484554Y1084090D03*
Y1090498D03*
X1486403Y1087294D03*
Y1093703D03*
X1488254Y1084090D03*
Y1090498D03*
X1490103Y1087294D03*
Y1093703D03*
X1491954Y1084090D03*
Y1090498D03*
X1493803Y1087294D03*
Y1093703D03*
X1479003Y1100111D03*
Y1106520D03*
X1480854Y1096907D03*
Y1103316D03*
Y1109724D03*
X1482703Y1100111D03*
Y1106520D03*
X1484554Y1096907D03*
Y1103316D03*
Y1109724D03*
X1486403Y1100111D03*
Y1106520D03*
X1488254Y1096907D03*
Y1103316D03*
Y1109724D03*
X1490103Y1100111D03*
Y1106520D03*
X1491954Y1096907D03*
Y1103316D03*
Y1109724D03*
X1493803Y1100111D03*
Y1106520D03*
X1479003Y1112929D03*
X1482703D03*
X1486403D03*
X1490103D03*
X1493803D03*
X1479003Y1119337D03*
Y1125746D03*
X1480854Y1116133D03*
Y1122541D03*
Y1128950D03*
X1482703Y1119337D03*
Y1125746D03*
X1484554Y1116133D03*
Y1122541D03*
Y1128950D03*
X1486403Y1119337D03*
Y1125746D03*
X1488254Y1116133D03*
Y1122541D03*
Y1128950D03*
X1490103Y1119337D03*
Y1125746D03*
X1491954Y1116133D03*
Y1122541D03*
Y1128950D03*
X1493803Y1119337D03*
Y1125746D03*
X1479003Y1132154D03*
X1480854Y1135359D03*
X1482703Y1132154D03*
X1484554Y1135359D03*
X1486403Y1132154D03*
X1488254Y1135359D03*
X1490103Y1132154D03*
X1491954Y1135359D03*
X1493803Y1132154D03*
X1502621Y850286D03*
X1506321D03*
X1495221D03*
X1497070Y847081D03*
X1498921Y850286D03*
X1502621Y856694D03*
Y863103D03*
X1504471Y853490D03*
Y859899D03*
Y866307D03*
X1506321Y856694D03*
Y863103D03*
X1508170Y853490D03*
Y859899D03*
Y866307D03*
X1510021Y856694D03*
Y863103D03*
X1495221Y856694D03*
Y863103D03*
X1497070Y853490D03*
Y859899D03*
Y866307D03*
X1498921Y856694D03*
Y863103D03*
X1500770Y853490D03*
Y859899D03*
Y866307D03*
X1502621Y869511D03*
X1504471Y872716D03*
X1506321Y869511D03*
X1508170Y872716D03*
X1510021Y869511D03*
X1495221D03*
X1497070Y872716D03*
X1498921Y869511D03*
X1500770Y872716D03*
X1502621Y875920D03*
Y882329D03*
X1504471Y879124D03*
X1506321Y875920D03*
Y882329D03*
X1508170Y879124D03*
X1510021Y875920D03*
Y882329D03*
X1495221Y875920D03*
Y882329D03*
X1497070Y879124D03*
X1498921Y875920D03*
Y882329D03*
X1500770Y879124D03*
X1502621Y888737D03*
Y895146D03*
Y901555D03*
X1504471Y885533D03*
Y891942D03*
Y898350D03*
X1506321Y888737D03*
Y895146D03*
Y901555D03*
X1508170Y885533D03*
Y891942D03*
Y898350D03*
X1510021Y888737D03*
Y895146D03*
Y901555D03*
X1495221Y888737D03*
Y895146D03*
Y901555D03*
X1497070Y885533D03*
Y891942D03*
Y898350D03*
X1498921Y888737D03*
Y895146D03*
Y901555D03*
X1500770Y885533D03*
Y891942D03*
Y898350D03*
X1502621Y907963D03*
Y914372D03*
X1504471Y904759D03*
Y911167D03*
Y917576D03*
X1506321Y907963D03*
Y914372D03*
X1508170Y904759D03*
Y911167D03*
Y917576D03*
X1510021Y907963D03*
Y914372D03*
X1495221Y907963D03*
Y914372D03*
X1497070Y904759D03*
Y911167D03*
Y917576D03*
X1498921Y907963D03*
Y914372D03*
X1500770Y904759D03*
Y911167D03*
Y917576D03*
X1502621Y920780D03*
Y927189D03*
X1504471Y923985D03*
Y930393D03*
X1506321Y920780D03*
Y927189D03*
X1508170Y923985D03*
Y930393D03*
X1510021Y920780D03*
Y927189D03*
X1495221Y920780D03*
Y927189D03*
X1497070Y923985D03*
Y930393D03*
X1498921Y920780D03*
Y927189D03*
X1500770Y923985D03*
Y930393D03*
X1502621Y933598D03*
X1506321D03*
X1510021D03*
X1495221D03*
X1498921D03*
X1502621Y940006D03*
Y946414D03*
X1504471Y936801D03*
Y943210D03*
Y949619D03*
X1506321Y940006D03*
Y946414D03*
X1508170Y936801D03*
Y943210D03*
Y949619D03*
X1510021Y940006D03*
Y946414D03*
X1495221Y940006D03*
Y946414D03*
X1497070Y936801D03*
Y943210D03*
Y949619D03*
X1498921Y940006D03*
Y946414D03*
X1500770Y936801D03*
Y943210D03*
Y949619D03*
X1502621Y952823D03*
Y959232D03*
X1504471Y956027D03*
Y962436D03*
X1506321Y952823D03*
Y959232D03*
X1508170Y956027D03*
Y962436D03*
X1510021Y952823D03*
Y959232D03*
X1495221Y952823D03*
Y959232D03*
X1497070Y956027D03*
Y962436D03*
X1498921Y952823D03*
Y959232D03*
X1500770Y956027D03*
Y962436D03*
X1502621Y965640D03*
X1506321D03*
X1510021D03*
X1495221D03*
X1498921D03*
X1502621Y972049D03*
Y978457D03*
X1504471Y968845D03*
Y975253D03*
Y981662D03*
X1506321Y972049D03*
Y978457D03*
X1508170Y968845D03*
Y975253D03*
Y981662D03*
X1510021Y972049D03*
Y978457D03*
X1495221Y972049D03*
Y978457D03*
X1497070Y968845D03*
Y975253D03*
Y981662D03*
X1498921Y972049D03*
Y978457D03*
X1500770Y968845D03*
Y975253D03*
Y981662D03*
X1502621Y984866D03*
X1506321D03*
X1510021D03*
X1495221D03*
X1498921D03*
X1504903Y997574D03*
X1508603D03*
X1497503D03*
X1501203D03*
X1503054Y1000778D03*
Y1007187D03*
Y1013595D03*
X1504903Y1003983D03*
Y1010391D03*
X1506754Y1000778D03*
Y1007187D03*
Y1013595D03*
X1508603Y1003983D03*
Y1010391D03*
X1495654Y1000778D03*
Y1007187D03*
Y1013595D03*
X1497503Y1003983D03*
Y1010391D03*
X1499354Y1000778D03*
Y1007187D03*
Y1013595D03*
X1501203Y1003983D03*
Y1010391D03*
X1503054Y1020004D03*
X1504903Y1016800D03*
X1506754Y1020004D03*
X1508603Y1016800D03*
X1495654Y1020004D03*
X1497503Y1016800D03*
X1499354Y1020004D03*
X1501203Y1016800D03*
X1503054Y1026413D03*
X1504903Y1023208D03*
Y1029617D03*
X1506754Y1026413D03*
X1508603Y1023208D03*
Y1029617D03*
X1495654Y1026413D03*
X1497503Y1023208D03*
Y1029617D03*
X1499354Y1026413D03*
X1501203Y1023208D03*
Y1029617D03*
X1503054Y1032821D03*
Y1039230D03*
Y1045639D03*
X1504903Y1036026D03*
Y1042434D03*
X1506754Y1032821D03*
Y1039230D03*
Y1045639D03*
X1508603Y1036026D03*
Y1042434D03*
X1495654Y1032821D03*
Y1039230D03*
Y1045639D03*
X1497503Y1036026D03*
Y1042434D03*
X1499354Y1032821D03*
Y1039230D03*
Y1045639D03*
X1501203Y1036026D03*
Y1042434D03*
X1503054Y1052047D03*
X1504903Y1048842D03*
X1506754Y1052047D03*
X1508603Y1048842D03*
X1495654Y1052047D03*
X1497503Y1048842D03*
X1499354Y1052047D03*
X1501203Y1048842D03*
X1503054Y1058455D03*
X1504903Y1055251D03*
Y1061660D03*
X1506754Y1058455D03*
X1508603Y1055251D03*
Y1061660D03*
X1495654Y1058455D03*
X1497503Y1055251D03*
Y1061660D03*
X1499354Y1058455D03*
X1501203Y1055251D03*
Y1061660D03*
X1503054Y1064864D03*
Y1071273D03*
Y1077681D03*
X1504903Y1068068D03*
Y1074477D03*
X1506754Y1064864D03*
Y1071273D03*
Y1077681D03*
X1508603Y1068068D03*
Y1074477D03*
X1495654Y1064864D03*
Y1071273D03*
Y1077681D03*
X1497503Y1068068D03*
Y1074477D03*
X1499354Y1064864D03*
Y1071273D03*
Y1077681D03*
X1501203Y1068068D03*
Y1074477D03*
X1504903Y1080885D03*
X1508603D03*
X1497503D03*
X1501203D03*
X1503054Y1084090D03*
Y1090498D03*
X1504903Y1087294D03*
Y1093703D03*
X1506754Y1084090D03*
Y1090498D03*
X1508603Y1087294D03*
Y1093703D03*
X1495654Y1084090D03*
Y1090498D03*
X1497503Y1087294D03*
Y1093703D03*
X1499354Y1084090D03*
Y1090498D03*
X1501203Y1087294D03*
Y1093703D03*
X1503054Y1096907D03*
Y1103316D03*
Y1109724D03*
X1504903Y1100111D03*
Y1106520D03*
X1506754Y1096907D03*
Y1103316D03*
Y1109724D03*
X1508603Y1100111D03*
Y1106520D03*
X1495654Y1096907D03*
Y1103316D03*
Y1109724D03*
X1497503Y1100111D03*
Y1106520D03*
X1499354Y1096907D03*
Y1103316D03*
Y1109724D03*
X1501203Y1100111D03*
Y1106520D03*
X1504903Y1112929D03*
X1508603D03*
X1497503D03*
X1501203D03*
X1503054Y1116133D03*
Y1122541D03*
Y1128950D03*
X1504903Y1119337D03*
Y1125746D03*
X1506754Y1116133D03*
Y1122541D03*
Y1128950D03*
X1508603Y1119337D03*
Y1125746D03*
X1495654Y1116133D03*
Y1122541D03*
Y1128950D03*
X1497503Y1119337D03*
Y1125746D03*
X1499354Y1116133D03*
Y1122541D03*
Y1128950D03*
X1501203Y1119337D03*
Y1125746D03*
X1504903Y1132154D03*
X1495654Y1135359D03*
X1497503Y1132154D03*
X1499354Y1135359D03*
X1501203Y1132154D03*
X1511871Y859899D03*
Y866307D03*
X1513721Y863103D03*
X1515570Y866307D03*
X1511871Y872716D03*
X1513721Y869511D03*
X1515570Y872716D03*
X1517421Y869511D03*
X1519271Y872716D03*
X1511871Y879124D03*
X1513721Y875920D03*
Y882329D03*
X1515570Y879124D03*
X1517421Y875920D03*
Y882329D03*
X1519271Y879124D03*
X1521121Y875920D03*
Y882329D03*
X1511871Y885533D03*
Y891942D03*
Y898350D03*
X1513721Y888737D03*
Y895146D03*
Y901555D03*
X1515570Y885533D03*
Y891942D03*
Y898350D03*
X1517421Y888737D03*
Y895146D03*
Y901555D03*
X1519271Y885533D03*
Y891942D03*
Y898350D03*
X1521121Y888737D03*
Y895146D03*
Y901555D03*
X1511871Y904759D03*
Y911167D03*
Y917576D03*
X1513721Y907963D03*
Y914372D03*
X1515570Y904759D03*
Y911167D03*
Y917576D03*
X1517421Y907963D03*
Y914372D03*
X1519271Y904759D03*
Y911167D03*
Y917576D03*
X1521121Y907963D03*
Y914372D03*
X1511871Y923985D03*
Y930393D03*
X1513721Y920780D03*
Y927189D03*
X1515570Y923985D03*
Y930393D03*
X1517421Y920780D03*
Y927189D03*
X1519271Y923985D03*
Y930393D03*
X1521121Y920780D03*
Y927189D03*
X1513721Y933598D03*
X1517421D03*
X1521121D03*
X1511871Y936801D03*
Y943210D03*
Y949619D03*
X1513721Y940006D03*
Y946414D03*
X1515570Y936801D03*
Y943210D03*
Y949619D03*
X1517421Y940006D03*
Y946414D03*
X1519271Y936801D03*
Y943210D03*
Y949619D03*
X1521121Y940006D03*
Y946414D03*
X1511871Y956027D03*
Y962436D03*
X1513721Y952823D03*
Y959232D03*
X1515570Y956027D03*
Y962436D03*
X1517421Y952823D03*
Y959232D03*
X1519271Y956027D03*
Y962436D03*
X1521121Y952823D03*
Y959232D03*
X1513721Y965640D03*
X1517421D03*
X1521121D03*
X1511871Y968845D03*
Y975253D03*
Y981662D03*
X1513721Y972049D03*
Y978457D03*
X1515570Y968845D03*
Y975253D03*
Y981662D03*
X1517421Y972049D03*
Y978457D03*
X1519271Y968845D03*
Y975253D03*
X1521121Y972049D03*
X1513721Y984866D03*
X1512303Y997574D03*
X1516003D03*
X1510453Y1000778D03*
Y1007187D03*
Y1013595D03*
X1512303Y1003983D03*
Y1010391D03*
X1514154Y1000778D03*
Y1007187D03*
Y1013595D03*
X1516003Y1003983D03*
Y1010391D03*
X1517853Y1000778D03*
Y1007187D03*
Y1013595D03*
X1519703Y1003983D03*
Y1010391D03*
X1521554Y1007187D03*
Y1013595D03*
X1510453Y1020004D03*
X1512303Y1016800D03*
X1514154Y1020004D03*
X1516003Y1016800D03*
X1517853Y1020004D03*
X1519703Y1016800D03*
X1521554Y1020004D03*
X1510453Y1026413D03*
X1512303Y1023208D03*
Y1029617D03*
X1514154Y1026413D03*
X1516003Y1023208D03*
Y1029617D03*
X1517853Y1026413D03*
X1519703Y1023208D03*
Y1029617D03*
X1521554Y1026413D03*
X1510453Y1032821D03*
Y1039230D03*
Y1045639D03*
X1512303Y1036026D03*
Y1042434D03*
X1514154Y1032821D03*
Y1039230D03*
Y1045639D03*
X1516003Y1036026D03*
Y1042434D03*
X1517853Y1032821D03*
Y1039230D03*
Y1045639D03*
X1519703Y1036026D03*
Y1042434D03*
X1521554Y1032821D03*
Y1039230D03*
X1510453Y1052047D03*
X1512303Y1048842D03*
X1514154Y1052047D03*
X1516003Y1048842D03*
X1517853Y1052047D03*
X1519703Y1048842D03*
X1510453Y1058455D03*
X1512303Y1055251D03*
Y1061660D03*
X1514154Y1058455D03*
X1516003Y1055251D03*
Y1061660D03*
X1517853Y1058455D03*
X1519703Y1055251D03*
Y1061660D03*
X1510453Y1064864D03*
Y1071273D03*
Y1077681D03*
X1512303Y1068068D03*
Y1074477D03*
X1514154Y1064864D03*
Y1071273D03*
Y1077681D03*
X1516003Y1068068D03*
Y1074477D03*
X1517853Y1064864D03*
Y1071273D03*
Y1077681D03*
X1519703Y1068068D03*
Y1074477D03*
X1512303Y1080885D03*
X1516003D03*
X1519703D03*
X1510453Y1084090D03*
Y1090498D03*
X1512303Y1087294D03*
Y1093703D03*
X1514154Y1084090D03*
Y1090498D03*
X1516003Y1087294D03*
Y1093703D03*
X1517853Y1084090D03*
Y1090498D03*
X1519703Y1087294D03*
Y1093703D03*
X1510453Y1096907D03*
Y1103316D03*
Y1109724D03*
X1512303Y1100111D03*
Y1106520D03*
X1514154Y1096907D03*
Y1103316D03*
Y1109724D03*
X1516003Y1100111D03*
Y1106520D03*
X1517853Y1096907D03*
Y1103316D03*
Y1109724D03*
X1519703Y1100111D03*
Y1106520D03*
X1512303Y1112929D03*
X1516003D03*
X1510453Y1116133D03*
Y1122541D03*
X1512303Y1119337D03*
X1514154Y1116133D03*
G54D225*
X922441Y154311D03*
Y243799D03*
G54D33*
X62106Y169291D03*
Y177165D03*
Y185039D03*
Y192913D03*
Y200787D03*
Y208661D03*
Y216535D03*
Y224409D03*
Y232283D03*
Y240157D03*
X78838Y169291D03*
Y177165D03*
Y185039D03*
Y192913D03*
Y200787D03*
Y208661D03*
Y216535D03*
Y224409D03*
Y232283D03*
Y240157D03*
G54D316*
G01X-6350Y-464479D02*
Y-539479D01*
X493650D01*
Y-464479D01*
X-6350D01*
G01X5650Y-529479D02*
Y-534479D01*
G01X4193Y-529479D02*
X7107D01*
G01X12017Y-534479D02*
X9483D01*
Y-529479D01*
X12017D01*
G01X11003Y-531896D02*
X9483D01*
G01X14583Y-529479D02*
Y-534479D01*
X17117D01*
G01X20950Y-534646D02*
X20823Y-534562D01*
Y-534396D01*
X20950Y-534312D01*
X21077Y-534396D01*
Y-534562D01*
X20950Y-534646D01*
G01Y-532396D02*
X20823Y-532312D01*
Y-532146D01*
X20950Y-532062D01*
X21077Y-532146D01*
Y-532312D01*
X20950Y-532396D01*
G01X25733Y-536146D02*
X25100Y-535312D01*
X24783Y-534479D01*
Y-531146D01*
X25100Y-530312D01*
X25733Y-529479D01*
G01X31150D02*
X30643Y-529646D01*
X30263Y-530062D01*
X30010Y-530562D01*
X29820Y-531229D01*
X29757Y-531979D01*
X29820Y-532729D01*
X30010Y-533396D01*
X30263Y-533896D01*
X30643Y-534312D01*
X31150Y-534479D01*
X31657Y-534312D01*
X32037Y-533896D01*
X32290Y-533396D01*
X32480Y-532729D01*
X32543Y-531979D01*
X32480Y-531229D01*
X32290Y-530562D01*
X32037Y-530062D01*
X31657Y-529646D01*
X31150Y-529479D01*
G01X34857Y-533479D02*
X35237Y-534062D01*
X35743Y-534396D01*
X36313Y-534479D01*
X36820Y-534396D01*
X37327Y-533979D01*
X37643Y-533479D01*
X37707Y-532979D01*
X37580Y-532396D01*
X37137Y-531979D01*
X36693Y-531812D01*
X36123D01*
G01X36693D02*
X37073Y-531562D01*
X37390Y-531146D01*
X37517Y-530646D01*
X37390Y-530146D01*
X37073Y-529729D01*
X36503Y-529479D01*
X35933Y-529562D01*
X35363Y-529896D01*
G01X41667Y-536146D02*
X42300Y-535312D01*
X42617Y-534479D01*
Y-531146D01*
X42300Y-530312D01*
X41667Y-529479D01*
G01X45057Y-533479D02*
X45437Y-534062D01*
X45943Y-534396D01*
X46513Y-534479D01*
X47020Y-534396D01*
X47527Y-533979D01*
X47843Y-533479D01*
X47907Y-532979D01*
X47780Y-532396D01*
X47337Y-531979D01*
X46893Y-531812D01*
X46323D01*
G01X46893D02*
X47273Y-531562D01*
X47590Y-531146D01*
X47717Y-530646D01*
X47590Y-530146D01*
X47273Y-529729D01*
X46703Y-529479D01*
X46133Y-529562D01*
X45563Y-529896D01*
G01X50347Y-530312D02*
X50727Y-529812D01*
X51170Y-529562D01*
X51677Y-529479D01*
X52310Y-529646D01*
X52753Y-530062D01*
X52880Y-530562D01*
X52817Y-531062D01*
X52563Y-531479D01*
X51297Y-532312D01*
X50727Y-532896D01*
X50347Y-533729D01*
X50220Y-534479D01*
X52880D01*
G01X56523D02*
X56650Y-533396D01*
X56840Y-532479D01*
X57093Y-531646D01*
X57410Y-530729D01*
X57917Y-529479D01*
X55383D01*
G01X60927Y-532812D02*
X62573D01*
G01X65647Y-530312D02*
X66027Y-529812D01*
X66470Y-529562D01*
X66977Y-529479D01*
X67610Y-529646D01*
X68053Y-530062D01*
X68180Y-530562D01*
X68117Y-531062D01*
X67863Y-531479D01*
X66597Y-532312D01*
X66027Y-532896D01*
X65647Y-533729D01*
X65520Y-534479D01*
X68180D01*
G01X70557Y-533479D02*
X70937Y-534062D01*
X71443Y-534396D01*
X72013Y-534479D01*
X72520Y-534396D01*
X73027Y-533979D01*
X73343Y-533479D01*
X73407Y-532979D01*
X73280Y-532396D01*
X72837Y-531979D01*
X72393Y-531812D01*
X71823D01*
G01X72393D02*
X72773Y-531562D01*
X73090Y-531146D01*
X73217Y-530646D01*
X73090Y-530146D01*
X72773Y-529729D01*
X72203Y-529479D01*
X71633Y-529562D01*
X71063Y-529896D01*
G01X77810Y-534479D02*
Y-529479D01*
X75467Y-533062D01*
X78633D01*
G01X80757Y-533729D02*
X81137Y-534146D01*
X81580Y-534396D01*
X82150Y-534479D01*
X82720Y-534312D01*
X83163Y-533979D01*
X83480Y-533396D01*
X83543Y-532729D01*
X83417Y-532062D01*
X83100Y-531646D01*
X82657Y-531312D01*
X82213Y-531229D01*
X81770Y-531312D01*
X81200Y-531646D01*
X81390Y-529479D01*
X83100D01*
G01X91147Y-534479D02*
Y-529479D01*
X93553D01*
G01X92667Y-531896D02*
X91147D01*
G01X95867Y-534479D02*
X97450Y-529479D01*
X99033Y-534479D01*
G01X98463Y-532729D02*
X96437D01*
G01X101220Y-534479D02*
X103880Y-529479D01*
G01X101220D02*
X103880Y-534479D01*
G01X107650Y-534646D02*
X107523Y-534562D01*
Y-534396D01*
X107650Y-534312D01*
X107777Y-534396D01*
Y-534562D01*
X107650Y-534646D01*
G01Y-532396D02*
X107523Y-532312D01*
Y-532146D01*
X107650Y-532062D01*
X107777Y-532146D01*
Y-532312D01*
X107650Y-532396D01*
G01X112433Y-536146D02*
X111800Y-535312D01*
X111483Y-534479D01*
Y-531146D01*
X111800Y-530312D01*
X112433Y-529479D01*
G01X117850D02*
X117343Y-529646D01*
X116963Y-530062D01*
X116710Y-530562D01*
X116520Y-531229D01*
X116457Y-531979D01*
X116520Y-532729D01*
X116710Y-533396D01*
X116963Y-533896D01*
X117343Y-534312D01*
X117850Y-534479D01*
X118357Y-534312D01*
X118737Y-533896D01*
X118990Y-533396D01*
X119180Y-532729D01*
X119243Y-531979D01*
X119180Y-531229D01*
X118990Y-530562D01*
X118737Y-530062D01*
X118357Y-529646D01*
X117850Y-529479D01*
G01X121557Y-533479D02*
X121937Y-534062D01*
X122443Y-534396D01*
X123013Y-534479D01*
X123520Y-534396D01*
X124027Y-533979D01*
X124343Y-533479D01*
X124407Y-532979D01*
X124280Y-532396D01*
X123837Y-531979D01*
X123393Y-531812D01*
X122823D01*
G01X123393D02*
X123773Y-531562D01*
X124090Y-531146D01*
X124217Y-530646D01*
X124090Y-530146D01*
X123773Y-529729D01*
X123203Y-529479D01*
X122633Y-529562D01*
X122063Y-529896D01*
G01X128367Y-536146D02*
X129000Y-535312D01*
X129317Y-534479D01*
Y-531146D01*
X129000Y-530312D01*
X128367Y-529479D01*
G01X131757Y-533479D02*
X132137Y-534062D01*
X132643Y-534396D01*
X133213Y-534479D01*
X133720Y-534396D01*
X134227Y-533979D01*
X134543Y-533479D01*
X134607Y-532979D01*
X134480Y-532396D01*
X134037Y-531979D01*
X133593Y-531812D01*
X133023D01*
G01X133593D02*
X133973Y-531562D01*
X134290Y-531146D01*
X134417Y-530646D01*
X134290Y-530146D01*
X133973Y-529729D01*
X133403Y-529479D01*
X132833Y-529562D01*
X132263Y-529896D01*
G01X137173Y-533896D02*
X137617Y-534312D01*
X138123Y-534479D01*
X138630Y-534312D01*
X139073Y-533812D01*
X139390Y-533062D01*
X139517Y-532312D01*
Y-531396D01*
X139390Y-530646D01*
X139073Y-529979D01*
X138693Y-529646D01*
X138250Y-529479D01*
X137743Y-529646D01*
X137363Y-529979D01*
X137110Y-530479D01*
X136983Y-531146D01*
X137110Y-531729D01*
X137427Y-532312D01*
X137807Y-532646D01*
X138250Y-532729D01*
X138757Y-532562D01*
X139137Y-532146D01*
X139517Y-531396D01*
G01X143223Y-534479D02*
X143350Y-533396D01*
X143540Y-532479D01*
X143793Y-531646D01*
X144110Y-530729D01*
X144617Y-529479D01*
X142083D01*
G01X147627Y-532812D02*
X149273D01*
G01X152157Y-533479D02*
X152537Y-534062D01*
X153043Y-534396D01*
X153613Y-534479D01*
X154120Y-534396D01*
X154627Y-533979D01*
X154943Y-533479D01*
X155007Y-532979D01*
X154880Y-532396D01*
X154437Y-531979D01*
X153993Y-531812D01*
X153423D01*
G01X153993D02*
X154373Y-531562D01*
X154690Y-531146D01*
X154817Y-530646D01*
X154690Y-530146D01*
X154373Y-529729D01*
X153803Y-529479D01*
X153233Y-529562D01*
X152663Y-529896D01*
G01X157447Y-532396D02*
X157890Y-531812D01*
X158270Y-531479D01*
X158777Y-531312D01*
X159220Y-531479D01*
X159537Y-531812D01*
X159790Y-532312D01*
X159853Y-532896D01*
X159790Y-533396D01*
X159537Y-533896D01*
X159157Y-534312D01*
X158713Y-534479D01*
X158207Y-534312D01*
X157763Y-533812D01*
X157510Y-533062D01*
X157447Y-532229D01*
X157573Y-531146D01*
X157763Y-530562D01*
X158080Y-529979D01*
X158523Y-529562D01*
X158967Y-529479D01*
X159410Y-529646D01*
X159727Y-530062D01*
G01X163750Y-534479D02*
Y-529479D01*
X162990Y-530479D01*
G01Y-534479D02*
X164510D01*
G01X169610D02*
Y-529479D01*
X167267Y-533062D01*
X170433D01*
G01X188650Y-464479D02*
Y-539479D01*
G01Y-514479D02*
X291650D01*
Y-489479D01*
G01X188650D02*
X291650D01*
G01Y-464479D02*
Y-539479D01*
G01X293650Y-464479D02*
Y-539479D01*
G01X299157Y-524479D02*
Y-519479D01*
X300423D01*
X300930Y-519729D01*
X301310Y-520062D01*
X301627Y-520562D01*
X301880Y-521146D01*
X301943Y-521979D01*
X301880Y-522812D01*
X301627Y-523396D01*
X301310Y-523896D01*
X300930Y-524229D01*
X300423Y-524479D01*
X299157D01*
G01X304067D02*
X305650Y-519479D01*
X307233Y-524479D01*
G01X306663Y-522729D02*
X304637D01*
G01X310750Y-519479D02*
Y-524479D01*
G01X309293Y-519479D02*
X312207D01*
G01X317117Y-524479D02*
X314583D01*
Y-519479D01*
X317117D01*
G01X316103Y-521896D02*
X314583D01*
G01X320950Y-524646D02*
X320823Y-524562D01*
Y-524396D01*
X320950Y-524312D01*
X321077Y-524396D01*
Y-524562D01*
X320950Y-524646D01*
G01Y-522396D02*
X320823Y-522312D01*
Y-522146D01*
X320950Y-522062D01*
X321077Y-522146D01*
Y-522312D01*
X320950Y-522396D01*
G01X299283Y-499479D02*
Y-494479D01*
X300803D01*
X301310Y-494729D01*
X301690Y-495312D01*
X301817Y-495979D01*
X301690Y-496646D01*
X301373Y-497146D01*
X300803Y-497396D01*
X299283D01*
G01X304510Y-499646D02*
X306790Y-494479D01*
G01X309293Y-499479D02*
Y-494479D01*
X312207Y-499479D01*
Y-494479D01*
G01X315850Y-499646D02*
X315723Y-499562D01*
Y-499396D01*
X315850Y-499312D01*
X315977Y-499396D01*
Y-499562D01*
X315850Y-499646D01*
G01Y-497396D02*
X315723Y-497312D01*
Y-497146D01*
X315850Y-497062D01*
X315977Y-497146D01*
Y-497312D01*
X315850Y-497396D01*
G01X293650Y-514479D02*
X493650D01*
G01X293650Y-489479D02*
X493650D01*
G01X299283Y-474479D02*
Y-469479D01*
X300803D01*
X301310Y-469729D01*
X301690Y-470312D01*
X301817Y-470979D01*
X301690Y-471646D01*
X301373Y-472146D01*
X300803Y-472396D01*
X299283D01*
G01X304383Y-474479D02*
Y-469479D01*
X305967D01*
X306473Y-469729D01*
X306790Y-470062D01*
X306917Y-470729D01*
X306790Y-471396D01*
X306410Y-471812D01*
X305967Y-472062D01*
X304383D01*
G01X305967D02*
X306917Y-474479D01*
G01X310750D02*
X310243Y-474396D01*
X309800Y-474062D01*
X309420Y-473562D01*
X309167Y-472979D01*
X309040Y-472312D01*
Y-471646D01*
X309167Y-470979D01*
X309420Y-470396D01*
X309800Y-469896D01*
X310243Y-469562D01*
X310750Y-469479D01*
X311257Y-469562D01*
X311700Y-469896D01*
X312080Y-470396D01*
X312333Y-470979D01*
X312460Y-471646D01*
Y-472312D01*
X312333Y-472979D01*
X312080Y-473562D01*
X311700Y-474062D01*
X311257Y-474396D01*
X310750Y-474479D01*
G01X314583Y-473479D02*
X314900Y-473979D01*
X315280Y-474312D01*
X315723Y-474479D01*
X316230Y-474312D01*
X316610Y-473979D01*
X316990Y-473479D01*
X317117Y-472812D01*
Y-469479D01*
G01X322217Y-474479D02*
X319683D01*
Y-469479D01*
X322217D01*
G01X321203Y-471896D02*
X319683D01*
G01X327443Y-469896D02*
X327063Y-469646D01*
X326620Y-469479D01*
X326113D01*
X325543Y-469729D01*
X325100Y-470146D01*
X324783Y-470646D01*
X324530Y-471479D01*
X324467Y-472229D01*
X324593Y-472979D01*
X324783Y-473479D01*
X325163Y-473979D01*
X325607Y-474312D01*
X326050Y-474479D01*
X326493D01*
X326937Y-474312D01*
X327317Y-474062D01*
X327633Y-473729D01*
G01X331150Y-469479D02*
Y-474479D01*
G01X329693Y-469479D02*
X332607D01*
G01X336250Y-474646D02*
X336123Y-474562D01*
Y-474396D01*
X336250Y-474312D01*
X336377Y-474396D01*
Y-474562D01*
X336250Y-474646D01*
G01Y-472396D02*
X336123Y-472312D01*
Y-472146D01*
X336250Y-472062D01*
X336377Y-472146D01*
Y-472312D01*
X336250Y-472396D01*
G01X408650Y-514479D02*
Y-539479D01*
G01X411283Y-516979D02*
Y-521979D01*
X413817D01*
G01X416890Y-516979D02*
X418410D01*
G01X417650D02*
Y-521979D01*
G01X416890D02*
X418410D01*
G01X423257Y-519312D02*
X423510Y-519062D01*
X423700Y-518646D01*
X423827Y-518062D01*
X423700Y-517562D01*
X423447Y-517229D01*
X423003Y-516979D01*
X421293D01*
Y-521979D01*
X423383D01*
X423827Y-521646D01*
X424080Y-521146D01*
X424207Y-520562D01*
X424080Y-519979D01*
X423700Y-519479D01*
X423257Y-519312D01*
X421293D01*
G01X427850Y-522146D02*
X427723Y-522062D01*
Y-521896D01*
X427850Y-521812D01*
X427977Y-521896D01*
Y-522062D01*
X427850Y-522146D01*
G01Y-519896D02*
X427723Y-519812D01*
Y-519646D01*
X427850Y-519562D01*
X427977Y-519646D01*
Y-519812D01*
X427850Y-519896D01*
G01X451650Y-514479D02*
Y-539479D01*
G01Y-489479D02*
Y-514479D01*
G01X456663Y-541646D02*
X456770Y-541521D01*
X456850Y-541312D01*
X456903Y-541021D01*
X456850Y-540771D01*
X456743Y-540604D01*
X456557Y-540479D01*
X455837D01*
Y-542979D01*
X456717D01*
X456903Y-542812D01*
X457010Y-542562D01*
X457063Y-542271D01*
X457010Y-541979D01*
X456850Y-541729D01*
X456663Y-541646D01*
X455837D01*
G01X459130Y-542979D02*
Y-541312D01*
G01Y-541604D02*
X459023Y-541437D01*
X458863Y-541354D01*
X458677Y-541312D01*
X458490Y-541396D01*
X458330Y-541562D01*
X458223Y-541812D01*
X458170Y-542146D01*
X458223Y-542479D01*
X458330Y-542729D01*
X458490Y-542896D01*
X458677Y-542979D01*
X458863Y-542937D01*
X459023Y-542812D01*
X459130Y-542646D01*
G01X460450Y-542687D02*
X460583Y-542854D01*
X460770Y-542979D01*
X460930D01*
X461090Y-542896D01*
X461197Y-542771D01*
X461250Y-542604D01*
X461223Y-542354D01*
X461117Y-542229D01*
X460637Y-541979D01*
X460530Y-541687D01*
X460583Y-541479D01*
X460690Y-541354D01*
X460850Y-541312D01*
X461010Y-541354D01*
X461170Y-541479D01*
G01X462650Y-541854D02*
X463503D01*
X463423Y-541562D01*
X463290Y-541396D01*
X463103Y-541312D01*
X462917Y-541354D01*
X462757Y-541479D01*
X462650Y-541771D01*
X462597Y-542021D01*
Y-542271D01*
X462650Y-542521D01*
X462783Y-542771D01*
X462943Y-542937D01*
X463130Y-542979D01*
X463317Y-542896D01*
X463503Y-542646D01*
G01X464770Y-542979D02*
Y-540479D01*
G01Y-541729D02*
X464903Y-541479D01*
X465063Y-541354D01*
X465223Y-541312D01*
X465463Y-541396D01*
X465623Y-541562D01*
X465730Y-541854D01*
Y-542187D01*
X465677Y-542521D01*
X465570Y-542771D01*
X465383Y-542937D01*
X465223Y-542979D01*
X465063Y-542937D01*
X464903Y-542812D01*
X464770Y-542604D01*
G01X467450Y-542979D02*
X467290Y-542937D01*
X467130Y-542771D01*
X467023Y-542479D01*
X466970Y-542146D01*
X467023Y-541812D01*
X467130Y-541521D01*
X467290Y-541354D01*
X467450Y-541312D01*
X467610Y-541354D01*
X467770Y-541521D01*
X467877Y-541812D01*
X467903Y-542146D01*
X467877Y-542479D01*
X467770Y-542771D01*
X467610Y-542937D01*
X467450Y-542979D01*
G01X470130D02*
Y-541312D01*
G01Y-541604D02*
X470023Y-541437D01*
X469863Y-541354D01*
X469677Y-541312D01*
X469490Y-541396D01*
X469330Y-541562D01*
X469223Y-541812D01*
X469170Y-542146D01*
X469223Y-542479D01*
X469330Y-542729D01*
X469490Y-542896D01*
X469677Y-542979D01*
X469863Y-542937D01*
X470023Y-542812D01*
X470130Y-542646D01*
G01X471477Y-542979D02*
Y-541312D01*
G01Y-541646D02*
X471610Y-541479D01*
X471743Y-541354D01*
X471930Y-541312D01*
X472063Y-541354D01*
X472223Y-541479D01*
G01X474530Y-540479D02*
Y-542979D01*
G01Y-542604D02*
X474423Y-542812D01*
X474263Y-542937D01*
X474077Y-542979D01*
X473863Y-542896D01*
X473703Y-542687D01*
X473597Y-542437D01*
X473570Y-542146D01*
X473597Y-541854D01*
X473703Y-541604D01*
X473863Y-541396D01*
X474077Y-541312D01*
X474263Y-541354D01*
X474397Y-541437D01*
X474530Y-541604D01*
G01X477917Y-542979D02*
Y-540479D01*
X478583D01*
X478797Y-540604D01*
X478930Y-540771D01*
X478983Y-541104D01*
X478930Y-541437D01*
X478770Y-541646D01*
X478583Y-541771D01*
X477917D01*
G01X478583D02*
X478983Y-542979D01*
G01X480250Y-541854D02*
X481103D01*
X481023Y-541562D01*
X480890Y-541396D01*
X480703Y-541312D01*
X480517Y-541354D01*
X480357Y-541479D01*
X480250Y-541771D01*
X480197Y-542021D01*
Y-542271D01*
X480250Y-542521D01*
X480383Y-542771D01*
X480543Y-542937D01*
X480730Y-542979D01*
X480917Y-542896D01*
X481103Y-542646D01*
G01X482370Y-541312D02*
X482850Y-542979D01*
X483330Y-541312D01*
G01X485050Y-543062D02*
X484997Y-543021D01*
Y-542937D01*
X485050Y-542896D01*
X485103Y-542937D01*
Y-543021D01*
X485050Y-543062D01*
G01X487250Y-542979D02*
X487437Y-542937D01*
X487650Y-542812D01*
X487783Y-542604D01*
X487837Y-542312D01*
X487783Y-542021D01*
X487623Y-541771D01*
X487383Y-541646D01*
X487117D01*
X486957Y-541562D01*
X486823Y-541354D01*
X486770Y-541062D01*
X486850Y-540771D01*
X487037Y-540562D01*
X487250Y-540479D01*
X487463Y-540562D01*
X487650Y-540771D01*
X487730Y-541062D01*
X487677Y-541354D01*
X487543Y-541562D01*
X487383Y-541646D01*
X487117D01*
X486877Y-541771D01*
X486717Y-542021D01*
X486663Y-542312D01*
X486717Y-542604D01*
X486850Y-542812D01*
X487063Y-542937D01*
X487250Y-542979D01*
G01X489663Y-541646D02*
X489770Y-541521D01*
X489850Y-541312D01*
X489903Y-541021D01*
X489850Y-540771D01*
X489743Y-540604D01*
X489557Y-540479D01*
X488837D01*
Y-542979D01*
X489717D01*
X489903Y-542812D01*
X490010Y-542562D01*
X490063Y-542271D01*
X490010Y-541979D01*
X489850Y-541729D01*
X489663Y-541646D01*
X488837D01*
G01X455550Y-516979D02*
Y-521979D01*
G01X454093Y-516979D02*
X457007D01*
G01X460650Y-521979D02*
X460270Y-521896D01*
X459890Y-521562D01*
X459637Y-520979D01*
X459510Y-520312D01*
X459637Y-519646D01*
X459890Y-519062D01*
X460270Y-518729D01*
X460650Y-518646D01*
X461030Y-518729D01*
X461410Y-519062D01*
X461663Y-519646D01*
X461727Y-520312D01*
X461663Y-520979D01*
X461410Y-521562D01*
X461030Y-521896D01*
X460650Y-521979D01*
G01X465750D02*
X465370Y-521896D01*
X464990Y-521562D01*
X464737Y-520979D01*
X464610Y-520312D01*
X464737Y-519646D01*
X464990Y-519062D01*
X465370Y-518729D01*
X465750Y-518646D01*
X466130Y-518729D01*
X466510Y-519062D01*
X466763Y-519646D01*
X466827Y-520312D01*
X466763Y-520979D01*
X466510Y-521562D01*
X466130Y-521896D01*
X465750Y-521979D01*
G01X470850D02*
Y-516979D01*
G01X475950Y-522146D02*
X475823Y-522062D01*
Y-521896D01*
X475950Y-521812D01*
X476077Y-521896D01*
Y-522062D01*
X475950Y-522146D01*
G01Y-519896D02*
X475823Y-519812D01*
Y-519646D01*
X475950Y-519562D01*
X476077Y-519646D01*
Y-519812D01*
X475950Y-519896D01*
G01X454283Y-496979D02*
Y-491979D01*
X455867D01*
X456373Y-492229D01*
X456690Y-492562D01*
X456817Y-493229D01*
X456690Y-493896D01*
X456310Y-494312D01*
X455867Y-494562D01*
X454283D01*
G01X455867D02*
X456817Y-496979D01*
G01X461917D02*
X459383D01*
Y-491979D01*
X461917D01*
G01X460903Y-494396D02*
X459383D01*
G01X464167Y-491979D02*
X465750Y-496979D01*
X467333Y-491979D01*
G01X470850Y-497146D02*
X470723Y-497062D01*
Y-496896D01*
X470850Y-496812D01*
X470977Y-496896D01*
Y-497062D01*
X470850Y-497146D01*
G01Y-494896D02*
X470723Y-494812D01*
Y-494646D01*
X470850Y-494562D01*
X470977Y-494646D01*
Y-494812D01*
X470850Y-494896D01*
G01X-984580Y-698988D02*
Y4193602D01*
X5868320D01*
Y-698988D01*
X-984580D01*
G01X7723Y-521204D02*
X7253Y-520889D01*
X6705Y-520679D01*
X6078D01*
X5373Y-520994D01*
X4825Y-521519D01*
X4433Y-522149D01*
X4120Y-523199D01*
X4042Y-524144D01*
X4198Y-525089D01*
X4433Y-525719D01*
X4903Y-526349D01*
X5452Y-526769D01*
X6000Y-526979D01*
X6548D01*
X7097Y-526769D01*
X7567Y-526454D01*
X7958Y-526034D01*
G01X11360Y-520679D02*
X13240D01*
G01X12300D02*
Y-526979D01*
G01X11360D02*
X13240D01*
G01X18600Y-520679D02*
Y-526979D01*
G01X16798Y-520679D02*
X20402D01*
G01X24900Y-526979D02*
Y-524144D01*
X23333Y-520679D01*
G01X26467D02*
X24900Y-524144D01*
G01X35777Y-525719D02*
X36247Y-526454D01*
X36873Y-526874D01*
X37578Y-526979D01*
X38205Y-526874D01*
X38832Y-526349D01*
X39223Y-525719D01*
X39302Y-525089D01*
X39145Y-524354D01*
X38597Y-523829D01*
X38048Y-523619D01*
X37343D01*
G01X38048D02*
X38518Y-523304D01*
X38910Y-522779D01*
X39067Y-522149D01*
X38910Y-521519D01*
X38518Y-520994D01*
X37813Y-520679D01*
X37108Y-520784D01*
X36403Y-521204D01*
G01X42077Y-525719D02*
X42547Y-526454D01*
X43173Y-526874D01*
X43878Y-526979D01*
X44505Y-526874D01*
X45132Y-526349D01*
X45523Y-525719D01*
X45602Y-525089D01*
X45445Y-524354D01*
X44897Y-523829D01*
X44348Y-523619D01*
X43643D01*
G01X44348D02*
X44818Y-523304D01*
X45210Y-522779D01*
X45367Y-522149D01*
X45210Y-521519D01*
X44818Y-520994D01*
X44113Y-520679D01*
X43408Y-520784D01*
X42703Y-521204D01*
G01X48377Y-525719D02*
X48847Y-526454D01*
X49473Y-526874D01*
X50178Y-526979D01*
X50805Y-526874D01*
X51432Y-526349D01*
X51823Y-525719D01*
X51902Y-525089D01*
X51745Y-524354D01*
X51197Y-523829D01*
X50648Y-523619D01*
X49943D01*
G01X50648D02*
X51118Y-523304D01*
X51510Y-522779D01*
X51667Y-522149D01*
X51510Y-521519D01*
X51118Y-520994D01*
X50413Y-520679D01*
X49708Y-520784D01*
X49003Y-521204D01*
G01X56243Y-526979D02*
X56400Y-525614D01*
X56635Y-524459D01*
X56948Y-523409D01*
X57340Y-522254D01*
X57967Y-520679D01*
X54833D01*
G01X62543Y-526979D02*
X62700Y-525614D01*
X62935Y-524459D01*
X63248Y-523409D01*
X63640Y-522254D01*
X64267Y-520679D01*
X61133D01*
G01X68843Y-528134D02*
X69157Y-526769D01*
G01X75300Y-520679D02*
Y-526979D01*
G01X73498Y-520679D02*
X77102D01*
G01X79642Y-526979D02*
X81600Y-520679D01*
X83558Y-526979D01*
G01X82853Y-524774D02*
X80347D01*
G01X86960Y-520679D02*
X88840D01*
G01X87900D02*
Y-526979D01*
G01X86960D02*
X88840D01*
G01X91850Y-520679D02*
X92947Y-526979D01*
X94200Y-520679D01*
X95453Y-526979D01*
X96550Y-520679D01*
G01X98542Y-526979D02*
X100500Y-520679D01*
X102458Y-526979D01*
G01X101753Y-524774D02*
X99247D01*
G01X104998Y-526979D02*
Y-520679D01*
X108602Y-526979D01*
Y-520679D01*
G01X119008Y-529079D02*
X118225Y-528029D01*
X117833Y-526979D01*
Y-522779D01*
X118225Y-521729D01*
X119008Y-520679D01*
G01X130433Y-526979D02*
Y-520679D01*
X132392D01*
X133018Y-520994D01*
X133410Y-521414D01*
X133567Y-522254D01*
X133410Y-523094D01*
X132940Y-523619D01*
X132392Y-523934D01*
X130433D01*
G01X132392D02*
X133567Y-526979D01*
G01X138300Y-527189D02*
X138143Y-527084D01*
Y-526874D01*
X138300Y-526769D01*
X138457Y-526874D01*
Y-527084D01*
X138300Y-527189D01*
G01X144600Y-526979D02*
X143973Y-526874D01*
X143425Y-526454D01*
X142955Y-525824D01*
X142642Y-525089D01*
X142485Y-524249D01*
Y-523409D01*
X142642Y-522569D01*
X142955Y-521834D01*
X143425Y-521204D01*
X143973Y-520784D01*
X144600Y-520679D01*
X145227Y-520784D01*
X145775Y-521204D01*
X146245Y-521834D01*
X146558Y-522569D01*
X146715Y-523409D01*
Y-524249D01*
X146558Y-525089D01*
X146245Y-525824D01*
X145775Y-526454D01*
X145227Y-526874D01*
X144600Y-526979D01*
G01X150900Y-527189D02*
X150743Y-527084D01*
Y-526874D01*
X150900Y-526769D01*
X151057Y-526874D01*
Y-527084D01*
X150900Y-527189D01*
G01X158923Y-521204D02*
X158453Y-520889D01*
X157905Y-520679D01*
X157278D01*
X156573Y-520994D01*
X156025Y-521519D01*
X155633Y-522149D01*
X155320Y-523199D01*
X155242Y-524144D01*
X155398Y-525089D01*
X155633Y-525719D01*
X156103Y-526349D01*
X156652Y-526769D01*
X157200Y-526979D01*
X157748D01*
X158297Y-526769D01*
X158767Y-526454D01*
X159158Y-526034D01*
G01X163500Y-527189D02*
X163343Y-527084D01*
Y-526874D01*
X163500Y-526769D01*
X163657Y-526874D01*
Y-527084D01*
X163500Y-527189D01*
G01X170192Y-529079D02*
X170975Y-528029D01*
X171367Y-526979D01*
Y-522779D01*
X170975Y-521729D01*
X170192Y-520679D01*
G01X6470Y-513829D02*
X8037D01*
Y-515719D01*
X7567Y-516349D01*
X7018Y-516769D01*
X6235Y-516979D01*
X5452Y-516769D01*
X4903Y-516349D01*
X4433Y-515719D01*
X4120Y-514984D01*
X3963Y-514144D01*
Y-513409D01*
X4120Y-512779D01*
X4433Y-512044D01*
X4903Y-511414D01*
X5373Y-510994D01*
X6000Y-510679D01*
X6548D01*
X7175Y-510889D01*
X7645Y-511309D01*
G01X10577Y-510679D02*
Y-515194D01*
X10890Y-516139D01*
X11517Y-516769D01*
X12300Y-516979D01*
X13083Y-516769D01*
X13710Y-516139D01*
X14023Y-515194D01*
Y-510679D01*
G01X17660D02*
X19540D01*
G01X18600D02*
Y-516979D01*
G01X17660D02*
X19540D01*
G01X23255Y-516139D02*
X23882Y-516664D01*
X24587Y-516979D01*
X25213D01*
X25840Y-516664D01*
X26310Y-516139D01*
X26545Y-515404D01*
X26388Y-514669D01*
X25997Y-514039D01*
X25292Y-513619D01*
X24352Y-513409D01*
X23803Y-512989D01*
X23568Y-512254D01*
X23725Y-511519D01*
X24117Y-510994D01*
X24665Y-510679D01*
X25213D01*
X25762Y-510889D01*
X26232Y-511414D01*
G01X29555Y-516979D02*
Y-510679D01*
G01X32845D02*
Y-516979D01*
G01Y-513829D02*
X29555D01*
G01X35542Y-516979D02*
X37500Y-510679D01*
X39458Y-516979D01*
G01X38753Y-514774D02*
X36247D01*
G01X41998Y-516979D02*
Y-510679D01*
X45602Y-516979D01*
Y-510679D01*
G01X54677Y-516979D02*
Y-510679D01*
X56243D01*
X56870Y-510994D01*
X57340Y-511414D01*
X57732Y-512044D01*
X58045Y-512779D01*
X58123Y-513829D01*
X58045Y-514879D01*
X57732Y-515614D01*
X57340Y-516244D01*
X56870Y-516664D01*
X56243Y-516979D01*
X54677D01*
G01X61760Y-510679D02*
X63640D01*
G01X62700D02*
Y-516979D01*
G01X61760D02*
X63640D01*
G01X67355Y-516139D02*
X67982Y-516664D01*
X68687Y-516979D01*
X69313D01*
X69940Y-516664D01*
X70410Y-516139D01*
X70645Y-515404D01*
X70488Y-514669D01*
X70097Y-514039D01*
X69392Y-513619D01*
X68452Y-513409D01*
X67903Y-512989D01*
X67668Y-512254D01*
X67825Y-511519D01*
X68217Y-510994D01*
X68765Y-510679D01*
X69313D01*
X69862Y-510889D01*
X70332Y-511414D01*
G01X75300Y-510679D02*
Y-516979D01*
G01X73498Y-510679D02*
X77102D01*
G01X81600Y-517189D02*
X81443Y-517084D01*
Y-516874D01*
X81600Y-516769D01*
X81757Y-516874D01*
Y-517084D01*
X81600Y-517189D01*
G01X87743Y-518134D02*
X88057Y-516769D01*
G01X94200Y-510679D02*
Y-516979D01*
G01X92398Y-510679D02*
X96002D01*
G01X98542Y-516979D02*
X100500Y-510679D01*
X102458Y-516979D01*
G01X101753Y-514774D02*
X99247D01*
G01X106800Y-516979D02*
X106173Y-516874D01*
X105625Y-516454D01*
X105155Y-515824D01*
X104842Y-515089D01*
X104685Y-514249D01*
Y-513409D01*
X104842Y-512569D01*
X105155Y-511834D01*
X105625Y-511204D01*
X106173Y-510784D01*
X106800Y-510679D01*
X107427Y-510784D01*
X107975Y-511204D01*
X108445Y-511834D01*
X108758Y-512569D01*
X108915Y-513409D01*
Y-514249D01*
X108758Y-515089D01*
X108445Y-515824D01*
X107975Y-516454D01*
X107427Y-516874D01*
X106800Y-516979D01*
G01X113100D02*
Y-514144D01*
X111533Y-510679D01*
G01X114667D02*
X113100Y-514144D01*
G01X117677Y-510679D02*
Y-515194D01*
X117990Y-516139D01*
X118617Y-516769D01*
X119400Y-516979D01*
X120183Y-516769D01*
X120810Y-516139D01*
X121123Y-515194D01*
Y-510679D01*
G01X123742Y-516979D02*
X125700Y-510679D01*
X127658Y-516979D01*
G01X126953Y-514774D02*
X124447D01*
G01X130198Y-516979D02*
Y-510679D01*
X133802Y-516979D01*
Y-510679D01*
G01X4198Y-506979D02*
Y-500679D01*
X7802Y-506979D01*
Y-500679D01*
G01X12300Y-506979D02*
X11673Y-506874D01*
X11125Y-506454D01*
X10655Y-505824D01*
X10342Y-505089D01*
X10185Y-504249D01*
Y-503409D01*
X10342Y-502569D01*
X10655Y-501834D01*
X11125Y-501204D01*
X11673Y-500784D01*
X12300Y-500679D01*
X12927Y-500784D01*
X13475Y-501204D01*
X13945Y-501834D01*
X14258Y-502569D01*
X14415Y-503409D01*
Y-504249D01*
X14258Y-505089D01*
X13945Y-505824D01*
X13475Y-506454D01*
X12927Y-506874D01*
X12300Y-506979D01*
G01X18600Y-507189D02*
X18443Y-507084D01*
Y-506874D01*
X18600Y-506769D01*
X18757Y-506874D01*
Y-507084D01*
X18600Y-507189D01*
G01X23412Y-501729D02*
X23882Y-501099D01*
X24430Y-500784D01*
X25057Y-500679D01*
X25840Y-500889D01*
X26388Y-501414D01*
X26545Y-502044D01*
X26467Y-502674D01*
X26153Y-503199D01*
X24587Y-504249D01*
X23882Y-504984D01*
X23412Y-506034D01*
X23255Y-506979D01*
X26545D01*
G01X31200D02*
Y-500679D01*
X30260Y-501939D01*
G01Y-506979D02*
X32140D01*
G01X37500D02*
Y-500679D01*
X36560Y-501939D01*
G01Y-506979D02*
X38440D01*
G01X43643Y-508134D02*
X43957Y-506769D01*
G01X47750Y-500679D02*
X48847Y-506979D01*
X50100Y-500679D01*
X51353Y-506979D01*
X52450Y-500679D01*
G01X57967Y-506979D02*
X54833D01*
Y-500679D01*
X57967D01*
G01X56713Y-503724D02*
X54833D01*
G01X60898Y-506979D02*
Y-500679D01*
X64502Y-506979D01*
Y-500679D01*
G01X67355Y-506979D02*
Y-500679D01*
G01X70645D02*
Y-506979D01*
G01Y-503829D02*
X67355D01*
G01X73577Y-500679D02*
Y-505194D01*
X73890Y-506139D01*
X74517Y-506769D01*
X75300Y-506979D01*
X76083Y-506769D01*
X76710Y-506139D01*
X77023Y-505194D01*
Y-500679D01*
G01X79642Y-506979D02*
X81600Y-500679D01*
X83558Y-506979D01*
G01X82853Y-504774D02*
X80347D01*
G01X92712Y-501729D02*
X93182Y-501099D01*
X93730Y-500784D01*
X94357Y-500679D01*
X95140Y-500889D01*
X95688Y-501414D01*
X95845Y-502044D01*
X95767Y-502674D01*
X95453Y-503199D01*
X93887Y-504249D01*
X93182Y-504984D01*
X92712Y-506034D01*
X92555Y-506979D01*
X95845D01*
G01X98698D02*
Y-500679D01*
X102302Y-506979D01*
Y-500679D01*
G01X105077Y-506979D02*
Y-500679D01*
X106643D01*
X107270Y-500994D01*
X107740Y-501414D01*
X108132Y-502044D01*
X108445Y-502779D01*
X108523Y-503829D01*
X108445Y-504879D01*
X108132Y-505614D01*
X107740Y-506244D01*
X107270Y-506664D01*
X106643Y-506979D01*
X105077D01*
G01X117833D02*
Y-500679D01*
X119792D01*
X120418Y-500994D01*
X120810Y-501414D01*
X120967Y-502254D01*
X120810Y-503094D01*
X120340Y-503619D01*
X119792Y-503934D01*
X117833D01*
G01X119792D02*
X120967Y-506979D01*
G01X123977D02*
Y-500679D01*
X125543D01*
X126170Y-500994D01*
X126640Y-501414D01*
X127032Y-502044D01*
X127345Y-502779D01*
X127423Y-503829D01*
X127345Y-504879D01*
X127032Y-505614D01*
X126640Y-506244D01*
X126170Y-506664D01*
X125543Y-506979D01*
X123977D01*
G01X132000Y-507189D02*
X131843Y-507084D01*
Y-506874D01*
X132000Y-506769D01*
X132157Y-506874D01*
Y-507084D01*
X132000Y-507189D01*
G01X28300Y-494279D02*
X25780Y-493862D01*
X23575Y-492196D01*
X21685Y-489696D01*
X20425Y-486779D01*
X19795Y-483446D01*
Y-480112D01*
X20425Y-476779D01*
X21685Y-473862D01*
X23575Y-471363D01*
X25780Y-469696D01*
X28300Y-469279D01*
X30820Y-469696D01*
X33025Y-471363D01*
X34915Y-473862D01*
X36175Y-476779D01*
X36805Y-480112D01*
Y-483446D01*
X36175Y-486779D01*
X34915Y-489696D01*
X33025Y-492196D01*
X30820Y-493862D01*
X28300Y-494279D01*
G01X30820Y-487612D02*
X34600Y-494279D01*
G01X48145Y-477613D02*
Y-489279D01*
X49405Y-492196D01*
X51295Y-493862D01*
X53500Y-494279D01*
X55705Y-493862D01*
X57595Y-492196D01*
X58855Y-489279D01*
G01Y-494279D02*
Y-477613D01*
G01X84370Y-494279D02*
Y-477613D01*
G01Y-480529D02*
X83110Y-478863D01*
X81220Y-478029D01*
X79015Y-477613D01*
X76810Y-478446D01*
X74920Y-480112D01*
X73660Y-482613D01*
X73030Y-485946D01*
X73660Y-489279D01*
X74920Y-491780D01*
X76810Y-493446D01*
X79015Y-494279D01*
X81220Y-493862D01*
X83110Y-492613D01*
X84370Y-490946D01*
G01X98545Y-494279D02*
Y-477613D01*
G01Y-481779D02*
X99805Y-479696D01*
X101695Y-478029D01*
X104215Y-477613D01*
X106420Y-478029D01*
X108310Y-479696D01*
X109255Y-482613D01*
Y-494279D01*
G01X129100Y-469279D02*
Y-494279D01*
G01X124690Y-477613D02*
X133510D01*
G01X159970Y-494279D02*
Y-477613D01*
G01Y-480529D02*
X158710Y-478863D01*
X156820Y-478029D01*
X154615Y-477613D01*
X152410Y-478446D01*
X150520Y-480112D01*
X149260Y-482613D01*
X148630Y-485946D01*
X149260Y-489279D01*
X150520Y-491780D01*
X152410Y-493446D01*
X154615Y-494279D01*
X156820Y-493862D01*
X158710Y-492613D01*
X159970Y-490946D01*
G01X206579Y-508436D02*
Y-500436D01*
X209179Y-507103D01*
X211779Y-500436D01*
Y-508436D01*
G01X214679D02*
X217179Y-500436D01*
X219679Y-508436D01*
G01X218779Y-505636D02*
X215579D01*
G01X223079Y-507370D02*
X223879Y-508036D01*
X224779Y-508436D01*
X225579D01*
X226379Y-508036D01*
X226979Y-507370D01*
X227279Y-506436D01*
X227079Y-505503D01*
X226579Y-504703D01*
X225679Y-504169D01*
X224479Y-503903D01*
X223779Y-503369D01*
X223479Y-502436D01*
X223679Y-501503D01*
X224179Y-500836D01*
X224879Y-500436D01*
X225579D01*
X226279Y-500703D01*
X226879Y-501369D01*
G01X230979Y-508436D02*
Y-500436D01*
G01X234779D02*
X230979Y-505370D01*
G01X235379Y-508436D02*
X232679Y-503103D01*
G01X239879Y-505769D02*
X242479D01*
G01X249179Y-500436D02*
Y-508436D01*
G01X246879Y-500436D02*
X251479D01*
G01X257179Y-508436D02*
X256379Y-508303D01*
X255679Y-507769D01*
X255079Y-506969D01*
X254679Y-506036D01*
X254479Y-504969D01*
Y-503903D01*
X254679Y-502836D01*
X255079Y-501903D01*
X255679Y-501103D01*
X256379Y-500569D01*
X257179Y-500436D01*
X257979Y-500569D01*
X258679Y-501103D01*
X259279Y-501903D01*
X259679Y-502836D01*
X259879Y-503903D01*
Y-504969D01*
X259679Y-506036D01*
X259279Y-506969D01*
X258679Y-507769D01*
X257979Y-508303D01*
X257179Y-508436D01*
G01X263179D02*
Y-500436D01*
X265579D01*
X266379Y-500836D01*
X266979Y-501769D01*
X267179Y-502836D01*
X266979Y-503903D01*
X266479Y-504703D01*
X265579Y-505103D01*
X263179D01*
G01X199650Y-473979D02*
Y-481979D01*
X203650D01*
G01X211450D02*
Y-476646D01*
G01Y-477579D02*
X211050Y-477046D01*
X210450Y-476779D01*
X209750Y-476646D01*
X209050Y-476912D01*
X208450Y-477446D01*
X208050Y-478246D01*
X207850Y-479312D01*
X208050Y-480379D01*
X208450Y-481179D01*
X209050Y-481712D01*
X209750Y-481979D01*
X210450Y-481846D01*
X211050Y-481446D01*
X211450Y-480913D01*
G01X215550Y-484379D02*
X216150Y-484646D01*
X216950Y-484379D01*
X217450Y-483846D01*
X217850Y-483179D01*
X218450Y-481046D01*
X219750Y-476646D01*
G01X216550D02*
X218450Y-481046D01*
G01X224150Y-478379D02*
X227350D01*
X227050Y-477446D01*
X226550Y-476912D01*
X225850Y-476646D01*
X225150Y-476779D01*
X224550Y-477179D01*
X224150Y-478112D01*
X223950Y-478913D01*
Y-479712D01*
X224150Y-480512D01*
X224650Y-481312D01*
X225250Y-481846D01*
X225950Y-481979D01*
X226650Y-481712D01*
X227350Y-480913D01*
G01X232250Y-481979D02*
Y-476646D01*
G01Y-477712D02*
X232750Y-477179D01*
X233250Y-476779D01*
X233950Y-476646D01*
X234450Y-476779D01*
X235050Y-477179D01*
G01X223350Y-531979D02*
Y-523979D01*
X227950Y-531979D01*
Y-523979D01*
G01X233650Y-526646D02*
Y-531979D01*
G01Y-524512D02*
X233450Y-524379D01*
Y-524112D01*
X233650Y-523979D01*
X233850Y-524112D01*
Y-524379D01*
X233650Y-524512D01*
G01X239950Y-531979D02*
Y-526646D01*
G01Y-527979D02*
X240350Y-527312D01*
X240950Y-526779D01*
X241750Y-526646D01*
X242450Y-526779D01*
X243050Y-527312D01*
X243350Y-528246D01*
Y-531979D01*
G01X251450D02*
Y-526646D01*
G01Y-527579D02*
X251050Y-527046D01*
X250450Y-526779D01*
X249750Y-526646D01*
X249050Y-526912D01*
X248450Y-527446D01*
X248050Y-528246D01*
X247850Y-529312D01*
X248050Y-530379D01*
X248450Y-531179D01*
X249050Y-531712D01*
X249750Y-531979D01*
X250450Y-531846D01*
X251050Y-531446D01*
X251450Y-530913D01*
G01X326250Y-525312D02*
X326850Y-524512D01*
X327550Y-524112D01*
X328350Y-523979D01*
X329350Y-524246D01*
X330050Y-524912D01*
X330250Y-525712D01*
X330150Y-526513D01*
X329750Y-527179D01*
X327750Y-528512D01*
X326850Y-529446D01*
X326250Y-530779D01*
X326050Y-531979D01*
X330250D01*
G01X336150Y-523979D02*
X335350Y-524246D01*
X334750Y-524912D01*
X334350Y-525712D01*
X334050Y-526779D01*
X333950Y-527979D01*
X334050Y-529179D01*
X334350Y-530246D01*
X334750Y-531046D01*
X335350Y-531712D01*
X336150Y-531979D01*
X336950Y-531712D01*
X337550Y-531046D01*
X337950Y-530246D01*
X338250Y-529179D01*
X338350Y-527979D01*
X338250Y-526779D01*
X337950Y-525712D01*
X337550Y-524912D01*
X336950Y-524246D01*
X336150Y-523979D01*
G01X342250Y-525312D02*
X342850Y-524512D01*
X343550Y-524112D01*
X344350Y-523979D01*
X345350Y-524246D01*
X346050Y-524912D01*
X346250Y-525712D01*
X346150Y-526513D01*
X345750Y-527179D01*
X343750Y-528512D01*
X342850Y-529446D01*
X342250Y-530779D01*
X342050Y-531979D01*
X346250D01*
G01X349950Y-530379D02*
X350550Y-531312D01*
X351350Y-531846D01*
X352250Y-531979D01*
X353050Y-531846D01*
X353850Y-531179D01*
X354350Y-530379D01*
X354450Y-529579D01*
X354250Y-528646D01*
X353550Y-527979D01*
X352850Y-527712D01*
X351950D01*
G01X352850D02*
X353450Y-527312D01*
X353950Y-526646D01*
X354150Y-525846D01*
X353950Y-525046D01*
X353450Y-524379D01*
X352550Y-523979D01*
X351650Y-524112D01*
X350750Y-524646D01*
G01X358350Y-532246D02*
X361950Y-523979D01*
G01X368150D02*
X367350Y-524246D01*
X366750Y-524912D01*
X366350Y-525712D01*
X366050Y-526779D01*
X365950Y-527979D01*
X366050Y-529179D01*
X366350Y-530246D01*
X366750Y-531046D01*
X367350Y-531712D01*
X368150Y-531979D01*
X368950Y-531712D01*
X369550Y-531046D01*
X369950Y-530246D01*
X370250Y-529179D01*
X370350Y-527979D01*
X370250Y-526779D01*
X369950Y-525712D01*
X369550Y-524912D01*
X368950Y-524246D01*
X368150Y-523979D01*
G01X373950Y-530379D02*
X374550Y-531312D01*
X375350Y-531846D01*
X376250Y-531979D01*
X377050Y-531846D01*
X377850Y-531179D01*
X378350Y-530379D01*
X378450Y-529579D01*
X378250Y-528646D01*
X377550Y-527979D01*
X376850Y-527712D01*
X375950D01*
G01X376850D02*
X377450Y-527312D01*
X377950Y-526646D01*
X378150Y-525846D01*
X377950Y-525046D01*
X377450Y-524379D01*
X376550Y-523979D01*
X375650Y-524112D01*
X374750Y-524646D01*
G01X382350Y-532246D02*
X385950Y-523979D01*
G01X390250Y-525312D02*
X390850Y-524512D01*
X391550Y-524112D01*
X392350Y-523979D01*
X393350Y-524246D01*
X394050Y-524912D01*
X394250Y-525712D01*
X394150Y-526513D01*
X393750Y-527179D01*
X391750Y-528512D01*
X390850Y-529446D01*
X390250Y-530779D01*
X390050Y-531979D01*
X394250D01*
G01X401350D02*
Y-523979D01*
X397650Y-529712D01*
X402650D01*
G01X325950Y-506979D02*
Y-498979D01*
X327950D01*
X328750Y-499379D01*
X329350Y-499912D01*
X329850Y-500712D01*
X330250Y-501646D01*
X330350Y-502979D01*
X330250Y-504312D01*
X329850Y-505246D01*
X329350Y-506046D01*
X328750Y-506579D01*
X327950Y-506979D01*
X325950D01*
G01X333650D02*
X336150Y-498979D01*
X338650Y-506979D01*
G01X337750Y-504179D02*
X334550D01*
G01X344150Y-498979D02*
X343350Y-499246D01*
X342750Y-499912D01*
X342350Y-500712D01*
X342050Y-501779D01*
X341950Y-502979D01*
X342050Y-504179D01*
X342350Y-505246D01*
X342750Y-506046D01*
X343350Y-506712D01*
X344150Y-506979D01*
X344950Y-506712D01*
X345550Y-506046D01*
X345950Y-505246D01*
X346250Y-504179D01*
X346350Y-502979D01*
X346250Y-501779D01*
X345950Y-500712D01*
X345550Y-499912D01*
X344950Y-499246D01*
X344150Y-498979D01*
G01X350250Y-506979D02*
Y-498979D01*
X354050D01*
G01X352650Y-502846D02*
X350250D01*
G01X360150Y-498979D02*
X359350Y-499246D01*
X358750Y-499912D01*
X358350Y-500712D01*
X358050Y-501779D01*
X357950Y-502979D01*
X358050Y-504179D01*
X358350Y-505246D01*
X358750Y-506046D01*
X359350Y-506712D01*
X360150Y-506979D01*
X360950Y-506712D01*
X361550Y-506046D01*
X361950Y-505246D01*
X362250Y-504179D01*
X362350Y-502979D01*
X362250Y-501779D01*
X361950Y-500712D01*
X361550Y-499912D01*
X360950Y-499246D01*
X360150Y-498979D01*
G01X368150D02*
Y-506979D01*
G01X365850Y-498979D02*
X370450D01*
G01X373550Y-506979D02*
Y-498979D01*
X376150Y-505646D01*
X378750Y-498979D01*
Y-506979D01*
G01X384950Y-502712D02*
X385350Y-502312D01*
X385650Y-501646D01*
X385850Y-500712D01*
X385650Y-499912D01*
X385250Y-499379D01*
X384550Y-498979D01*
X381850D01*
Y-506979D01*
X385150D01*
X385850Y-506446D01*
X386250Y-505646D01*
X386450Y-504712D01*
X386250Y-503779D01*
X385650Y-502979D01*
X384950Y-502712D01*
X381850D01*
G01X390950Y-498979D02*
X393350D01*
G01X392150D02*
Y-506979D01*
G01X390950D02*
X393350D01*
G01X398150Y-505379D02*
X398650Y-506179D01*
X399250Y-506712D01*
X399950Y-506979D01*
X400750Y-506712D01*
X401350Y-506179D01*
X401950Y-505379D01*
X402150Y-504312D01*
Y-498979D01*
G01X408150D02*
X407350Y-499246D01*
X406750Y-499912D01*
X406350Y-500712D01*
X406050Y-501779D01*
X405950Y-502979D01*
X406050Y-504179D01*
X406350Y-505246D01*
X406750Y-506046D01*
X407350Y-506712D01*
X408150Y-506979D01*
X408950Y-506712D01*
X409550Y-506046D01*
X409950Y-505246D01*
X410250Y-504179D01*
X410350Y-502979D01*
X410250Y-501779D01*
X409950Y-500712D01*
X409550Y-499912D01*
X408950Y-499246D01*
X408150Y-498979D01*
G01X343750Y-481979D02*
Y-473979D01*
X347550D01*
G01X346150Y-477846D02*
X343750D01*
G01X353650Y-473979D02*
X352850Y-474246D01*
X352250Y-474912D01*
X351850Y-475712D01*
X351550Y-476779D01*
X351450Y-477979D01*
X351550Y-479179D01*
X351850Y-480246D01*
X352250Y-481046D01*
X352850Y-481712D01*
X353650Y-481979D01*
X354450Y-481712D01*
X355050Y-481046D01*
X355450Y-480246D01*
X355750Y-479179D01*
X355850Y-477979D01*
X355750Y-476779D01*
X355450Y-475712D01*
X355050Y-474912D01*
X354450Y-474246D01*
X353650Y-473979D01*
G01X361650D02*
Y-481979D01*
G01X359350Y-473979D02*
X363950D01*
G01X366650Y-484646D02*
X372650D01*
G01X375050Y-481979D02*
Y-473979D01*
X377650Y-480646D01*
X380250Y-473979D01*
Y-481979D01*
G01X386450Y-477712D02*
X386850Y-477312D01*
X387150Y-476646D01*
X387350Y-475712D01*
X387150Y-474912D01*
X386750Y-474379D01*
X386050Y-473979D01*
X383350D01*
Y-481979D01*
X386650D01*
X387350Y-481446D01*
X387750Y-480646D01*
X387950Y-479712D01*
X387750Y-478779D01*
X387150Y-477979D01*
X386450Y-477712D01*
X383350D01*
G01X390650Y-484646D02*
X396650D01*
G01X403650Y-481979D02*
X399650D01*
Y-473979D01*
X403650D01*
G01X402050Y-477846D02*
X399650D01*
G01X407050Y-481979D02*
Y-473979D01*
X409650Y-480646D01*
X412250Y-473979D01*
Y-481979D01*
G01X417650D02*
X418350Y-481846D01*
X419150Y-481446D01*
X419650Y-480779D01*
X419850Y-479846D01*
X419650Y-478913D01*
X419050Y-478112D01*
X418150Y-477712D01*
X417150D01*
X416550Y-477446D01*
X416050Y-476779D01*
X415850Y-475846D01*
X416150Y-474912D01*
X416850Y-474246D01*
X417650Y-473979D01*
X418450Y-474246D01*
X419150Y-474912D01*
X419450Y-475846D01*
X419250Y-476779D01*
X418750Y-477446D01*
X418150Y-477712D01*
X417150D01*
X416250Y-478112D01*
X415650Y-478913D01*
X415450Y-479846D01*
X415650Y-480779D01*
X416150Y-481446D01*
X416950Y-481846D01*
X417650Y-481979D01*
G01X423950Y-481046D02*
X424650Y-481712D01*
X425450Y-481979D01*
X426250Y-481712D01*
X426950Y-480913D01*
X427450Y-479712D01*
X427650Y-478512D01*
Y-477046D01*
X427450Y-475846D01*
X426950Y-474779D01*
X426350Y-474246D01*
X425650Y-473979D01*
X424850Y-474246D01*
X424250Y-474779D01*
X423850Y-475579D01*
X423650Y-476646D01*
X423850Y-477579D01*
X424350Y-478512D01*
X424950Y-479046D01*
X425650Y-479179D01*
X426450Y-478913D01*
X427050Y-478246D01*
X427650Y-477046D01*
G01X433650Y-473979D02*
X432850Y-474246D01*
X432250Y-474912D01*
X431850Y-475712D01*
X431550Y-476779D01*
X431450Y-477979D01*
X431550Y-479179D01*
X431850Y-480246D01*
X432250Y-481046D01*
X432850Y-481712D01*
X433650Y-481979D01*
X434450Y-481712D01*
X435050Y-481046D01*
X435450Y-480246D01*
X435750Y-479179D01*
X435850Y-477979D01*
X435750Y-476779D01*
X435450Y-475712D01*
X435050Y-474912D01*
X434450Y-474246D01*
X433650Y-473979D01*
G01X439450Y-481979D02*
Y-473979D01*
G01X443250D02*
X439450Y-478913D01*
G01X443850Y-481979D02*
X441150Y-476646D01*
G01X414650Y-534979D02*
Y-526979D01*
X413450Y-528579D01*
G01Y-534979D02*
X415850D01*
G01X420750Y-531646D02*
X421450Y-530712D01*
X422050Y-530179D01*
X422850Y-529912D01*
X423550Y-530179D01*
X424050Y-530712D01*
X424450Y-531512D01*
X424550Y-532446D01*
X424450Y-533246D01*
X424050Y-534046D01*
X423450Y-534712D01*
X422750Y-534979D01*
X421950Y-534712D01*
X421250Y-533913D01*
X420850Y-532712D01*
X420750Y-531379D01*
X420950Y-529646D01*
X421250Y-528712D01*
X421750Y-527779D01*
X422450Y-527112D01*
X423150Y-526979D01*
X423850Y-527246D01*
X424350Y-527912D01*
G01X430650Y-535246D02*
X430450Y-535112D01*
Y-534846D01*
X430650Y-534712D01*
X430850Y-534846D01*
Y-535112D01*
X430650Y-535246D01*
G01X436750Y-531646D02*
X437450Y-530712D01*
X438050Y-530179D01*
X438850Y-529912D01*
X439550Y-530179D01*
X440050Y-530712D01*
X440450Y-531512D01*
X440550Y-532446D01*
X440450Y-533246D01*
X440050Y-534046D01*
X439450Y-534712D01*
X438750Y-534979D01*
X437950Y-534712D01*
X437250Y-533913D01*
X436850Y-532712D01*
X436750Y-531379D01*
X436950Y-529646D01*
X437250Y-528712D01*
X437750Y-527779D01*
X438450Y-527112D01*
X439150Y-526979D01*
X439850Y-527246D01*
X440350Y-527912D01*
G01X459650Y-534979D02*
Y-526979D01*
X458450Y-528579D01*
G01Y-534979D02*
X460850D01*
G01X467450D02*
X467650Y-533246D01*
X467950Y-531779D01*
X468350Y-530446D01*
X468850Y-528979D01*
X469650Y-526979D01*
X465650D01*
G01X475650Y-535246D02*
X475450Y-535112D01*
Y-534846D01*
X475650Y-534712D01*
X475850Y-534846D01*
Y-535112D01*
X475650Y-535246D01*
G01X481750Y-528312D02*
X482350Y-527512D01*
X483050Y-527112D01*
X483850Y-526979D01*
X484850Y-527246D01*
X485550Y-527912D01*
X485750Y-528712D01*
X485650Y-529513D01*
X485250Y-530179D01*
X483250Y-531512D01*
X482350Y-532446D01*
X481750Y-533779D01*
X481550Y-534979D01*
X485750D01*
G01X479650Y-508379D02*
X480150Y-509179D01*
X480750Y-509712D01*
X481450Y-509979D01*
X482250Y-509712D01*
X482850Y-509179D01*
X483450Y-508379D01*
X483650Y-507312D01*
Y-501979D01*
G54D25*
X36595Y385068D03*
X46834Y363428D03*
X55190D03*
X54333Y1606850D03*
X57833Y1666350D03*
X53333D03*
X49333D03*
X61000Y1676216D03*
X70333Y1615850D03*
X69833Y1666350D03*
X73833D03*
X77833D03*
X65000Y1676216D03*
X90518Y637121D03*
X82014Y699608D03*
X92096Y694696D03*
X84474Y1520110D03*
X87500Y1561610D03*
X91500D03*
X81833Y1666350D03*
X90297Y1666396D03*
X85833Y1666350D03*
X108643Y523833D03*
X96774Y1526110D03*
X108800Y1608916D03*
X117597Y491407D03*
X113597D03*
X114720Y1680378D03*
X120910Y1723563D03*
X130317Y480329D03*
X135317D03*
X138489Y525465D03*
X134557Y1728198D03*
X149174Y480329D03*
X152470Y502879D03*
X149568Y1389686D03*
X152806Y1408475D03*
X158570Y1523521D03*
X154581Y1523480D03*
X159014Y1573925D03*
X154580D03*
X170673Y1409461D03*
X175067Y1730108D03*
X190110Y569488D03*
X187711Y1389686D03*
X181806Y1390706D03*
X177702D03*
X190949Y1408475D03*
X205320Y670078D03*
X201220D03*
X207716Y1408761D03*
X220387Y1390815D03*
X216090D03*
X212120Y1706778D03*
X237220Y62378D03*
X241220D03*
X249220D03*
X245220D03*
X251487Y104776D03*
X263580Y221118D03*
X270240Y239298D03*
X267759Y254747D03*
X271821D03*
X275797Y124059D03*
X276491Y254747D03*
X281077D03*
X286481D03*
X289274Y293404D03*
X284515D03*
X302517Y68508D03*
X301315Y95815D03*
X305315D03*
X291759Y254747D03*
X304651D03*
X298184Y293404D03*
X302765D03*
X293763D03*
X302684Y559883D03*
X303551Y1347832D03*
X322155Y232235D03*
X317995Y232265D03*
X317129Y254747D03*
X306736Y293404D03*
X316463D03*
X307019Y1366553D03*
X325617Y73879D03*
X338267Y210643D03*
X329648Y254693D03*
X329002Y293404D03*
X335679Y1325034D03*
X338917Y1343823D03*
X336205Y1350863D03*
X331773Y1348969D03*
X324656Y1366707D03*
X354672Y255184D03*
X342000Y255103D03*
X354145Y293082D03*
X341295Y292730D03*
X367306Y255302D03*
X366498Y292755D03*
X367717Y1311608D03*
X366903Y1335191D03*
X370874Y1330399D03*
X363805Y1326133D03*
X356784Y1343909D03*
X379860Y254987D03*
X379112Y292877D03*
X385797Y1395701D03*
X385123Y1631475D03*
X378497Y1631411D03*
X374500Y1642938D03*
X378509Y1682675D03*
X392616Y254977D03*
X392083Y293445D03*
X399935Y1311608D03*
X395933Y1312707D03*
X402973Y1330369D03*
X390029Y1329934D03*
X393699Y1402554D03*
X403125Y1419519D03*
X399134Y1419497D03*
X391293Y1631495D03*
X417765Y255296D03*
X404985Y254906D03*
X417218Y293765D03*
X404215Y293631D03*
X418616Y936164D03*
X410816D03*
X410795Y951181D03*
X414595D03*
X414626Y965580D03*
X418626D03*
X410826D03*
X418595Y951181D03*
X414600Y980093D03*
X410800D03*
X418600D03*
X414600Y994408D03*
X410800D03*
X418600D03*
X418550Y1008966D03*
X410838D03*
X414550D03*
X410816Y1023576D03*
X414591D03*
X418591D03*
X409980Y1393969D03*
X431873Y255296D03*
X429702Y293254D03*
X422395Y936164D03*
X422426Y965580D03*
X422395Y951181D03*
X422400Y980093D03*
X422350Y994408D03*
Y1008966D03*
X422391Y1023576D03*
X432063Y1311608D03*
X428061Y1312707D03*
X434983Y1330398D03*
X421224Y1329934D03*
X442265Y293430D03*
X448520Y416778D03*
X444020D03*
X442520Y470353D03*
X437520D03*
X451520D03*
X451014Y1397495D03*
X442020Y1564953D03*
X446020D03*
X452020Y1574953D03*
X437383Y1597170D03*
X458264Y260973D03*
X467736Y293914D03*
X467211Y366249D03*
X455720Y399278D03*
X462921Y425019D03*
X453020Y416778D03*
X457520D03*
X456520Y470353D03*
X461520D03*
X462704Y965580D03*
X466704Y951181D03*
Y965580D03*
X462704Y951181D03*
X458904D03*
Y965580D03*
X466704Y980093D03*
X458904D03*
X462704D03*
X466704Y994408D03*
X462704D03*
X458904D03*
X466704Y1008966D03*
X458904D03*
X462704D03*
X458904Y1023576D03*
X466704D03*
X462704D03*
X464191Y1311608D03*
X460189Y1312707D03*
X467644Y1330416D03*
X452961Y1329926D03*
X460020Y1574953D03*
X466320Y1596245D03*
X483500Y234878D03*
X474720Y363378D03*
X485020Y416778D03*
X480520D03*
X479169Y470212D03*
X474169D03*
X470504Y951181D03*
Y965580D03*
Y980093D03*
Y994408D03*
Y1008966D03*
Y1023576D03*
X485296Y1329926D03*
X478460Y1442595D03*
X501136Y293214D03*
X490720Y363378D03*
X498720D03*
X486720D03*
X499570Y424878D03*
X489520Y416778D03*
X494020D03*
X498169Y470212D03*
X493169D03*
X488169D03*
X492317Y1312707D03*
X496319Y1325034D03*
X499458Y1343855D03*
X510830Y106188D03*
X507750Y293099D03*
X506720Y363378D03*
X517720Y392878D03*
X505720D03*
X517020Y480968D03*
X517424Y1343909D03*
X506096Y1415333D03*
X518720Y363378D03*
X531720D03*
X523720D03*
X533720Y392878D03*
X521720D03*
X524445Y1326133D03*
X528447Y1347832D03*
X531610Y1366665D03*
X547330Y363258D03*
X548300Y408423D03*
X549552Y1366707D03*
X564698Y363218D03*
X554300Y408423D03*
X564300D03*
X559300D03*
X560969Y1348984D03*
X556586D03*
X557720Y1449878D03*
X552000D03*
X578582Y363173D03*
X573460Y363218D03*
X569340D03*
X571556Y375065D03*
X569152Y416503D03*
X598795Y143168D03*
X594220Y430878D03*
X606079Y121908D03*
X604725Y275146D03*
X607675Y320915D03*
X615635Y320971D03*
X618460Y121908D03*
X621536Y208592D03*
X618115Y275146D03*
X631146Y321006D03*
X623365Y320991D03*
X634500Y79878D03*
X638500D03*
X646815Y512400D03*
X642225Y1702710D03*
X646225D03*
X648320Y84278D03*
X659000Y91878D03*
X650845Y525196D03*
X654895Y518110D03*
X650794Y518123D03*
X663187Y1389711D03*
X651725Y1646210D03*
X654225Y1657710D03*
X650225Y1695710D03*
X667610Y110428D03*
X675220Y524878D03*
X680220D03*
Y511378D03*
X666425Y1408500D03*
X684643Y108901D03*
X688470Y391678D03*
X685220Y498378D03*
X695220Y524878D03*
Y511378D03*
X691321Y1390731D03*
X695425D03*
X684292Y1408586D03*
X708953Y128184D03*
X708720Y380878D03*
X713220Y390878D03*
X705220Y498378D03*
X711220D03*
X705220Y524878D03*
X701330Y1389711D03*
X704568Y1408500D03*
X711719Y1639867D03*
X728220Y380878D03*
Y390878D03*
X718220D03*
X717220Y498378D03*
X723220D03*
X729220D03*
X717220Y511378D03*
X723220D03*
X729220D03*
X722435Y1408586D03*
X715780Y1617446D03*
X719770Y1617436D03*
X723820D03*
X718830Y1649986D03*
X737093Y87993D03*
X737340Y115751D03*
X741270Y115675D03*
X733220Y380878D03*
X740200Y368241D03*
X738220Y390878D03*
X733220D03*
X735173Y524853D03*
X745220Y511378D03*
X735220D03*
X734006Y1390840D03*
X729709D03*
X743462Y1667261D03*
X739538Y1671271D03*
X760193Y93364D03*
X753089Y498393D03*
X749179Y498373D03*
X755859Y1689111D03*
X759359Y1723611D03*
X755359D03*
X764130Y113196D03*
X777220Y438378D03*
X763859Y1689111D03*
X794220Y425378D03*
X782800Y505578D03*
X783450Y516998D03*
X794600Y363216D03*
X802200D03*
X809800D03*
X809600Y383116D03*
X800498Y413142D03*
Y398542D03*
X831539Y62859D03*
X834615Y104297D03*
X835114Y117714D03*
X833715Y225084D03*
X832500Y267230D03*
X832400Y421416D03*
X828300D03*
X840200D03*
X856629Y63009D03*
X850015Y90267D03*
X858783Y224499D03*
X844200Y421416D03*
X863294Y266052D03*
X863571Y293901D03*
X867571D03*
X886503Y271423D03*
X880772Y876851D03*
X909293Y461944D03*
X913293D03*
X920747Y467743D03*
X921720Y1006878D03*
X924747Y467743D03*
X937747D03*
X933747D03*
X931496Y964703D03*
X927220Y1006878D03*
X941747Y467743D03*
X945747D03*
X947275Y976923D03*
X943750Y980168D03*
X985500Y148315D03*
X989605Y175569D03*
X985445Y175599D03*
X988835Y187969D03*
X1005735Y153959D03*
X1001395Y214439D03*
X1019939Y297429D03*
X1031270Y303578D03*
X1033268Y502318D03*
X1052705Y363211D03*
X1095457Y1641366D03*
X1099457D03*
X1115802Y1617786D03*
X1109287Y1669956D03*
X1122879Y1426015D03*
X1126117Y1444804D03*
X1120472Y1617776D03*
X1120432Y1625436D03*
X1151013Y1427035D03*
X1143984Y1444890D03*
X1160720Y183378D03*
X1155117Y1427035D03*
X1161022Y1426015D03*
X1164260Y1444804D03*
X1164830Y1648231D03*
X1159930D03*
X1163576Y1677565D03*
X1181476Y163822D03*
X1182127Y1444890D03*
X1175830Y1648231D03*
X1181930D03*
X1170930D03*
X1174576Y1677565D03*
X1195278Y136065D03*
X1193260Y1427035D03*
X1189156D03*
X1185080Y1619005D03*
X1197400Y1648541D03*
X1186830Y1648231D03*
X1192500Y1648541D03*
X1196146Y1677875D03*
X1185576Y1677565D03*
X1197240Y1694021D03*
X1192340D03*
X1195986Y1723355D03*
X1212202Y117633D03*
X1208010Y1694066D03*
X1203110D03*
X1213910Y1694331D03*
X1206756Y1723400D03*
X1220500Y207378D03*
X1218810Y1694331D03*
X1217556Y1723665D03*
X1263040Y103638D03*
X1258539Y103443D03*
X1259150Y300032D03*
X1255150D03*
X1274520Y81378D03*
X1281913Y79415D03*
X1271150Y300032D03*
X1279812Y1348068D03*
X1291823Y87785D03*
X1287913Y87735D03*
X1295767Y92232D03*
X1298407Y104983D03*
X1294937Y749481D03*
X1283280Y1366789D03*
X1311960Y52524D03*
X1309790Y62316D03*
X1311636Y72522D03*
X1307578Y72520D03*
X1308792Y91317D03*
X1310906Y100705D03*
X1314906D03*
X1311820Y1325034D03*
X1312346Y1350863D03*
X1308140Y1348930D03*
X1315058Y1343823D03*
X1300917Y1366943D03*
X1325902Y62373D03*
X1330102D03*
X1317831Y62316D03*
X1321869Y62298D03*
X1315649Y72521D03*
X1319721D03*
X1324120Y88424D03*
X1329891Y93839D03*
X1322906Y97219D03*
Y104249D03*
X1318906Y100699D03*
X1329646Y107485D03*
X1324093Y247978D03*
X1345083Y93859D03*
X1336549Y108461D03*
X1343858Y1311608D03*
X1339946Y1326133D03*
X1343044Y1335191D03*
X1347015Y1330399D03*
X1332925Y1343909D03*
X1349621Y106738D03*
X1358277Y1396111D03*
X1366124Y104045D03*
X1378550Y118677D03*
X1372074Y1312707D03*
X1376076Y1311608D03*
X1366170Y1329934D03*
X1379114Y1330369D03*
X1377075Y1419497D03*
X1394757Y936163D03*
X1386957D03*
X1390767Y965579D03*
X1394767D03*
X1394736Y951180D03*
X1390736D03*
X1386936D03*
X1386967Y965579D03*
X1394812Y980092D03*
X1390812D03*
X1387012D03*
X1390741Y994407D03*
X1386941D03*
X1394741D03*
X1394691Y1008965D03*
X1390691D03*
X1386891D03*
X1390732Y1023575D03*
X1386869D03*
X1394732D03*
X1386181Y1394169D03*
X1381066Y1419519D03*
X1385720Y1430378D03*
X1398557Y936163D03*
X1398567Y965579D03*
X1398536Y951180D03*
X1398612Y980092D03*
X1398541Y994407D03*
X1398491Y1008965D03*
X1398532Y1023575D03*
X1408204Y1311608D03*
X1404202Y1312707D03*
X1411124Y1330398D03*
X1397365Y1329934D03*
X1398700Y1600298D03*
X1427155Y1397495D03*
X1438845Y965579D03*
X1442845D03*
X1435045D03*
X1442845Y951180D03*
X1438845D03*
X1435045D03*
X1438845Y980092D03*
X1442845D03*
X1435045D03*
X1442845Y994407D03*
X1438845D03*
X1435045D03*
X1438845Y1008965D03*
X1442845D03*
X1435045D03*
X1438845Y1023575D03*
X1435045D03*
X1442845D03*
X1436330Y1312707D03*
X1440332Y1311608D03*
X1429102Y1329926D03*
X1443785Y1330416D03*
X1442573Y1652485D03*
X1451700Y291216D03*
X1445777Y364512D03*
X1449600Y396828D03*
X1446645Y951180D03*
Y965579D03*
Y980092D03*
Y994407D03*
Y1008965D03*
Y1023575D03*
X1461437Y1329926D03*
X1454938Y1442469D03*
X1454207Y1628081D03*
X1459117Y1628061D03*
X1462777Y364512D03*
X1477384Y413804D03*
X1468458Y1312707D03*
X1472460Y1325034D03*
X1475599Y1343855D03*
X1463747Y1628061D03*
X1467840Y1628118D03*
X1473527Y1658065D03*
X1489564Y364214D03*
X1493874D03*
X1481484Y364304D03*
X1489384Y413804D03*
X1493565Y1343909D03*
X1482237Y1415333D03*
X1500904Y382784D03*
X1500586Y1326133D03*
X1504588Y1347832D03*
X1507751Y1366665D03*
X1526118Y113121D03*
X1525693Y1366707D03*
X1539720Y584378D03*
X1532727Y1348984D03*
X1537110D03*
X1543779Y121294D03*
X1556747Y589431D03*
X1552720Y584378D03*
X1546312Y637732D03*
X1550162D03*
X1619515Y114575D03*
X1624353Y1423307D03*
X1627591Y1442096D03*
X1654110Y428718D03*
X1654032Y654025D03*
Y688025D03*
X1652487Y1424327D03*
X1656591D03*
X1645458Y1442182D03*
X1659610Y397218D03*
X1663610D03*
X1663376Y518104D03*
X1667376D03*
X1657632Y550430D03*
X1665706Y586072D03*
X1661506D03*
X1661132Y620525D03*
X1661120Y613978D03*
X1658085Y642127D03*
Y676127D03*
Y710127D03*
X1662496Y1423307D03*
X1665734Y1442096D03*
X1688504Y401576D03*
X1683601Y1442182D03*
X1694314Y428671D03*
X1690154Y428701D03*
X1693648Y466292D03*
X1697648D03*
X1703960Y544019D03*
X1690080Y552273D03*
X1695446Y704034D03*
X1703768Y698922D03*
X1695172Y1424436D03*
X1690875D03*
X1716875Y62485D03*
X1711832Y62249D03*
X1720895Y62485D03*
X1711832Y75737D03*
X1716965Y75725D03*
X1710426Y407679D03*
X1717686Y499493D03*
X1725520Y62378D03*
X1726608Y105900D03*
X1750918Y125183D03*
X1752324Y200508D03*
X1738290Y417356D03*
X1767638Y69632D03*
X1767891Y97336D03*
X1771891D03*
X1779226Y278120D03*
X1778810Y444078D03*
X1790738Y75003D03*
X1802150Y1499496D03*
X1797722Y1499559D03*
X1790011Y1511514D03*
X1813955Y143036D03*
X1849191Y163391D03*
X1836750Y376499D03*
G54D271*
X1268043Y132212D03*
G54D61*
X95132Y1534944D03*
G54D52*
X89981Y714088D03*
X1703413Y718214D03*
G54D208*
X791280Y1704890D03*
X1066280D03*
G54D181*
X542554Y462744D03*
Y491680D03*
X565586Y462744D03*
Y491680D03*
X1790546Y438156D03*
Y467092D03*
X1813578Y438156D03*
Y467092D03*
G54D217*
X842470Y407020D03*
Y410760D03*
Y414500D03*
X853100Y410760D03*
Y407020D03*
Y414500D03*
G54D190*
X667551Y149803D03*
Y151771D03*
Y153740D03*
Y155708D03*
Y165551D03*
Y167519D03*
Y169488D03*
Y171456D03*
Y173425D03*
Y175393D03*
Y177362D03*
Y179330D03*
Y181299D03*
Y183268D03*
Y185236D03*
Y187204D03*
Y189173D03*
Y191142D03*
Y193110D03*
Y195079D03*
Y197047D03*
Y199016D03*
Y200984D03*
Y202953D03*
Y204921D03*
Y206890D03*
Y208858D03*
Y210827D03*
Y212795D03*
Y214764D03*
Y216732D03*
Y218701D03*
Y220669D03*
X697276Y148819D03*
Y150787D03*
Y152756D03*
Y154724D03*
Y156693D03*
Y166535D03*
Y168504D03*
Y170472D03*
Y172441D03*
Y174409D03*
Y176378D03*
Y178346D03*
Y180315D03*
Y182283D03*
Y184252D03*
Y186220D03*
Y188189D03*
Y190157D03*
Y192126D03*
Y194094D03*
Y196063D03*
Y198031D03*
Y200000D03*
Y201968D03*
Y203937D03*
Y205905D03*
Y207874D03*
Y209842D03*
Y211811D03*
Y213779D03*
Y215748D03*
Y217716D03*
Y219685D03*
Y221653D03*
G54D226*
X913386Y167579D03*
Y184114D03*
Y181752D03*
Y179390D03*
Y177027D03*
Y174665D03*
Y172303D03*
Y169941D03*
Y200649D03*
Y198287D03*
Y195925D03*
Y193563D03*
Y191201D03*
Y188838D03*
Y186476D03*
Y217185D03*
Y214823D03*
Y212461D03*
Y210098D03*
Y207736D03*
Y205374D03*
Y203012D03*
Y231358D03*
Y228996D03*
Y226634D03*
Y224272D03*
Y221909D03*
Y219547D03*
X931496Y167579D03*
Y184114D03*
Y181752D03*
Y179390D03*
Y177027D03*
Y174665D03*
Y172303D03*
Y169941D03*
Y200649D03*
Y198287D03*
Y195925D03*
Y193563D03*
Y191201D03*
Y188838D03*
Y186476D03*
Y217185D03*
Y214823D03*
Y212461D03*
Y210098D03*
Y207736D03*
Y205374D03*
Y203012D03*
Y231358D03*
Y228996D03*
Y226634D03*
Y224272D03*
Y221909D03*
Y219547D03*
G54D154*
X402220Y160951D03*
Y155833D03*
X394780D03*
Y158392D03*
Y160951D03*
X1796768Y150744D03*
X1789328D03*
X1796768Y155862D03*
X1789328Y153303D03*
Y155862D03*
G54D307*
X1766413Y298829D03*
X1768382D03*
X1760508D03*
X1762476D03*
X1764445D03*
X1770350D03*
G54D145*
X347677Y130002D03*
Y126262D03*
Y122522D03*
X357323D03*
Y130002D03*
X1460023Y60322D03*
Y64062D03*
Y67802D03*
X1450377D03*
Y60322D03*
G54D235*
X953904Y1573642D03*
X977270D03*
X1000636D03*
X1024002D03*
X1047368D03*
X1070734D03*
X1094100D03*
X1737611Y1482629D03*
G54D172*
X482720Y375319D03*
Y382405D03*
X496120Y375426D03*
Y382512D03*
X512220Y375319D03*
Y382405D03*
X510220Y404819D03*
Y411905D03*
X529220Y375819D03*
Y382905D03*
X526220Y404819D03*
Y411905D03*
G54D34*
X61280Y380803D03*
X59311D03*
X57342D03*
X55374D03*
X53406D03*
X51437D03*
X49468D03*
Y399799D03*
X51437D03*
X53406D03*
X55374D03*
X57342D03*
X59311D03*
X61280D03*
X614707Y139283D03*
X612738D03*
Y158279D03*
X614707D03*
X624550Y139283D03*
X622581D03*
X620612D03*
X618644D03*
X616676D03*
Y158279D03*
X618644D03*
X620612D03*
X622581D03*
X624550D03*
G54D262*
X1145335Y1605511D03*
Y1608070D03*
Y1610630D03*
Y1613189D03*
X1163839D03*
Y1610630D03*
Y1608070D03*
Y1605511D03*
G54D127*
X269772Y228719D03*
X271740D03*
Y220845D03*
X269772D03*
X273708Y228719D03*
Y220845D03*
X1516181Y294071D03*
X1514212D03*
X1512244D03*
X1510275D03*
Y305489D03*
X1512244D03*
X1514212D03*
X1516181D03*
X1655610Y410265D03*
X1653642D03*
Y418139D03*
X1655610D03*
X1657578Y410265D03*
Y418139D03*
G54D136*
X312277Y152338D03*
X321333Y148598D03*
Y156078D03*
X862232Y183600D03*
X871288Y187340D03*
X862232Y191080D03*
X1656982Y201640D03*
Y209120D03*
X1666038Y205380D03*
G54D43*
X77416Y1534944D03*
G54D109*
X220668Y582055D03*
Y616055D03*
Y650055D03*
G54D118*
X238780Y1648385D03*
X230906Y1644448D03*
X238780Y1662558D03*
X230906Y1658621D03*
X238780Y1676732D03*
X230906Y1672795D03*
X238780Y1690905D03*
X230906Y1686968D03*
X238780Y1705078D03*
X230906Y1701141D03*
Y1715314D03*
X238780Y1719251D03*
X230906Y1729488D03*
X238780Y1733425D03*
X254528Y1648385D03*
X246654Y1644448D03*
X254528Y1662558D03*
X246654Y1658621D03*
X254528Y1676732D03*
X246654Y1672795D03*
X254528Y1690905D03*
X246654Y1686968D03*
X254528Y1705078D03*
X246654Y1701141D03*
Y1715314D03*
X254528Y1719251D03*
X246654Y1729488D03*
X254528Y1733425D03*
X270276Y1648385D03*
X262402Y1644448D03*
X270276Y1662558D03*
X262402Y1658621D03*
X270276Y1676732D03*
X262402Y1672795D03*
X270276Y1690905D03*
X262402Y1686968D03*
X270276Y1705078D03*
X262402Y1701141D03*
Y1715314D03*
X270276Y1719251D03*
X262402Y1729488D03*
X270276Y1733425D03*
X286024Y1648385D03*
X278150Y1644448D03*
X286024Y1662558D03*
X278150Y1658621D03*
X286024Y1676732D03*
X278150Y1672795D03*
X286024Y1690905D03*
X278150Y1686968D03*
X286024Y1705078D03*
X278150Y1701141D03*
Y1715314D03*
X286024Y1719251D03*
X278150Y1729488D03*
X286024Y1733425D03*
X297835Y1672795D03*
X305709Y1676732D03*
X297835Y1686968D03*
X305709Y1690905D03*
X297835Y1701141D03*
X305709Y1705078D03*
X297835Y1715314D03*
X305709Y1719251D03*
X297835Y1729488D03*
X305709Y1733425D03*
X313583Y1672795D03*
X321457Y1676732D03*
X313583Y1686968D03*
X321457Y1690905D03*
X313583Y1701141D03*
X321457Y1705078D03*
X313583Y1715314D03*
X321457Y1719251D03*
X313583Y1729488D03*
X321457Y1733425D03*
X329331Y1672795D03*
X337205Y1676732D03*
X329331Y1686968D03*
X337205Y1690905D03*
X329331Y1701141D03*
X337205Y1705078D03*
X329331Y1715314D03*
X337205Y1719251D03*
X329331Y1729488D03*
X337205Y1733425D03*
X345079Y1672795D03*
X352953Y1676732D03*
X345079Y1686968D03*
X352953Y1690905D03*
X345079Y1701141D03*
X352953Y1705078D03*
X345079Y1715314D03*
X352953Y1719251D03*
X345079Y1729488D03*
X352953Y1733425D03*
X495079Y1672795D03*
Y1686968D03*
Y1701141D03*
Y1715314D03*
Y1729488D03*
X510827Y1672795D03*
X502953Y1676732D03*
X518701D03*
X510827Y1686968D03*
X502953Y1690905D03*
X518701D03*
X510827Y1701141D03*
X502953Y1705078D03*
X518701D03*
X510827Y1715314D03*
X502953Y1719251D03*
X518701D03*
X510827Y1729488D03*
X502953Y1733425D03*
X518701D03*
X526575Y1672795D03*
X534449Y1676732D03*
X526575Y1686968D03*
X534449Y1690905D03*
X526575Y1701141D03*
X534449Y1705078D03*
X526575Y1715314D03*
X534449Y1719251D03*
X526575Y1729488D03*
X534449Y1733425D03*
X542323Y1672795D03*
X550197Y1676732D03*
X542323Y1686968D03*
X550197Y1690905D03*
X542323Y1701141D03*
X550197Y1705078D03*
X542323Y1715314D03*
X550197Y1719251D03*
X542323Y1729488D03*
X550197Y1733425D03*
X562008Y1672795D03*
Y1686968D03*
Y1701141D03*
Y1715314D03*
Y1729488D03*
X577756Y1672795D03*
X569882Y1676732D03*
X577756Y1686968D03*
X569882Y1690905D03*
X577756Y1701141D03*
X569882Y1705078D03*
X577756Y1715314D03*
X569882Y1719251D03*
X577756Y1729488D03*
X569882Y1733425D03*
X593504Y1672795D03*
X585630Y1676732D03*
X593504Y1686968D03*
X585630Y1690905D03*
X593504Y1701141D03*
X585630Y1705078D03*
X593504Y1715314D03*
X585630Y1719251D03*
X593504Y1729488D03*
X585630Y1733425D03*
X609252Y1672795D03*
X601378Y1676732D03*
X609252Y1686968D03*
X601378Y1690905D03*
X609252Y1701141D03*
X601378Y1705078D03*
X609252Y1715314D03*
X601378Y1719251D03*
X609252Y1729488D03*
X601378Y1733425D03*
X617126Y1676732D03*
Y1690905D03*
Y1705078D03*
Y1719251D03*
Y1733425D03*
X1238780Y1672795D03*
X1246654Y1676732D03*
X1238780Y1686968D03*
X1246654Y1690905D03*
X1238780Y1701141D03*
X1246654Y1705078D03*
X1238780Y1715314D03*
X1246654Y1719251D03*
X1238780Y1729488D03*
X1246654Y1733425D03*
X1254528Y1672795D03*
X1262402Y1676732D03*
X1254528Y1686968D03*
X1262402Y1690905D03*
X1254528Y1701141D03*
X1262402Y1705078D03*
X1254528Y1715314D03*
X1262402Y1719251D03*
X1254528Y1729488D03*
X1262402Y1733425D03*
X1270276Y1672795D03*
X1278150Y1676732D03*
X1270276Y1686968D03*
X1278150Y1690905D03*
X1270276Y1701141D03*
X1278150Y1705078D03*
X1270276Y1715314D03*
X1278150Y1719251D03*
X1270276Y1729488D03*
X1278150Y1733425D03*
X1286024Y1672795D03*
X1293898Y1676732D03*
X1286024Y1686968D03*
X1293898Y1690905D03*
X1286024Y1701141D03*
X1293898Y1705078D03*
X1286024Y1715314D03*
X1293898Y1719251D03*
X1286024Y1729488D03*
X1293898Y1733425D03*
X1305709Y1672795D03*
X1313583Y1676732D03*
X1305709Y1686968D03*
X1313583Y1690905D03*
X1305709Y1701141D03*
X1313583Y1705078D03*
X1305709Y1715314D03*
X1313583Y1719251D03*
X1305709Y1729488D03*
X1313583Y1733425D03*
X1321457Y1672795D03*
X1329331Y1676732D03*
X1321457Y1686968D03*
X1329331Y1690905D03*
X1321457Y1701141D03*
X1329331Y1705078D03*
X1321457Y1715314D03*
X1329331Y1719251D03*
X1321457Y1729488D03*
X1329331Y1733425D03*
X1337205Y1672795D03*
X1345079Y1676732D03*
X1337205Y1686968D03*
X1345079Y1690905D03*
X1337205Y1701141D03*
X1345079Y1705078D03*
X1337205Y1715314D03*
X1345079Y1719251D03*
X1337205Y1729488D03*
X1345079Y1733425D03*
X1352953Y1672795D03*
X1360827Y1676732D03*
X1352953Y1686968D03*
X1360827Y1690905D03*
X1352953Y1701141D03*
X1360827Y1705078D03*
X1352953Y1715314D03*
X1360827Y1719251D03*
X1352953Y1729488D03*
X1360827Y1733425D03*
X1502953Y1672795D03*
X1510827Y1676732D03*
X1502953Y1686968D03*
X1510827Y1690905D03*
X1502953Y1701141D03*
X1510827Y1705078D03*
X1502953Y1715314D03*
X1510827Y1719251D03*
X1502953Y1729488D03*
X1510827Y1733425D03*
X1518701Y1672795D03*
X1526575Y1676732D03*
X1518701Y1686968D03*
X1526575Y1690905D03*
X1518701Y1701141D03*
X1526575Y1705078D03*
X1518701Y1715314D03*
X1526575Y1719251D03*
X1518701Y1729488D03*
X1526575Y1733425D03*
X1534449Y1672795D03*
X1542323Y1676732D03*
X1534449Y1686968D03*
X1542323Y1690905D03*
X1534449Y1701141D03*
X1542323Y1705078D03*
X1534449Y1715314D03*
X1542323Y1719251D03*
X1534449Y1729488D03*
X1542323Y1733425D03*
X1550197Y1672795D03*
X1558071Y1676732D03*
X1550197Y1686968D03*
X1558071Y1690905D03*
X1550197Y1701141D03*
X1558071Y1705078D03*
X1550197Y1715314D03*
X1558071Y1719251D03*
X1550197Y1729488D03*
X1558071Y1733425D03*
X1569882Y1672795D03*
Y1686968D03*
Y1701141D03*
Y1715314D03*
Y1729488D03*
X1585630Y1672795D03*
X1577756Y1676732D03*
X1585630Y1686968D03*
X1577756Y1690905D03*
X1585630Y1701141D03*
X1577756Y1705078D03*
X1585630Y1715314D03*
X1577756Y1719251D03*
X1585630Y1729488D03*
X1577756Y1733425D03*
X1601378Y1672795D03*
X1593504Y1676732D03*
X1601378Y1686968D03*
X1593504Y1690905D03*
X1601378Y1701141D03*
X1593504Y1705078D03*
X1601378Y1715314D03*
X1593504Y1719251D03*
X1601378Y1729488D03*
X1593504Y1733425D03*
X1617126Y1672795D03*
X1609252Y1676732D03*
X1625000D03*
X1617126Y1686968D03*
X1609252Y1690905D03*
X1625000D03*
X1617126Y1701141D03*
X1609252Y1705078D03*
X1625000D03*
X1617126Y1715314D03*
X1609252Y1719251D03*
X1625000D03*
X1617126Y1729488D03*
X1609252Y1733425D03*
X1625000D03*
G54D16*
X27737Y216362D03*
Y224362D03*
X36517Y200862D03*
Y192862D03*
X36237Y216362D03*
Y208362D03*
Y232362D03*
Y224342D03*
Y240362D03*
X33197Y302472D03*
X59291Y1520094D03*
Y1536094D03*
Y1540094D03*
Y1560094D03*
X62823Y302926D03*
X65625Y421746D03*
X78008Y424319D03*
Y420319D03*
X77707Y648574D03*
Y644564D03*
Y652564D03*
X79657Y278798D03*
Y295798D03*
Y286262D03*
Y303262D03*
X81908Y376026D03*
X81891Y386502D03*
X88318Y438519D03*
Y442519D03*
X85657Y644564D03*
Y648564D03*
Y656564D03*
Y652564D03*
X86536Y685488D03*
X85525Y694209D03*
X86525Y690644D03*
X93205Y1581852D03*
Y1597867D03*
X84155Y1589872D03*
X93280Y1601867D03*
Y1615821D03*
Y1619821D03*
X93190Y1630362D03*
Y1642362D03*
X88762Y1683071D03*
X88737Y1694362D03*
X88747Y1686622D03*
X109092Y186362D03*
X108032Y216596D03*
X111029Y282995D03*
Y278875D03*
Y274800D03*
Y300354D03*
Y306236D03*
X104967Y517925D03*
X107112Y685490D03*
X95767Y718880D03*
X107291Y1524594D03*
Y1544594D03*
Y1548594D03*
Y1536594D03*
Y1540594D03*
Y1560594D03*
Y1564594D03*
X127499Y404571D03*
X112831Y523785D03*
X125255Y656603D03*
X124255Y647103D03*
X125255Y652603D03*
X122691Y665515D03*
Y661515D03*
X122667Y669400D03*
X116250Y1535767D03*
X116352Y1541935D03*
X116423Y1548027D03*
X121737Y1678362D03*
Y1670362D03*
Y1674362D03*
X114737Y1696362D03*
X121737Y1692362D03*
Y1688362D03*
Y1708362D03*
Y1700362D03*
Y1704362D03*
X127574Y1727182D03*
Y1731182D03*
X128698Y643603D03*
X143562Y688207D03*
X142634Y1396275D03*
Y1392745D03*
X158417Y409362D03*
X143913Y415062D03*
Y423383D03*
Y427383D03*
Y419383D03*
Y431383D03*
Y435383D03*
Y439383D03*
Y443383D03*
X144014Y498810D03*
Y502810D03*
X143979Y506533D03*
X144014Y522810D03*
X157075Y1412173D03*
X148237Y1708362D03*
Y1712362D03*
X155237Y1716362D03*
X172413Y421383D03*
Y425383D03*
Y443383D03*
Y430883D03*
X165628Y1443390D03*
X180999Y393071D03*
Y385071D03*
Y389071D03*
Y405071D03*
X192068Y681291D03*
X191159Y693623D03*
X179999Y1535462D03*
X179885Y1544028D03*
X179965Y1548486D03*
X179988Y1539723D03*
X179956Y1552874D03*
Y1557874D03*
X182084Y1723592D03*
X201641Y420255D03*
Y414755D03*
Y425755D03*
Y436755D03*
Y431255D03*
Y442255D03*
Y447755D03*
Y453255D03*
Y458755D03*
Y462755D03*
Y468255D03*
X196618Y570901D03*
X197090Y588879D03*
X196618Y604901D03*
X197090Y622879D03*
X196618Y638901D03*
X197090Y656879D03*
X195218Y1412173D03*
X193385Y1719697D03*
X205135Y1718017D03*
X199142Y1733022D03*
X212071Y452735D03*
X215408Y567981D03*
X214309Y596107D03*
X215408Y601981D03*
X214309Y630107D03*
X215408Y635981D03*
X214309Y664107D03*
X211558Y673737D03*
X230537Y154126D03*
X242237Y71862D03*
X247314Y111743D03*
X256787Y458617D03*
X273784Y99183D03*
X270017Y136962D03*
X267067Y142892D03*
X267070Y159203D03*
Y155203D03*
X262737Y214022D03*
X266571Y422735D03*
X266553Y418579D03*
X266571Y426735D03*
X266603Y431039D03*
X266571Y443735D03*
X276917Y136962D03*
X277797Y210802D03*
X289137Y637809D03*
X295434Y71513D03*
X295464Y75673D03*
X296570Y151703D03*
Y156203D03*
X306236Y595318D03*
X322559Y69863D03*
X317074Y91803D03*
X320322Y563176D03*
X314732Y599926D03*
X312163Y1369807D03*
X340017Y161862D03*
X353237Y221862D03*
X346750Y709995D03*
X343186Y1347521D03*
X363717Y130162D03*
X363617Y156202D03*
X376237Y128452D03*
X376257Y124312D03*
X385677Y124322D03*
X385592Y128491D03*
X375314Y1334095D03*
X384867Y1627062D03*
X396113Y1330142D03*
X403421Y1404207D03*
Y1400684D03*
X403348Y1397038D03*
X403416Y1407727D03*
X394842Y1413619D03*
X396435Y1432571D03*
Y1427569D03*
X399438Y1541810D03*
Y1556810D03*
X419854Y67465D03*
Y62665D03*
X417714Y149373D03*
X408376Y161162D03*
X417714Y157466D03*
Y161466D03*
Y153477D03*
X409060Y1334095D03*
X415494Y1390306D03*
X408832Y1390325D03*
X405235Y1427569D03*
Y1432571D03*
X411217Y1611300D03*
Y1607400D03*
X409949Y1680267D03*
X423592Y117491D03*
X428981Y128515D03*
Y124015D03*
X428237Y214862D03*
Y209862D03*
X423237Y225362D03*
X423937Y232562D03*
Y236562D03*
Y240562D03*
X427672Y1330042D03*
X429938Y1543810D03*
Y1555810D03*
X427062Y1579466D03*
X451510Y75985D03*
X446838Y149864D03*
X436835Y498733D03*
Y504233D03*
Y509733D03*
Y515233D03*
Y520733D03*
Y526233D03*
Y542733D03*
X445345Y537483D03*
X436835Y547769D03*
Y552769D03*
X439570Y1334095D03*
X451106Y1393959D03*
X450118Y1420625D03*
Y1409125D03*
Y1413125D03*
Y1417125D03*
Y1427632D03*
Y1424125D03*
X450107Y1431134D03*
X450097Y1611923D03*
X456656Y115948D03*
X455838Y149864D03*
Y154864D03*
X460597Y1330533D03*
X466430Y1614682D03*
X466387Y1618626D03*
X472270Y66575D03*
X472244Y61129D03*
X472200Y55935D03*
X481338Y158864D03*
X480237Y391362D03*
X471698Y1334095D03*
X477983Y1400385D03*
X476588Y1411144D03*
X485167Y1631038D03*
X472447Y1643242D03*
Y1659242D03*
Y1651242D03*
Y1667242D03*
X472377Y1673462D03*
Y1685462D03*
X499597Y93582D03*
X501017Y228362D03*
X489353Y305398D03*
X489327Y313582D03*
X493237Y391362D03*
X491135Y547947D03*
X492757Y1319592D03*
X503967Y86422D03*
X507017Y209862D03*
X502517Y237862D03*
X505517Y288862D03*
X505274Y315404D03*
X508237Y420862D03*
X504035Y507819D03*
Y511819D03*
Y519819D03*
Y515819D03*
Y523819D03*
Y527819D03*
Y539819D03*
X503826Y1347521D03*
X523237Y420862D03*
X522897Y478492D03*
X526917Y489112D03*
Y495112D03*
X525355Y1338837D03*
X536337Y103352D03*
X536407Y108062D03*
X547487Y149802D03*
X535467Y442376D03*
Y450330D03*
Y446396D03*
X535954Y1370319D03*
X552487Y131756D03*
X559237Y167112D03*
Y161362D03*
X559737Y184862D03*
X554581Y253202D03*
Y257202D03*
X566706Y305247D03*
X565057Y442656D03*
X565034Y451710D03*
X570737Y167112D03*
X581967Y190092D03*
X581973Y198378D03*
Y210378D03*
Y202378D03*
Y206378D03*
X581737Y225362D03*
Y221362D03*
X575451Y262632D03*
X568932Y498546D03*
X579017Y514362D03*
X588337Y129642D03*
X595237Y174612D03*
X596331Y257532D03*
X586581Y252202D03*
X585062Y296657D03*
Y311571D03*
Y304052D03*
X591322Y363354D03*
X588087Y488212D03*
X591517Y524862D03*
X601737Y164612D03*
X611473Y202878D03*
Y207378D03*
X599947Y458688D03*
X599737Y482362D03*
X600737Y514862D03*
X618324Y184022D03*
X627081Y249202D03*
Y260202D03*
X631737Y411362D03*
X631517Y406862D03*
X631737Y426362D03*
Y421362D03*
Y441862D03*
Y431362D03*
X616737Y442862D03*
X631740Y436650D03*
X631737Y457862D03*
Y452862D03*
Y447862D03*
X616737Y457862D03*
X631737Y462862D03*
X631717Y482662D03*
X638570Y88035D03*
X638530Y92085D03*
X646517Y93362D03*
X645178Y134506D03*
X645161Y144982D03*
X646237Y161862D03*
Y166362D03*
Y171362D03*
X637237Y230362D03*
X637662Y298297D03*
Y315587D03*
Y310962D03*
Y302247D03*
X633017Y392862D03*
X646017D03*
X646517Y406862D03*
Y402362D03*
X646737Y416362D03*
Y441862D03*
Y431362D03*
Y452862D03*
Y457862D03*
Y447862D03*
Y467862D03*
Y462862D03*
X643742Y1653194D03*
X642242Y1695694D03*
X642237Y1718362D03*
Y1722362D03*
X652127Y120412D03*
X652762Y290371D03*
X656253Y1392770D03*
Y1396300D03*
X663737Y1720362D03*
X680470Y115868D03*
X670147Y391602D03*
X670694Y1412198D03*
X665589Y1642667D03*
X665610Y1655557D03*
X665535Y1651557D03*
X665637Y1672862D03*
Y1668862D03*
X668737Y1708362D03*
Y1724362D03*
Y1716362D03*
Y1732362D03*
X681917Y1442245D03*
X691664Y1632667D03*
X691739Y1644667D03*
X691749Y1648843D03*
X692137Y1658862D03*
X687137Y1670862D03*
X692137Y1666862D03*
Y1674862D03*
Y1682862D03*
X706940Y103308D03*
X710237Y161862D03*
Y157362D03*
X708837Y1412198D03*
X704659Y1563733D03*
X704629Y1583683D03*
X703597Y1607102D03*
Y1611022D03*
X704589Y1601963D03*
X718287Y1644550D03*
X718850Y1676500D03*
X730040Y95158D03*
X730010Y90998D03*
X745752Y142050D03*
X745172Y1674362D03*
X757135Y89348D03*
X751650Y111288D03*
X748217Y167537D03*
X748177Y276322D03*
X760737Y393212D03*
Y418212D03*
Y423212D03*
Y428212D03*
X759857Y464862D03*
Y469862D03*
Y488862D03*
Y483862D03*
Y479862D03*
X759867Y497659D03*
X762037Y1388562D03*
Y1392762D03*
Y1406062D03*
X761937Y1410262D03*
X754629Y1579183D03*
Y1587183D03*
Y1592183D03*
X774806Y158026D03*
X774820Y153728D03*
X777559Y299279D03*
X763759D03*
X763660Y311249D03*
X763187Y317432D03*
X775737Y413212D03*
Y408212D03*
Y403212D03*
Y398212D03*
Y418212D03*
Y423212D03*
X774857Y464862D03*
Y469862D03*
Y488862D03*
X765669Y1594893D03*
X779677Y267822D03*
Y281822D03*
X789937Y393462D03*
Y402500D03*
X789857Y464862D03*
Y474862D03*
X788417Y483262D03*
X802979Y269800D03*
X805357Y469862D03*
Y474862D03*
X807169Y1577793D03*
Y1593793D03*
Y1601793D03*
Y1609793D03*
X821625Y274885D03*
Y279885D03*
X824280Y494000D03*
X824287Y498082D03*
Y502082D03*
Y523082D03*
Y515082D03*
X831478Y58632D03*
X828237Y166862D03*
Y176362D03*
X833152Y275045D03*
Y280045D03*
X827495Y389012D03*
Y397276D03*
X827517Y384400D03*
X827494Y413260D03*
X835517Y446800D03*
X838737Y495362D03*
X848837Y162762D03*
X848427Y185812D03*
X856350Y273217D03*
X856320Y269057D03*
X849417Y476900D03*
X857137Y503162D03*
Y499062D03*
X857287Y515582D03*
Y519582D03*
X849169Y1577793D03*
Y1593793D03*
Y1601793D03*
Y1609793D03*
X871237Y166362D03*
X865003Y394620D03*
Y390620D03*
Y382415D03*
X865055Y406812D03*
Y418836D03*
X864837Y431462D03*
X879237Y176862D03*
Y171362D03*
X881232Y183169D03*
X881242Y187449D03*
X883445Y267407D03*
X877932Y289439D03*
X884839Y874405D03*
X885409Y920325D03*
X891169Y1577793D03*
Y1593793D03*
Y1601793D03*
Y1609793D03*
X933169Y1581393D03*
Y1585393D03*
Y1589393D03*
X955362Y484271D03*
X955337Y480262D03*
X955388Y540727D03*
X955389Y536806D03*
X958307Y997496D03*
X961496Y1551855D03*
X981641Y185347D03*
X981366Y276394D03*
X977811Y356910D03*
X986274Y363660D03*
X984862Y1551855D03*
X994429Y217233D03*
Y221233D03*
X993540Y363155D03*
X1015744Y195114D03*
X1015737Y199076D03*
X1013712Y203423D03*
Y210423D03*
Y214423D03*
Y218423D03*
Y222423D03*
X1008255Y363356D03*
X1018286Y517728D03*
Y512574D03*
X1008228Y1551855D03*
X1034350Y264130D03*
X1024350Y297264D03*
Y305313D03*
Y301313D03*
X1031594Y1551855D03*
X1041044Y291105D03*
X1042505Y502161D03*
X1069722Y382141D03*
X1054960Y1551855D03*
X1079206Y78553D03*
X1073681Y509645D03*
X1078326Y1551855D03*
X1076474Y1663950D03*
X1094736Y65262D03*
X1091627Y379251D03*
X1091507Y369061D03*
X1091567Y374131D03*
X1101692Y1551855D03*
X1098547Y1679870D03*
Y1675970D03*
X1097067Y1672030D03*
X1104149Y55505D03*
X1115945Y1429074D03*
Y1432604D03*
X1119127Y1612320D03*
X1119097Y1608420D03*
X1121620Y60545D03*
X1121520Y56545D03*
X1121620Y64545D03*
X1130386Y1448502D03*
X1148887Y211231D03*
X1137407Y377011D03*
X1150527Y373231D03*
X1142050Y1479313D03*
X1149487Y1618960D03*
X1168529Y1448502D03*
X1156178Y1622340D03*
Y1626220D03*
Y1630090D03*
X1160942Y1642600D03*
X1156178Y1633880D03*
X1182588Y61311D03*
X1182488Y65811D03*
X1182508Y57111D03*
X1175762Y202174D03*
Y198174D03*
Y186174D03*
Y218174D03*
Y214174D03*
X1172397Y1601100D03*
Y1609100D03*
Y1605100D03*
X1172277Y1612960D03*
X1179088D03*
X1182942Y1642600D03*
X1171942D03*
X1195317Y93200D03*
X1193493Y127804D03*
X1197492Y236592D03*
X1193512Y1642910D03*
X1193352Y1688390D03*
X1204278Y57130D03*
X1217110Y140962D03*
Y185462D03*
X1207737Y189362D03*
X1210922Y1673963D03*
X1203598Y1677873D03*
X1210852Y1681773D03*
X1204122Y1688435D03*
X1214922Y1688700D03*
X1228517Y94200D03*
Y98400D03*
X1228610Y168162D03*
Y172962D03*
X1242399Y98785D03*
X1239077Y191279D03*
X1248110Y201562D03*
X1239110Y197462D03*
X1248110Y211762D03*
Y205362D03*
Y215762D03*
Y219662D03*
X1248195Y245442D03*
X1259110Y217462D03*
Y233462D03*
Y221462D03*
Y229462D03*
Y225462D03*
Y243562D03*
Y238662D03*
Y247562D03*
X1259310Y251562D03*
X1267271Y88572D03*
Y96768D03*
X1278808Y98828D03*
X1266610Y233462D03*
X1296182Y81169D03*
X1288424Y1370043D03*
X1302551Y64572D03*
X1305280Y81775D03*
X1325081Y261514D03*
X1319327Y1347521D03*
X1351455Y1334095D03*
X1368769Y81111D03*
X1372254Y1330142D03*
X1379562Y1400684D03*
Y1404207D03*
X1370143Y1417374D03*
X1370983Y1413019D03*
X1379557Y1407727D03*
X1385201Y1334095D03*
X1391635Y1390306D03*
X1384193Y1390335D03*
X1408900Y227948D03*
X1403813Y1330042D03*
X1406925Y1565037D03*
X1406865Y1576197D03*
X1406925Y1570037D03*
X1399417Y1586400D03*
Y1590200D03*
X1402517Y1626362D03*
X1410992Y1622200D03*
X1402517Y1634362D03*
Y1638362D03*
X1415711Y1334095D03*
X1427247Y1393959D03*
X1426259Y1417125D03*
Y1413125D03*
Y1409125D03*
Y1420625D03*
Y1427632D03*
Y1424125D03*
X1426287Y1431150D03*
X1417350Y1516435D03*
X1417590Y1532255D03*
X1417350Y1521335D03*
X1417590Y1537155D03*
X1417740Y1548375D03*
Y1543475D03*
X1420787Y1603262D03*
X1424287Y1608442D03*
X1424227Y1616932D03*
X1445017Y211862D03*
Y215862D03*
X1436738Y1330533D03*
X1440197Y1590382D03*
X1440917Y1606800D03*
Y1602600D03*
X1436317Y1632900D03*
Y1620300D03*
X1441250Y1665495D03*
X1441160Y1673955D03*
X1441164Y1669629D03*
X1447839Y1334095D03*
X1454124Y1400385D03*
X1452729Y1411144D03*
X1452425Y1560037D03*
Y1565037D03*
X1450147Y1586262D03*
X1454482Y1612800D03*
X1471400Y225448D03*
Y233448D03*
X1463900Y242448D03*
X1471602Y263378D03*
Y255378D03*
X1463602Y271378D03*
X1468898Y1319592D03*
X1481425Y281456D03*
X1488917Y421982D03*
X1484897Y431972D03*
X1479967Y1347521D03*
X1495926Y280027D03*
X1508418Y288030D03*
X1501496Y1338837D03*
X1516517Y116462D03*
X1515517Y136162D03*
X1517085Y243362D03*
Y235116D03*
Y258616D03*
Y254616D03*
X1516775Y284956D03*
X1512895Y1369919D03*
X1542469Y152873D03*
X1543254Y634165D03*
X1563096Y655416D03*
Y659416D03*
X1565973Y735691D03*
Y732165D03*
X1589095Y219526D03*
Y227526D03*
X1588856Y248008D03*
X1588876Y243890D03*
X1588836Y252126D03*
X1604297Y654542D03*
X1602477Y722582D03*
X1597433Y1420169D03*
Y1433669D03*
Y1438169D03*
Y1452071D03*
X1611337Y586762D03*
X1617419Y1426366D03*
Y1429896D03*
X1626550Y117627D03*
Y129627D03*
Y121627D03*
X1631860Y1445794D03*
X1654746Y544622D03*
X1653925Y635791D03*
X1646099Y652601D03*
X1653925Y669791D03*
X1646099Y686601D03*
X1653925Y703791D03*
X1646099Y720601D03*
X1643124Y1476695D03*
X1661820Y550382D03*
X1662877Y598522D03*
X1670003Y1445794D03*
X1668615Y1493362D03*
Y1501362D03*
Y1516862D03*
Y1533862D03*
Y1520862D03*
Y1545862D03*
X1668690Y1561557D03*
X1668615Y1557557D03*
X1668690Y1581321D03*
X1684448Y495290D03*
Y499290D03*
X1701811Y369773D03*
Y373773D03*
X1699901Y401485D03*
X1693793Y525507D03*
Y529507D03*
Y533507D03*
Y549507D03*
X1703544Y655141D03*
X1700937Y688130D03*
Y691730D03*
Y695330D03*
X1701977Y726552D03*
X1711734Y174970D03*
X1714707Y364962D03*
X1719946Y474859D03*
Y478869D03*
X1722435Y112867D03*
X1736218Y486837D03*
X1722672Y688211D03*
X1748905Y100307D03*
X1751237Y372452D03*
X1741452Y1451841D03*
X1760585Y76797D03*
X1760555Y72637D03*
X1763527Y164362D03*
X1757158Y433221D03*
X1760258Y461393D03*
X1760368Y465893D03*
X1757773Y692742D03*
X1754542Y1475951D03*
X1782195Y92927D03*
X1771892Y169903D03*
X1779945Y291876D03*
X1779960Y295643D03*
Y299243D03*
X1784816Y403932D03*
Y410432D03*
Y418932D03*
Y425432D03*
X1787680Y70987D03*
X1799782Y165565D03*
X1792288Y367866D03*
X1791586Y390252D03*
X1795544Y1527366D03*
X1803307Y156557D03*
X1810267Y179897D03*
X1817249Y371329D03*
X1817086Y395552D03*
X1816316Y407932D03*
Y403225D03*
X1815816Y421432D03*
Y427932D03*
X1815758Y472521D03*
X1806658Y1494318D03*
Y1498318D03*
X1815231Y1504241D03*
X1823568Y363731D03*
Y367701D03*
X1823186Y379552D03*
Y383952D03*
X1832458Y459121D03*
X1835852Y182712D03*
X1842972Y176722D03*
G54D163*
X450000Y278543D03*
X460000D03*
X470000D03*
X483500Y246362D03*
X480000Y278543D03*
X493500Y246362D03*
X490000Y278543D03*
X500000D03*
X510000D03*
X518563Y607067D03*
X508563D03*
X559236Y1441207D03*
X569236D03*
X688500Y1601900D03*
Y1611900D03*
X1041435Y143357D03*
Y153357D03*
X1056225Y143131D03*
Y153131D03*
X1099970Y1702570D03*
Y1712570D03*
X1689646Y115669D03*
X1679646D03*
X1689646Y125669D03*
Y135669D03*
X1679646Y125669D03*
Y135669D03*
X1689646Y145669D03*
Y155669D03*
X1679646Y145669D03*
Y155669D03*
X1689646Y165669D03*
X1679646D03*
X1689646Y175669D03*
X1771457Y1634646D03*
Y1644646D03*
G54D70*
X95132Y1539669D03*
Y1538094D03*
Y1536519D03*
G54D244*
X1005878Y291426D03*
Y308748D03*
G54D280*
X1288347Y150750D03*
X1290927Y151438D03*
X1294866D03*
X1292896Y149804D03*
X1296835D03*
X1294866Y148170D03*
X1287401Y167116D03*
X1290669D03*
X1289035Y165146D03*
X1292303D03*
X1287401Y163177D03*
X1290669D03*
X1289035Y161207D03*
X1292303D03*
X1287401Y159238D03*
X1290669D03*
X1285767Y157268D03*
X1289035D03*
X1292303D03*
X1287401Y155299D03*
X1290669D03*
X1294866Y154706D03*
X1289035Y153329D03*
X1292896Y153072D03*
X1296835D03*
X1289035Y184841D03*
X1292303D03*
X1287401Y182871D03*
X1290669D03*
X1289035Y180902D03*
X1292303D03*
X1287401Y178932D03*
X1290669D03*
X1289035Y176963D03*
X1292303D03*
X1287401Y174993D03*
X1290669D03*
X1289035Y173024D03*
X1292303D03*
X1287401Y171055D03*
X1290669D03*
X1289035Y169085D03*
X1292303D03*
X1289035Y196657D03*
X1292303D03*
X1287401Y194688D03*
X1290669D03*
X1289035Y192718D03*
X1292303D03*
X1287401Y190749D03*
X1290669D03*
X1289035Y188780D03*
X1292303D03*
X1287401Y186810D03*
X1290669D03*
X1289035Y200596D03*
X1292303D03*
X1287401Y198627D03*
X1290669D03*
X1289035Y216352D03*
X1292303D03*
X1287401Y214382D03*
X1290669D03*
X1289035Y212413D03*
X1292303D03*
X1287401Y210443D03*
X1290669D03*
X1289035Y208474D03*
X1292303D03*
X1287401Y206505D03*
X1290669D03*
X1289035Y204535D03*
X1292303D03*
X1287401Y202566D03*
X1290669D03*
X1292896Y231694D03*
X1296835D03*
X1290927Y230060D03*
X1294866D03*
X1289035Y228169D03*
X1292896Y228426D03*
X1296835D03*
X1287401Y226199D03*
X1290669D03*
X1294866Y226792D03*
X1289035Y224230D03*
X1292303D03*
X1287401Y222260D03*
X1290669D03*
X1289035Y220291D03*
X1292303D03*
X1287401Y218321D03*
X1290669D03*
X1302744Y151438D03*
X1306683D03*
X1310621D03*
X1314560D03*
X1298805D03*
X1304713Y149804D03*
X1308652D03*
X1312591D03*
X1300774D03*
X1302744Y154706D03*
X1306683D03*
X1310621D03*
X1314560D03*
X1298805D03*
X1304713Y153072D03*
X1308652D03*
X1312591D03*
X1300774D03*
X1304713Y231694D03*
X1308652D03*
X1312591D03*
X1300774D03*
X1302744Y230060D03*
X1306683D03*
X1310621D03*
X1314560D03*
X1298805D03*
X1304713Y228426D03*
X1308652D03*
X1312591D03*
X1300774D03*
X1302744Y226792D03*
X1306683D03*
X1310621D03*
X1314560D03*
X1298805D03*
X1318499Y151438D03*
X1322438D03*
X1326377D03*
X1330316D03*
X1316530Y149804D03*
X1320469D03*
X1324408D03*
X1328346D03*
X1318499Y154706D03*
X1322438D03*
X1326377D03*
X1330316D03*
X1316530Y153072D03*
X1320469D03*
X1324408D03*
X1328346D03*
X1316530Y231694D03*
X1320469D03*
X1324408D03*
X1328346D03*
X1318499Y230060D03*
X1322438D03*
X1326377D03*
X1330316D03*
X1316530Y228426D03*
X1320469D03*
X1324408D03*
X1328346D03*
X1318499Y226792D03*
X1322438D03*
X1326377D03*
X1330316D03*
X1334255Y151438D03*
X1338194D03*
X1342133D03*
X1346071D03*
X1332285Y149804D03*
X1336224D03*
X1340163D03*
X1344102D03*
X1334255Y154706D03*
X1338194D03*
X1342133D03*
X1346071D03*
X1332285Y153072D03*
X1336224D03*
X1340163D03*
X1344102D03*
X1332285Y231694D03*
X1336224D03*
X1340163D03*
X1344102D03*
X1334255Y230060D03*
X1338194D03*
X1342133D03*
X1346071D03*
X1332285Y228426D03*
X1336224D03*
X1340163D03*
X1344102D03*
X1334255Y226792D03*
X1338194D03*
X1342133D03*
X1346071D03*
X1350010Y151438D03*
X1353949D03*
X1357888D03*
X1361827D03*
X1348041Y149804D03*
X1351980D03*
X1355919D03*
X1359858D03*
X1362085Y167116D03*
X1360451Y165146D03*
X1362085Y163177D03*
X1360451Y161207D03*
X1362085Y159238D03*
X1360451Y157268D03*
X1350010Y154706D03*
X1353949D03*
X1357888D03*
X1362085Y155299D03*
X1348041Y153072D03*
X1351980D03*
X1355919D03*
X1359858D03*
X1360451Y184841D03*
X1362085Y182871D03*
X1360451Y180902D03*
X1362085Y178932D03*
X1360451Y176963D03*
X1362085Y174993D03*
X1360451Y173024D03*
X1362085Y171055D03*
X1360451Y169085D03*
Y196657D03*
X1362085Y194688D03*
X1360451Y192718D03*
X1362085Y190749D03*
X1360451Y188780D03*
X1362085Y186810D03*
X1360451Y200596D03*
X1362085Y198627D03*
X1360451Y216352D03*
X1362085Y214382D03*
X1360451Y212413D03*
X1362085Y210443D03*
X1360451Y208474D03*
X1362085Y206505D03*
X1360451Y204535D03*
X1362085Y202566D03*
X1348041Y231694D03*
X1351980D03*
X1355919D03*
X1359858D03*
X1350010Y230060D03*
X1353949D03*
X1357888D03*
X1361827D03*
X1348041Y228426D03*
X1351980D03*
X1355919D03*
X1359858D03*
X1350010Y226792D03*
X1353949D03*
X1357888D03*
X1362085Y226199D03*
X1360451Y224230D03*
X1362085Y222260D03*
X1360451Y220291D03*
X1362085Y218321D03*
X1364407Y150750D03*
X1365353Y167116D03*
X1363719Y165146D03*
X1365353Y163177D03*
X1363719Y161207D03*
X1365353Y159238D03*
X1363719Y157268D03*
X1365353Y155299D03*
X1363719Y153329D03*
Y184841D03*
X1365353Y182871D03*
X1363719Y180902D03*
X1365353Y178932D03*
X1363719Y176963D03*
X1365353Y174993D03*
X1363719Y173024D03*
X1365353Y171055D03*
X1363719Y169085D03*
Y196657D03*
X1365353Y194688D03*
X1363719Y192718D03*
X1365353Y190749D03*
X1363719Y188780D03*
X1365353Y186810D03*
X1363719Y200596D03*
X1365353Y198627D03*
X1363719Y216352D03*
X1365353Y214382D03*
X1363719Y212413D03*
X1365353Y210443D03*
X1363719Y208474D03*
X1365353Y206505D03*
X1363719Y204535D03*
X1365353Y202566D03*
X1364407Y230748D03*
X1363719Y228169D03*
X1365353Y226199D03*
X1363719Y224230D03*
X1365353Y222260D03*
X1363719Y220291D03*
X1365353Y218321D03*
G54D253*
X1037026Y286579D03*
G54D62*
X93361Y1533173D03*
G54D128*
X275630Y109804D03*
X708786Y113929D03*
X1750751Y110928D03*
G54D26*
X36595Y388035D03*
X46834Y366395D03*
X55190D03*
X54333Y1609817D03*
X57833Y1669317D03*
X53333D03*
X49333D03*
X61000Y1679183D03*
X70333Y1618817D03*
X69833Y1669317D03*
X73833D03*
X77833D03*
X65000Y1679183D03*
X90518Y640088D03*
X82014Y702575D03*
X92096Y697663D03*
X84474Y1523077D03*
X87500Y1564577D03*
X91500D03*
X81833Y1669317D03*
X90297Y1669363D03*
X85833Y1669317D03*
X108643Y526800D03*
X96774Y1529077D03*
X108800Y1611883D03*
X117597Y494374D03*
X113597D03*
X114720Y1683345D03*
X120910Y1726530D03*
X130317Y483296D03*
X135317D03*
X138489Y528432D03*
X134557Y1731165D03*
X149174Y483296D03*
X152470Y505846D03*
X149568Y1392653D03*
X152806Y1411442D03*
X158570Y1526488D03*
X154581Y1526447D03*
X159014Y1576892D03*
X154580D03*
X170673Y1412428D03*
X175067Y1733075D03*
X190110Y572455D03*
X187711Y1392653D03*
X181806Y1393673D03*
X177702D03*
X190949Y1411442D03*
X205320Y673045D03*
X201220D03*
X207716Y1411728D03*
X220387Y1393782D03*
X216090D03*
X212120Y1709745D03*
X237220Y65345D03*
X241220D03*
X249220D03*
X245220D03*
X251487Y107743D03*
X263580Y224085D03*
X270240Y242265D03*
X267759Y257714D03*
X271821D03*
X275797Y127026D03*
X276491Y257714D03*
X281077D03*
X286481D03*
X289274Y296371D03*
X284515D03*
X302517Y71475D03*
X301315Y98782D03*
X305315D03*
X291759Y257714D03*
X304651D03*
X298184Y296371D03*
X302765D03*
X293763D03*
X302684Y562850D03*
X303551Y1350799D03*
X322155Y235202D03*
X317995Y235232D03*
X317129Y257714D03*
X306736Y296371D03*
X316463D03*
X307019Y1369520D03*
X325617Y76846D03*
X338267Y213610D03*
X329648Y257660D03*
X329002Y296371D03*
X335679Y1328001D03*
X338917Y1346790D03*
X336205Y1353830D03*
X331773Y1351936D03*
X324656Y1369674D03*
X354672Y258151D03*
X342000Y258070D03*
X354145Y296049D03*
X341295Y295697D03*
X367306Y258269D03*
X366498Y295722D03*
X367717Y1314575D03*
X366903Y1338158D03*
X370874Y1333366D03*
X363805Y1329100D03*
X356784Y1346876D03*
X379860Y257954D03*
X379112Y295844D03*
X385797Y1398668D03*
X385123Y1634442D03*
X378497Y1634378D03*
X374500Y1645905D03*
X378509Y1685642D03*
X392616Y257944D03*
X392083Y296412D03*
X399935Y1314575D03*
X395933Y1315674D03*
X402973Y1333336D03*
X390029Y1332901D03*
X393699Y1405521D03*
X403125Y1422486D03*
X399134Y1422464D03*
X391293Y1634462D03*
X417765Y258263D03*
X404985Y257873D03*
X417218Y296732D03*
X404215Y296598D03*
X418616Y939131D03*
X410816D03*
X410795Y954148D03*
X414595D03*
X418595D03*
X414626Y968547D03*
X418626D03*
X410826D03*
X414600Y983060D03*
X410800D03*
X414600Y997375D03*
X410800D03*
X418600Y983060D03*
Y997375D03*
X418550Y1011933D03*
X410838D03*
X414550D03*
X410816Y1026543D03*
X414591D03*
X418591D03*
X409980Y1396936D03*
X431873Y258263D03*
X429702Y296221D03*
X422395Y939131D03*
Y954148D03*
X422426Y968547D03*
X422400Y983060D03*
X422350Y997375D03*
Y1011933D03*
X422391Y1026543D03*
X432063Y1314575D03*
X428061Y1315674D03*
X434983Y1333365D03*
X421224Y1332901D03*
X442265Y296397D03*
X448520Y419745D03*
X444020D03*
X442520Y473320D03*
X437520D03*
X451520D03*
X451014Y1400462D03*
X442020Y1567920D03*
X446020D03*
X452020Y1577920D03*
X437383Y1600137D03*
X458264Y263940D03*
X467736Y296881D03*
X467211Y369216D03*
X455720Y402245D03*
X462921Y427986D03*
X453020Y419745D03*
X457520D03*
X456520Y473320D03*
X461520D03*
X466704Y954148D03*
X462704D03*
X458904D03*
X462704Y968547D03*
X466704D03*
X458904D03*
X466704Y997375D03*
Y983060D03*
X458904D03*
X462704D03*
Y997375D03*
X458904D03*
X466704Y1011933D03*
X458904D03*
X462704D03*
X458904Y1026543D03*
X466704D03*
X462704D03*
X464191Y1314575D03*
X460189Y1315674D03*
X467644Y1333383D03*
X452961Y1332893D03*
X460020Y1577920D03*
X466320Y1599212D03*
X483500Y237845D03*
X474720Y366345D03*
X485020Y419745D03*
X480520D03*
X479169Y473179D03*
X474169D03*
X470504Y954148D03*
Y968547D03*
Y983060D03*
Y997375D03*
Y1011933D03*
Y1026543D03*
X485296Y1332893D03*
X478460Y1445562D03*
X501136Y296181D03*
X490720Y366345D03*
X498720D03*
X486720D03*
X499570Y427845D03*
X489520Y419745D03*
X494020D03*
X498169Y473179D03*
X493169D03*
X488169D03*
X492317Y1315674D03*
X496319Y1328001D03*
X499458Y1346822D03*
X510830Y109155D03*
X507750Y296066D03*
X506720Y366345D03*
X517720Y395845D03*
X505720D03*
X517020Y483935D03*
X517424Y1346876D03*
X506096Y1418300D03*
X518720Y366345D03*
X531720D03*
X523720D03*
X533720Y395845D03*
X521720D03*
X524445Y1329100D03*
X528447Y1350799D03*
X531610Y1369632D03*
X547330Y366225D03*
X548300Y411390D03*
X549552Y1369674D03*
X564698Y366185D03*
X554300Y411390D03*
X564300D03*
X559300D03*
X560969Y1351951D03*
X556586D03*
X557720Y1452845D03*
X552000D03*
X571556Y378032D03*
X578582Y366140D03*
X573460Y366185D03*
X569340D03*
X569152Y419470D03*
X598795Y146135D03*
X594220Y433845D03*
X606079Y124875D03*
X604725Y278113D03*
X607675Y323882D03*
X615635Y323938D03*
X618460Y124875D03*
X621536Y211559D03*
X618115Y278113D03*
X631146Y323973D03*
X623365Y323958D03*
X634500Y82845D03*
X638500D03*
X646815Y515367D03*
X642225Y1705677D03*
X646225D03*
X648320Y87245D03*
X659000Y94845D03*
X654895Y521077D03*
X650794Y521090D03*
X650845Y528163D03*
X663187Y1392678D03*
X651725Y1649177D03*
X654225Y1660677D03*
X650225Y1698677D03*
X667610Y113395D03*
X680220Y514345D03*
X675220Y527845D03*
X680220D03*
X666425Y1411467D03*
X684643Y111868D03*
X688470Y394645D03*
X685220Y501345D03*
X695220Y514345D03*
Y527845D03*
X691321Y1393698D03*
X695425D03*
X684292Y1411553D03*
X708953Y131151D03*
X708720Y383845D03*
X713220Y393845D03*
X705220Y501345D03*
X711220D03*
X705220Y527845D03*
X701330Y1392678D03*
X704568Y1411467D03*
X711719Y1642834D03*
X728220Y393845D03*
Y383845D03*
X718220Y393845D03*
X717220Y501345D03*
X723220D03*
X729220D03*
X717220Y514345D03*
X723220D03*
X729220D03*
X722435Y1411553D03*
X715780Y1620413D03*
X719770Y1620403D03*
X723820D03*
X718830Y1652953D03*
X737093Y90960D03*
X737340Y118718D03*
X741270Y118642D03*
X740200Y371208D03*
X738220Y393845D03*
X733220D03*
Y383845D03*
X745220Y514345D03*
X735220D03*
X735173Y527820D03*
X734006Y1393807D03*
X729709D03*
X743462Y1670228D03*
X739538Y1674238D03*
X760193Y96331D03*
X753089Y501360D03*
X749179Y501340D03*
X755859Y1692078D03*
X759359Y1726578D03*
X755359D03*
X764130Y116163D03*
X777220Y441345D03*
X763859Y1692078D03*
X794220Y428345D03*
X782800Y508545D03*
X783450Y519965D03*
X794600Y366183D03*
X802200D03*
X809800D03*
X809600Y386083D03*
X800498Y401509D03*
Y416109D03*
X831539Y65826D03*
X834615Y107264D03*
X835114Y120681D03*
X833715Y228051D03*
X832500Y270197D03*
X832400Y424383D03*
X828300D03*
X840200D03*
X856629Y65976D03*
X850015Y93234D03*
X858783Y227466D03*
X844200Y424383D03*
X863294Y269019D03*
X863571Y296868D03*
X867571D03*
X886503Y274390D03*
X880772Y879818D03*
X909293Y464911D03*
X913293D03*
X920747Y470710D03*
X921720Y1009845D03*
X924747Y470710D03*
X937747D03*
X933747D03*
X931496Y967670D03*
X927220Y1009845D03*
X941747Y470710D03*
X945747D03*
X947275Y979890D03*
X943750Y983135D03*
X985500Y151282D03*
X989605Y178536D03*
X985445Y178566D03*
X988835Y190936D03*
X1005735Y156926D03*
X1001395Y217406D03*
X1019939Y300396D03*
X1031270Y306545D03*
X1033268Y505285D03*
X1052705Y366178D03*
X1095457Y1644333D03*
X1099457D03*
X1115802Y1620753D03*
X1109287Y1672923D03*
X1122879Y1428982D03*
X1126117Y1447771D03*
X1120472Y1620743D03*
X1120432Y1628403D03*
X1151013Y1430002D03*
X1143984Y1447857D03*
X1160720Y186345D03*
X1155117Y1430002D03*
X1161022Y1428982D03*
X1164260Y1447771D03*
X1164830Y1651198D03*
X1159930D03*
X1163576Y1680532D03*
X1181476Y166789D03*
X1182127Y1447857D03*
X1175830Y1651198D03*
X1181930D03*
X1170930D03*
X1174576Y1680532D03*
X1195278Y139032D03*
X1193260Y1430002D03*
X1189156D03*
X1185080Y1621972D03*
X1197400Y1651508D03*
X1186830Y1651198D03*
X1192500Y1651508D03*
X1196146Y1680842D03*
X1185576Y1680532D03*
X1197240Y1696988D03*
X1192340D03*
X1195986Y1726322D03*
X1212202Y120600D03*
X1208010Y1697033D03*
X1203110D03*
X1213910Y1697298D03*
X1206756Y1726367D03*
X1220500Y210345D03*
X1218810Y1697298D03*
X1217556Y1726632D03*
X1263040Y106605D03*
X1258539Y106410D03*
X1259150Y302999D03*
X1255150D03*
X1274520Y84345D03*
X1281913Y82382D03*
X1271150Y302999D03*
X1279812Y1351035D03*
X1291823Y90752D03*
X1287913Y90702D03*
X1295767Y95199D03*
X1298407Y107950D03*
X1294937Y752448D03*
X1283280Y1369756D03*
X1311960Y55491D03*
X1309790Y65283D03*
X1311636Y75489D03*
X1307578Y75487D03*
X1308792Y94284D03*
X1310906Y103672D03*
X1314906D03*
X1311820Y1328001D03*
X1312346Y1353830D03*
X1308140Y1351897D03*
X1315058Y1346790D03*
X1300917Y1369910D03*
X1325902Y65340D03*
X1330102D03*
X1317831Y65283D03*
X1321869Y65265D03*
X1315649Y75488D03*
X1319721D03*
X1324120Y91391D03*
X1329891Y96806D03*
X1322906Y100186D03*
X1318906Y103666D03*
X1329646Y110452D03*
X1322906Y107216D03*
X1324093Y250945D03*
X1345083Y96826D03*
X1336549Y111428D03*
X1343858Y1314575D03*
X1339946Y1329100D03*
X1343044Y1338158D03*
X1347015Y1333366D03*
X1332925Y1346876D03*
X1349621Y109705D03*
X1358277Y1399078D03*
X1366124Y107012D03*
X1378550Y121644D03*
X1372074Y1315674D03*
X1376076Y1314575D03*
X1366170Y1332901D03*
X1379114Y1333336D03*
X1377075Y1422464D03*
X1394757Y939130D03*
X1386957D03*
X1394736Y954147D03*
X1390736D03*
X1386936D03*
X1390767Y968546D03*
X1394767D03*
X1386967D03*
X1390741Y997374D03*
X1386941D03*
X1394812Y983059D03*
X1390812D03*
X1387012D03*
X1394741Y997374D03*
X1394691Y1011932D03*
X1390691D03*
X1386891D03*
X1390732Y1026542D03*
X1386869D03*
X1394732D03*
X1386181Y1397136D03*
X1381066Y1422486D03*
X1385720Y1433345D03*
X1398557Y939130D03*
X1398536Y954147D03*
X1398567Y968546D03*
X1398612Y983059D03*
X1398541Y997374D03*
X1398491Y1011932D03*
X1398532Y1026542D03*
X1408204Y1314575D03*
X1404202Y1315674D03*
X1411124Y1333365D03*
X1397365Y1332901D03*
X1398700Y1603265D03*
X1427155Y1400462D03*
X1442845Y954147D03*
X1438845D03*
X1435045D03*
X1438845Y968546D03*
X1442845D03*
X1435045D03*
X1438845Y983059D03*
X1442845D03*
X1435045D03*
X1442845Y997374D03*
X1438845D03*
X1435045D03*
X1438845Y1011932D03*
X1442845D03*
X1435045D03*
X1438845Y1026542D03*
X1435045D03*
X1442845D03*
X1436330Y1315674D03*
X1440332Y1314575D03*
X1429102Y1332893D03*
X1443785Y1333383D03*
X1442573Y1655452D03*
X1451700Y294183D03*
X1445777Y367479D03*
X1449600Y399795D03*
X1446645Y954147D03*
Y968546D03*
Y983059D03*
Y997374D03*
Y1011932D03*
Y1026542D03*
X1461437Y1332893D03*
X1454938Y1445436D03*
X1454207Y1631048D03*
X1459117Y1631028D03*
X1462777Y367479D03*
X1477384Y416771D03*
X1468458Y1315674D03*
X1472460Y1328001D03*
X1475599Y1346822D03*
X1463747Y1631028D03*
X1467840Y1631085D03*
X1473527Y1661032D03*
X1489564Y367181D03*
X1493874D03*
X1481484Y367271D03*
X1489384Y416771D03*
X1493565Y1346876D03*
X1482237Y1418300D03*
X1500904Y385751D03*
X1500586Y1329100D03*
X1504588Y1350799D03*
X1507751Y1369632D03*
X1526118Y116088D03*
X1525693Y1369674D03*
X1539720Y587345D03*
X1532727Y1351951D03*
X1537110D03*
X1543779Y124261D03*
X1556747Y592398D03*
X1552720Y587345D03*
X1546312Y640699D03*
X1550162D03*
X1619515Y117542D03*
X1624353Y1426274D03*
X1627591Y1445063D03*
X1654110Y431685D03*
X1654032Y656992D03*
Y690992D03*
X1652487Y1427294D03*
X1656591D03*
X1645458Y1445149D03*
X1659610Y400185D03*
X1663610D03*
X1663376Y521071D03*
X1667376D03*
X1657632Y553397D03*
X1665706Y589039D03*
X1661506D03*
X1661132Y623492D03*
X1661120Y616945D03*
X1658085Y645094D03*
Y679094D03*
Y713094D03*
X1662496Y1426274D03*
X1665734Y1445063D03*
X1688504Y404543D03*
X1683601Y1445149D03*
X1694314Y431638D03*
X1690154Y431668D03*
X1693648Y469259D03*
X1697648D03*
X1703960Y546986D03*
X1690080Y555240D03*
X1703768Y701889D03*
X1695446Y707001D03*
X1695172Y1427403D03*
X1690875D03*
X1716875Y65452D03*
X1711832Y65216D03*
X1720895Y65452D03*
X1711832Y78704D03*
X1716965Y78692D03*
X1710426Y410646D03*
X1717686Y502460D03*
X1725520Y65345D03*
X1726608Y108867D03*
X1750918Y128150D03*
X1752324Y203475D03*
X1738290Y420323D03*
X1767638Y72599D03*
X1767891Y100303D03*
X1771891D03*
X1779226Y281087D03*
X1778810Y447045D03*
X1790738Y77970D03*
X1802150Y1502463D03*
X1797722Y1502526D03*
X1790011Y1514481D03*
X1813955Y146003D03*
X1849191Y166358D03*
X1836750Y379466D03*
G54D272*
X1270142Y134311D03*
G54D53*
X91949Y714088D03*
X1705381Y718214D03*
G54D35*
X55374Y390301D03*
X618644Y148781D03*
G54D209*
X805690Y204724D03*
X1057658D03*
G54D164*
X451062Y364503D03*
X448503D03*
X445944D03*
Y387503D03*
X448503D03*
X451062D03*
X451421Y434003D03*
X448862D03*
X446303D03*
X443744D03*
Y457003D03*
X446303D03*
X448862D03*
X451421D03*
X461298Y364503D03*
X458739D03*
X456180D03*
X453621D03*
Y387503D03*
X456180D03*
X458739D03*
X461298D03*
X459098Y434003D03*
X456539D03*
X453980D03*
Y457003D03*
X456539D03*
X459098D03*
X482952Y433862D03*
X480393D03*
Y456862D03*
X482952D03*
X495747Y433862D03*
X493188D03*
X490629D03*
X488070D03*
X485511D03*
Y456862D03*
X488070D03*
X490629D03*
X493188D03*
X495747D03*
X550024Y373573D03*
Y396573D03*
X565378Y373573D03*
X562819D03*
X560260D03*
X557701D03*
X555142D03*
X552583D03*
Y396573D03*
X555142D03*
X557701D03*
X560260D03*
X562819D03*
X565378D03*
X842596Y58448D03*
X840037D03*
Y81448D03*
X842596D03*
X847715Y58448D03*
X845156D03*
Y81448D03*
X847715D03*
X1460718Y378996D03*
X1458159D03*
X1455600D03*
Y401996D03*
X1458159D03*
X1460718D03*
X1470954Y378996D03*
X1468395D03*
X1465836D03*
X1463277D03*
Y401996D03*
X1465836D03*
X1468395D03*
X1470954D03*
X1492002Y378788D03*
X1489443D03*
X1486884D03*
X1484325D03*
X1481766D03*
X1479207D03*
Y401788D03*
X1481766D03*
X1484325D03*
X1486884D03*
X1489443D03*
X1492002D03*
X1494561Y378788D03*
Y401788D03*
G54D155*
X393415Y209949D03*
Y212508D03*
Y215067D03*
Y217626D03*
Y220185D03*
Y222744D03*
Y225303D03*
X416415Y217626D03*
Y215067D03*
Y212508D03*
Y209949D03*
Y225303D03*
Y222744D03*
Y220185D03*
X471000Y212685D03*
Y215244D03*
Y217803D03*
Y220362D03*
Y222921D03*
Y225480D03*
Y228039D03*
X494000Y217803D03*
Y215244D03*
Y212685D03*
Y228039D03*
Y225480D03*
Y222921D03*
Y220362D03*
X598416Y222287D03*
Y224846D03*
Y227406D03*
Y229965D03*
X616014D03*
Y227406D03*
Y224846D03*
Y222287D03*
X1436383Y222771D03*
Y225330D03*
Y227889D03*
Y230448D03*
Y233007D03*
Y235566D03*
Y238125D03*
X1435880Y251265D03*
Y253824D03*
Y256383D03*
Y258942D03*
Y261501D03*
Y264060D03*
Y266619D03*
X1459383Y233007D03*
Y230448D03*
Y227889D03*
Y225330D03*
Y222771D03*
Y238125D03*
Y235566D03*
X1458880Y266619D03*
Y264060D03*
Y261501D03*
Y258942D03*
Y256383D03*
Y253824D03*
Y251265D03*
G54D218*
X839035Y512888D03*
Y515447D03*
Y518006D03*
X845483D03*
Y515447D03*
Y512888D03*
G54D146*
X347876Y148462D03*
Y152202D03*
Y155942D03*
X357324Y148462D03*
Y155942D03*
X548670Y442656D03*
Y446396D03*
Y450136D03*
X558118Y442656D03*
Y450136D03*
X1079225Y55682D03*
Y59422D03*
Y63162D03*
X1088673Y55682D03*
Y63162D03*
X1223507Y54100D03*
X1232955D03*
X1223507Y61580D03*
X1232955D03*
Y57840D03*
X1516776Y122122D03*
Y129602D03*
X1526224D03*
Y125862D03*
Y122122D03*
G54D44*
X77416Y1536519D03*
Y1538094D03*
Y1539669D03*
G54D308*
X1758539Y298879D03*
X1772319D03*
G54D182*
X542554Y465696D03*
Y468255D03*
Y470814D03*
Y473373D03*
Y475932D03*
Y478492D03*
Y481051D03*
Y483610D03*
Y486169D03*
Y488728D03*
X565586Y478492D03*
Y475932D03*
Y473373D03*
Y470814D03*
Y468255D03*
Y465696D03*
Y488728D03*
Y486169D03*
Y483610D03*
Y481051D03*
X1790546Y441108D03*
Y443667D03*
Y446226D03*
Y448785D03*
Y451344D03*
Y453904D03*
Y456463D03*
Y459022D03*
Y461581D03*
Y464140D03*
X1813578Y443667D03*
Y441108D03*
Y461581D03*
Y459022D03*
Y456463D03*
Y453904D03*
Y451344D03*
Y448785D03*
Y446226D03*
Y464140D03*
G54D254*
X1025609Y286776D03*
X1027183D03*
X1028758D03*
X1030333D03*
X1031908D03*
X1033483D03*
X1035057D03*
X1802550Y1510568D03*
X1800975D03*
X1799400D03*
X1797826D03*
X1807274D03*
X1805700D03*
X1804125D03*
G54D71*
X110757Y388071D03*
Y392071D03*
X113907Y388071D03*
D03*
X117057D03*
X113907Y392071D03*
D03*
X117057D03*
X155226Y425383D03*
X158376D03*
D03*
X155226Y421383D03*
X158376D03*
D03*
X155226Y417383D03*
X158376D03*
D03*
X155226Y443319D03*
X158376D03*
D03*
Y439397D03*
X155226D03*
X158376D03*
Y435383D03*
X155226D03*
X158376D03*
X155226Y430883D03*
X158376D03*
D03*
X161526Y425383D03*
Y421383D03*
Y417383D03*
Y443319D03*
Y439397D03*
Y435383D03*
Y430883D03*
X235147Y127118D03*
X238297D03*
X1013620Y226423D03*
X1016770D03*
X1671605Y201670D03*
X1674755D03*
X1710268Y128242D03*
X1713418D03*
G54D236*
X956404Y1558189D03*
X951404D03*
X946404D03*
X961404D03*
X969770D03*
X984770D03*
X979770D03*
X974770D03*
X1003136D03*
X998136D03*
X993136D03*
X1008136D03*
X1021502D03*
X1016502D03*
X1031502D03*
X1026502D03*
X1054868D03*
X1049868D03*
X1044868D03*
X1039868D03*
X1068234D03*
X1063234D03*
X1078234D03*
X1073234D03*
X1086600D03*
X1101600D03*
X1096600D03*
X1091600D03*
X1735111Y1467176D03*
X1730111D03*
X1745111D03*
X1740111D03*
G54D245*
X1003672Y376725D03*
X1001704D03*
X999735D03*
X997767D03*
X995798D03*
X993830D03*
Y407237D03*
X995798D03*
X997767D03*
X999735D03*
X1001704D03*
X1003672D03*
X1019420Y376725D03*
X1017452D03*
X1015483D03*
X1013515D03*
X1011546D03*
X1009578D03*
X1007609D03*
X1005641D03*
Y407237D03*
X1007609D03*
X1009578D03*
X1011546D03*
X1013515D03*
X1015483D03*
X1017452D03*
X1019420D03*
G54D173*
X500453Y1410179D03*
X1476594D03*
G54D80*
X109960Y1687921D03*
Y1685362D03*
Y1682803D03*
X102480D03*
Y1685362D03*
Y1687921D03*
X109960Y1696362D03*
Y1693803D03*
X102480D03*
Y1696362D03*
X109960Y1698921D03*
X102480D03*
X462060Y1645841D03*
Y1643282D03*
Y1640723D03*
X454580D03*
Y1643282D03*
Y1645841D03*
X558240Y311616D03*
Y309057D03*
Y306498D03*
X550760D03*
Y309057D03*
Y311616D03*
X658960Y1722921D03*
Y1720362D03*
Y1717803D03*
X651480D03*
Y1720362D03*
Y1722921D03*
X674880Y1668303D03*
Y1670862D03*
Y1673421D03*
X682360D03*
Y1670862D03*
Y1668303D03*
X1408250Y1600723D03*
Y1603282D03*
Y1605841D03*
X1415730Y1600723D03*
Y1605841D03*
Y1603282D03*
G54D263*
X1156378Y133866D03*
G54D227*
X928739Y323031D03*
G54D119*
X238780Y1643661D03*
X230906Y1649173D03*
X238780Y1653110D03*
Y1657834D03*
X230906Y1653897D03*
Y1663346D03*
X238780Y1667283D03*
Y1672007D03*
Y1681456D03*
X230906Y1668070D03*
Y1677519D03*
Y1682244D03*
X238780Y1686180D03*
Y1695629D03*
X230906Y1691692D03*
Y1696417D03*
X238780Y1700354D03*
Y1709803D03*
Y1714527D03*
X230906Y1705866D03*
Y1710590D03*
X238780Y1723976D03*
Y1728700D03*
X230906Y1720039D03*
Y1724763D03*
X254528Y1643661D03*
X246654Y1649173D03*
X254528Y1653110D03*
Y1657834D03*
X246654Y1653897D03*
Y1663346D03*
X254528Y1667283D03*
Y1672007D03*
Y1681456D03*
X246654Y1668070D03*
Y1677519D03*
Y1682244D03*
X254528Y1686180D03*
Y1695629D03*
X246654Y1691692D03*
Y1696417D03*
X254528Y1700354D03*
Y1709803D03*
Y1714527D03*
X246654Y1705866D03*
Y1710590D03*
X254528Y1723976D03*
Y1728700D03*
X246654Y1720039D03*
Y1724763D03*
Y1734212D03*
X270276Y1643661D03*
X262402Y1649173D03*
X270276Y1653110D03*
Y1657834D03*
X262402Y1653897D03*
Y1663346D03*
X270276Y1667283D03*
Y1672007D03*
Y1681456D03*
X262402Y1668070D03*
Y1677519D03*
Y1682244D03*
X270276Y1686180D03*
Y1695629D03*
X262402Y1691692D03*
Y1696417D03*
X270276Y1700354D03*
Y1709803D03*
Y1714527D03*
X262402Y1705866D03*
Y1710590D03*
X270276Y1723976D03*
Y1728700D03*
X262402Y1720039D03*
Y1724763D03*
Y1734212D03*
X286024Y1643661D03*
X278150Y1649173D03*
X286024Y1653110D03*
Y1657834D03*
X278150Y1653897D03*
Y1663346D03*
X286024Y1667283D03*
Y1672007D03*
Y1681456D03*
X278150Y1668070D03*
Y1677519D03*
Y1682244D03*
X286024Y1686180D03*
Y1695629D03*
X278150Y1691692D03*
Y1696417D03*
X286024Y1700354D03*
Y1709803D03*
Y1714527D03*
X278150Y1705866D03*
Y1710590D03*
X286024Y1723976D03*
Y1728700D03*
X278150Y1720039D03*
Y1724763D03*
Y1734212D03*
X305709Y1672007D03*
X297835Y1677519D03*
Y1682244D03*
X305709Y1681456D03*
Y1686180D03*
X297835Y1691692D03*
Y1696417D03*
X305709Y1695629D03*
Y1700354D03*
X297835Y1705866D03*
Y1710590D03*
X305709Y1709803D03*
Y1714527D03*
X297835Y1720039D03*
Y1724763D03*
X305709Y1723976D03*
Y1728700D03*
X321457Y1672007D03*
X313583Y1677519D03*
Y1682244D03*
X321457Y1681456D03*
Y1686180D03*
X313583Y1691692D03*
Y1696417D03*
X321457Y1695629D03*
Y1700354D03*
X313583Y1705866D03*
Y1710590D03*
X321457Y1709803D03*
Y1714527D03*
X313583Y1720039D03*
Y1724763D03*
X321457Y1723976D03*
Y1728700D03*
X313583Y1734212D03*
X337205Y1672007D03*
X329331Y1677519D03*
Y1682244D03*
X337205Y1681456D03*
Y1686180D03*
X329331Y1691692D03*
Y1696417D03*
X337205Y1695629D03*
Y1700354D03*
X329331Y1705866D03*
Y1710590D03*
X337205Y1709803D03*
Y1714527D03*
X329331Y1720039D03*
Y1724763D03*
X337205Y1723976D03*
Y1728700D03*
X329331Y1734212D03*
X352953Y1672007D03*
X345079Y1677519D03*
Y1682244D03*
X352953Y1681456D03*
Y1686180D03*
X345079Y1691692D03*
Y1696417D03*
X352953Y1695629D03*
Y1700354D03*
X345079Y1705866D03*
Y1710590D03*
X352953Y1709803D03*
Y1714527D03*
X345079Y1720039D03*
Y1724763D03*
X352953Y1723976D03*
Y1728700D03*
X345079Y1734212D03*
X495079Y1677519D03*
Y1682244D03*
Y1691692D03*
Y1696417D03*
Y1705866D03*
Y1710590D03*
Y1720039D03*
Y1724763D03*
X502953Y1672007D03*
X510827Y1677519D03*
X502953Y1681456D03*
X510827Y1682244D03*
X502953Y1686180D03*
X510827Y1691692D03*
X502953Y1695629D03*
X510827Y1696417D03*
X502953Y1700354D03*
X510827Y1705866D03*
X502953Y1709803D03*
X510827Y1710590D03*
X502953Y1714527D03*
X510827Y1720039D03*
X502953Y1723976D03*
X510827Y1724763D03*
X502953Y1728700D03*
X510827Y1734212D03*
X518701Y1672007D03*
X534449D03*
X526575Y1677519D03*
X518701Y1681456D03*
X526575Y1682244D03*
X534449Y1681456D03*
X518701Y1686180D03*
X534449D03*
X526575Y1691692D03*
X518701Y1695629D03*
X526575Y1696417D03*
X534449Y1695629D03*
X518701Y1700354D03*
X534449D03*
X526575Y1705866D03*
X518701Y1709803D03*
X526575Y1710590D03*
X534449Y1709803D03*
X518701Y1714527D03*
X534449D03*
X526575Y1720039D03*
X518701Y1723976D03*
X526575Y1724763D03*
X534449Y1723976D03*
X518701Y1728700D03*
X534449D03*
X526575Y1734212D03*
X550197Y1672007D03*
X542323Y1677519D03*
Y1682244D03*
X550197Y1681456D03*
Y1686180D03*
X542323Y1691692D03*
Y1696417D03*
X550197Y1695629D03*
Y1700354D03*
X542323Y1705866D03*
Y1710590D03*
X550197Y1709803D03*
Y1714527D03*
X542323Y1720039D03*
Y1724763D03*
X550197Y1723976D03*
Y1728700D03*
X542323Y1734212D03*
X562008Y1677519D03*
Y1682244D03*
Y1691692D03*
Y1696417D03*
Y1705866D03*
Y1710590D03*
Y1720039D03*
Y1724763D03*
X569882Y1672007D03*
X577756Y1677519D03*
X569882Y1681456D03*
X577756Y1682244D03*
X569882Y1686180D03*
X577756Y1691692D03*
X569882Y1695629D03*
X577756Y1696417D03*
X569882Y1700354D03*
X577756Y1705866D03*
X569882Y1709803D03*
X577756Y1710590D03*
X569882Y1714527D03*
X577756Y1720039D03*
X569882Y1723976D03*
X577756Y1724763D03*
X569882Y1728700D03*
X577756Y1734212D03*
X585630Y1672007D03*
X593504Y1677519D03*
X585630Y1681456D03*
X593504Y1682244D03*
X585630Y1686180D03*
X593504Y1691692D03*
X585630Y1695629D03*
X593504Y1696417D03*
X585630Y1700354D03*
X593504Y1705866D03*
X585630Y1709803D03*
X593504Y1710590D03*
X585630Y1714527D03*
X593504Y1720039D03*
X585630Y1723976D03*
X593504Y1724763D03*
X585630Y1728700D03*
X593504Y1734212D03*
X601378Y1672007D03*
X609252Y1677519D03*
X601378Y1681456D03*
X609252Y1682244D03*
X601378Y1686180D03*
X609252Y1691692D03*
X601378Y1695629D03*
X609252Y1696417D03*
X601378Y1700354D03*
X609252Y1705866D03*
X601378Y1709803D03*
X609252Y1710590D03*
X601378Y1714527D03*
X609252Y1720039D03*
X601378Y1723976D03*
X609252Y1724763D03*
X601378Y1728700D03*
X609252Y1734212D03*
X617126Y1672007D03*
Y1681456D03*
Y1686180D03*
Y1695629D03*
Y1700354D03*
Y1709803D03*
Y1714527D03*
Y1723976D03*
Y1728700D03*
X1246654Y1672007D03*
X1238780Y1677519D03*
Y1682244D03*
X1246654Y1681456D03*
Y1686180D03*
X1238780Y1691692D03*
Y1696417D03*
X1246654Y1695629D03*
Y1700354D03*
X1238780Y1705866D03*
Y1710590D03*
X1246654Y1709803D03*
Y1714527D03*
X1238780Y1720039D03*
Y1724763D03*
X1246654Y1723976D03*
Y1728700D03*
X1262402Y1672007D03*
X1254528Y1677519D03*
Y1682244D03*
X1262402Y1681456D03*
Y1686180D03*
X1254528Y1691692D03*
Y1696417D03*
X1262402Y1695629D03*
Y1700354D03*
X1254528Y1705866D03*
Y1710590D03*
X1262402Y1709803D03*
Y1714527D03*
X1254528Y1720039D03*
Y1724763D03*
X1262402Y1723976D03*
Y1728700D03*
X1254528Y1734212D03*
X1278150Y1672007D03*
X1270276Y1677519D03*
Y1682244D03*
X1278150Y1681456D03*
Y1686180D03*
X1270276Y1691692D03*
Y1696417D03*
X1278150Y1695629D03*
Y1700354D03*
X1270276Y1705866D03*
Y1710590D03*
X1278150Y1709803D03*
Y1714527D03*
X1270276Y1720039D03*
Y1724763D03*
X1278150Y1723976D03*
Y1728700D03*
X1270276Y1734212D03*
X1293898Y1672007D03*
X1286024Y1677519D03*
Y1682244D03*
X1293898Y1681456D03*
Y1686180D03*
X1286024Y1691692D03*
Y1696417D03*
X1293898Y1695629D03*
Y1700354D03*
X1286024Y1705866D03*
Y1710590D03*
X1293898Y1709803D03*
Y1714527D03*
X1286024Y1720039D03*
Y1724763D03*
X1293898Y1723976D03*
Y1728700D03*
X1286024Y1734212D03*
X1313583Y1672007D03*
X1305709Y1677519D03*
Y1682244D03*
X1313583Y1681456D03*
Y1686180D03*
X1305709Y1691692D03*
Y1696417D03*
X1313583Y1695629D03*
Y1700354D03*
X1305709Y1705866D03*
Y1710590D03*
X1313583Y1709803D03*
Y1714527D03*
X1305709Y1720039D03*
Y1724763D03*
X1313583Y1723976D03*
Y1728700D03*
X1329331Y1672007D03*
X1321457Y1677519D03*
Y1682244D03*
X1329331Y1681456D03*
Y1686180D03*
X1321457Y1691692D03*
Y1696417D03*
X1329331Y1695629D03*
Y1700354D03*
X1321457Y1705866D03*
Y1710590D03*
X1329331Y1709803D03*
Y1714527D03*
X1321457Y1720039D03*
Y1724763D03*
X1329331Y1723976D03*
Y1728700D03*
X1321457Y1734212D03*
X1345079Y1672007D03*
X1337205Y1677519D03*
Y1682244D03*
X1345079Y1681456D03*
Y1686180D03*
X1337205Y1691692D03*
Y1696417D03*
X1345079Y1695629D03*
Y1700354D03*
X1337205Y1705866D03*
Y1710590D03*
X1345079Y1709803D03*
Y1714527D03*
X1337205Y1720039D03*
Y1724763D03*
X1345079Y1723976D03*
Y1728700D03*
X1337205Y1734212D03*
X1360827Y1672007D03*
X1352953Y1677519D03*
Y1682244D03*
X1360827Y1681456D03*
Y1686180D03*
X1352953Y1691692D03*
Y1696417D03*
X1360827Y1695629D03*
Y1700354D03*
X1352953Y1705866D03*
Y1710590D03*
X1360827Y1709803D03*
Y1714527D03*
X1352953Y1720039D03*
Y1724763D03*
X1360827Y1723976D03*
Y1728700D03*
X1352953Y1734212D03*
X1510827Y1672007D03*
X1502953Y1677519D03*
Y1682244D03*
X1510827Y1681456D03*
Y1686180D03*
X1502953Y1691692D03*
Y1696417D03*
X1510827Y1695629D03*
Y1700354D03*
X1502953Y1705866D03*
Y1710590D03*
X1510827Y1709803D03*
Y1714527D03*
X1502953Y1720039D03*
Y1724763D03*
X1510827Y1723976D03*
Y1728700D03*
X1526575Y1672007D03*
X1518701Y1677519D03*
Y1682244D03*
X1526575Y1681456D03*
Y1686180D03*
X1518701Y1691692D03*
Y1696417D03*
X1526575Y1695629D03*
Y1700354D03*
X1518701Y1705866D03*
Y1710590D03*
X1526575Y1709803D03*
Y1714527D03*
X1518701Y1720039D03*
Y1724763D03*
X1526575Y1723976D03*
Y1728700D03*
X1518701Y1734212D03*
X1542323Y1672007D03*
X1534449Y1677519D03*
Y1682244D03*
X1542323Y1681456D03*
Y1686180D03*
X1534449Y1691692D03*
Y1696417D03*
X1542323Y1695629D03*
Y1700354D03*
X1534449Y1705866D03*
Y1710590D03*
X1542323Y1709803D03*
Y1714527D03*
X1534449Y1720039D03*
Y1724763D03*
X1542323Y1723976D03*
Y1728700D03*
X1534449Y1734212D03*
X1558071Y1672007D03*
X1550197Y1677519D03*
Y1682244D03*
X1558071Y1681456D03*
Y1686180D03*
X1550197Y1691692D03*
Y1696417D03*
X1558071Y1695629D03*
Y1700354D03*
X1550197Y1705866D03*
Y1710590D03*
X1558071Y1709803D03*
Y1714527D03*
X1550197Y1720039D03*
Y1724763D03*
X1558071Y1723976D03*
Y1728700D03*
X1550197Y1734212D03*
X1569882Y1677519D03*
Y1682244D03*
Y1691692D03*
Y1696417D03*
Y1705866D03*
Y1710590D03*
Y1720039D03*
Y1724763D03*
X1577756Y1672007D03*
X1585630Y1677519D03*
X1577756Y1681456D03*
X1585630Y1682244D03*
X1577756Y1686180D03*
X1585630Y1691692D03*
X1577756Y1695629D03*
X1585630Y1696417D03*
X1577756Y1700354D03*
X1585630Y1705866D03*
X1577756Y1709803D03*
X1585630Y1710590D03*
X1577756Y1714527D03*
X1585630Y1720039D03*
X1577756Y1723976D03*
X1585630Y1724763D03*
X1577756Y1728700D03*
X1585630Y1734212D03*
X1593504Y1672007D03*
X1601378Y1677519D03*
X1593504Y1681456D03*
X1601378Y1682244D03*
X1593504Y1686180D03*
X1601378Y1691692D03*
X1593504Y1695629D03*
X1601378Y1696417D03*
X1593504Y1700354D03*
X1601378Y1705866D03*
X1593504Y1709803D03*
X1601378Y1710590D03*
X1593504Y1714527D03*
X1601378Y1720039D03*
X1593504Y1723976D03*
X1601378Y1724763D03*
X1593504Y1728700D03*
X1601378Y1734212D03*
X1609252Y1672007D03*
X1617126Y1677519D03*
X1609252Y1681456D03*
X1617126Y1682244D03*
X1609252Y1686180D03*
X1617126Y1691692D03*
X1609252Y1695629D03*
X1617126Y1696417D03*
X1609252Y1700354D03*
X1617126Y1705866D03*
X1609252Y1709803D03*
X1617126Y1710590D03*
X1609252Y1714527D03*
X1617126Y1720039D03*
X1609252Y1723976D03*
X1617126Y1724763D03*
X1609252Y1728700D03*
X1617126Y1734212D03*
X1625000Y1672007D03*
Y1681456D03*
Y1686180D03*
Y1695629D03*
Y1700354D03*
Y1709803D03*
Y1714527D03*
Y1723976D03*
Y1728700D03*
G54D137*
X317642Y1296728D03*
Y1330192D03*
X349650Y1273694D03*
Y1307158D03*
X381731Y1260612D03*
Y1294076D03*
X413909Y1260612D03*
Y1294076D03*
X446256Y1260612D03*
Y1294076D03*
X478433Y1260612D03*
Y1294076D03*
X510620Y1273793D03*
Y1307257D03*
X542985Y1296463D03*
Y1329927D03*
X1293783Y1296728D03*
Y1330192D03*
X1325791Y1273694D03*
Y1307158D03*
X1357872Y1260612D03*
Y1294076D03*
X1390050Y1260612D03*
Y1294076D03*
X1422397Y1260612D03*
Y1294076D03*
X1454574Y1260612D03*
Y1294076D03*
X1486761Y1273793D03*
Y1307257D03*
X1519126Y1296463D03*
Y1329927D03*
G54D290*
X1554724Y211909D03*
Y236909D03*
G54D17*
X19360Y304152D03*
X46720Y200787D03*
Y192913D03*
X46745Y208661D03*
X46720Y216535D03*
Y232283D03*
X46359Y240157D03*
X36000Y295952D03*
X39600Y378562D03*
X44700Y375262D03*
X49357Y406260D03*
X40800Y400962D03*
X34356Y412914D03*
X34440Y406562D03*
X47940Y1635504D03*
X43450Y1638102D03*
X59410Y57052D03*
X56370Y66552D03*
X60220Y80860D03*
X63048Y78031D03*
X49594Y304848D03*
X50200Y375262D03*
X63350Y371362D03*
X57342Y375262D03*
X53500Y371362D03*
X52185Y409088D03*
X64922Y405732D03*
X60522D03*
X60333Y1623834D03*
X50333D03*
X55333D03*
X62075Y1661030D03*
X65088Y1666334D03*
X62833Y1671334D03*
X65710Y376042D03*
X70500Y381562D03*
X76200Y395865D03*
X71136Y390398D03*
X76600Y386364D03*
X71480Y399442D03*
X72274Y1530094D03*
X68274Y1533594D03*
X70250Y1544094D03*
X69274Y1539094D03*
X77040Y1601102D03*
X65120Y1609909D03*
X65520Y1615972D03*
X66000Y1623800D03*
X76000D03*
X81000D03*
X71000D03*
X78333Y1661334D03*
X73333D03*
X68088Y1660691D03*
X77833Y1678902D03*
X73833Y1674252D03*
X69833Y1678582D03*
X94585Y164327D03*
X96880Y216535D03*
X96540Y232283D03*
X96396Y416383D03*
X96496Y430383D03*
X96396Y425383D03*
X97496Y446519D03*
X97096Y436383D03*
X97396Y441383D03*
X95250Y637848D03*
X94250Y649702D03*
X94408Y644740D03*
X94160Y657130D03*
X86050Y1527962D03*
X85487Y1556594D03*
X92928Y1556094D03*
X86000Y1623800D03*
X90100Y1650862D03*
X83333Y1661214D03*
X87600Y1655562D03*
X81833Y1674526D03*
X99480Y177165D03*
X106045Y303798D03*
X98896Y420883D03*
X113700Y536792D03*
X108550D03*
X102310Y685500D03*
X112270Y1518907D03*
X102070Y1524694D03*
X101274Y1535594D03*
X100236Y1549531D03*
X100274Y1540594D03*
X101363Y1600667D03*
X101558Y1619821D03*
X104500Y1655800D03*
X109960Y1677362D03*
X118820Y274800D03*
X116482Y409571D03*
X129480Y536662D03*
X124435Y536727D03*
X118880Y536862D03*
X125620Y631065D03*
X119263Y1601131D03*
X123750Y1616882D03*
X119058Y1637862D03*
X117100Y1651800D03*
X121645Y1683362D03*
X114720Y1691362D03*
X114991Y1702633D03*
X138482Y384071D03*
Y392881D03*
X135482Y388571D03*
Y404385D03*
X134896Y429883D03*
X138896Y426608D03*
X134896Y422883D03*
Y443383D03*
X138896Y433383D03*
Y439883D03*
X134896Y436383D03*
X143922Y531783D03*
X133160Y532002D03*
X138793Y1535926D03*
X139453Y1548920D03*
X139247Y1542048D03*
X142884Y1555204D03*
X138300Y1625200D03*
X152877Y411530D03*
X147800Y1414500D03*
X158307Y1531330D03*
X154685Y1558156D03*
X159794Y1558238D03*
X175982Y383071D03*
X173482Y387571D03*
X175982Y392071D03*
X173482Y396571D03*
Y405571D03*
X175982Y401071D03*
X166690Y427733D03*
X166917Y421148D03*
X167359Y443845D03*
X166580Y433115D03*
X171570Y1535141D03*
X174501Y1539847D03*
X175121Y1545985D03*
X172623Y1551715D03*
X169754Y1542489D03*
X175064Y1557874D03*
X181266Y234993D03*
X220054Y462235D03*
X223554Y458235D03*
X220200Y454162D03*
X237220Y57362D03*
X242220D03*
X242200Y119302D03*
X237933Y107835D03*
X239740Y134102D03*
X236920Y146829D03*
X237400Y163962D03*
X228024Y316772D03*
X252220Y57362D03*
X247220D03*
X253090Y87362D03*
X246297Y132012D03*
X254825Y151937D03*
X254940Y146879D03*
X259500Y162662D03*
X260300Y304762D03*
X275000Y153862D03*
X275053Y148703D03*
X275000Y159203D03*
X276234Y165350D03*
X276190Y215532D03*
X270740Y215582D03*
X262140Y234282D03*
X269740D03*
X271620Y266602D03*
X267759Y262672D03*
X274600Y305762D03*
X265824Y305962D03*
X271877Y750415D03*
X272208Y768516D03*
X282000Y143962D03*
X277000D03*
X287200D03*
X292500Y144013D03*
X286234Y165350D03*
X281234D03*
X277340Y234282D03*
X291754Y266962D03*
X281120Y267002D03*
X276620Y262572D03*
X286320Y262752D03*
X279400Y296463D03*
X277046Y735442D03*
X283350Y728483D03*
X285046Y737964D03*
X297700Y144162D03*
X302290Y191222D03*
X307640Y234652D03*
X304354Y263002D03*
X299120Y302112D03*
X304500Y303862D03*
X294760Y553672D03*
X293027Y755985D03*
X316900Y139962D03*
X314249Y223352D03*
X316954Y262752D03*
X316224Y305762D03*
X321100Y360422D03*
X309573Y567704D03*
X319590Y567906D03*
X339195Y131052D03*
X337464Y137082D03*
X335000Y162862D03*
X329648Y262677D03*
X341295Y300452D03*
X332000Y302862D03*
X332808Y357484D03*
X327310Y363143D03*
X327470Y374917D03*
X327550Y388243D03*
X327060Y400371D03*
X327150Y409452D03*
X331020Y594362D03*
X342500Y155942D03*
X342000Y263087D03*
X354672Y263068D03*
X354145Y300892D03*
X355671Y364133D03*
X354100Y720743D03*
X367341Y151303D03*
X373720Y214862D03*
X367326Y263050D03*
X366498Y300723D03*
X364667Y357923D03*
X359000Y359762D03*
X360680Y383412D03*
X357946Y369798D03*
X360140Y375392D03*
X361040Y389478D03*
X360880Y400628D03*
X359669Y686744D03*
X371850Y1534062D03*
X369000Y1639500D03*
X386720Y212508D03*
X386690Y229142D03*
X386540Y223342D03*
X379954Y263232D03*
X379107Y300712D03*
X386670Y297482D03*
X387070Y359122D03*
X385780Y352352D03*
X386540Y367222D03*
X388811Y383335D03*
X386750Y394832D03*
X388735Y388879D03*
X388692Y401745D03*
X385700Y1609400D03*
X389690Y1650552D03*
X381640Y1651162D03*
X375914Y1659005D03*
X378509Y1677584D03*
X394210Y133422D03*
X392554Y263232D03*
X405154Y263472D03*
X392083Y301160D03*
X404215Y301544D03*
X394100Y357592D03*
X403260Y1391142D03*
X394367Y1421475D03*
X396824Y1650332D03*
X409900Y155833D03*
X417754Y263642D03*
X417219Y301637D03*
X417390Y359132D03*
X415630Y374921D03*
X415970Y386252D03*
X415830Y396152D03*
X416498Y402729D03*
X415710Y412972D03*
X414333Y1385292D03*
X417920Y1395170D03*
X411121Y1405157D03*
X422708Y1437560D03*
X413697Y1428315D03*
X416999Y1441908D03*
X407296Y1543686D03*
X407260Y1556810D03*
X407810Y1675512D03*
X423500Y123647D03*
X423580Y129222D03*
X429780Y149373D03*
X423220Y209949D03*
X425780Y220022D03*
X432054Y263264D03*
X429708Y301092D03*
X433956Y381770D03*
X433996Y394722D03*
X437520Y464837D03*
X430320Y1383862D03*
X432243Y1391779D03*
X430291Y1437778D03*
X433897Y1434670D03*
X424921Y1546310D03*
X436383Y1591964D03*
X438749Y1611713D03*
X431500Y1610300D03*
X426510Y1620392D03*
X433021Y1647466D03*
X426968Y1646026D03*
X426728Y1636495D03*
X431035Y1641851D03*
X442650Y101912D03*
X450380Y123012D03*
X442224Y301142D03*
X455000Y340362D03*
X446416Y394306D03*
X454513Y394372D03*
X442802Y424850D03*
X447552Y427100D03*
X452552Y425100D03*
X442520Y464837D03*
X451520D03*
X453423Y505483D03*
X455423Y510983D03*
X453423Y526167D03*
X454885Y539483D03*
X453423Y547519D03*
X445339Y1415731D03*
X443850Y1423404D03*
X445294Y1430415D03*
X445520Y1547437D03*
X447740Y1591180D03*
X445225Y1613427D03*
X446920Y1644280D03*
X465455Y69991D03*
Y64991D03*
Y59991D03*
X464321Y149864D03*
X463821Y154864D03*
X465000Y340362D03*
X467500Y399187D03*
X458052Y427100D03*
X456520Y464837D03*
X461520D03*
X466520D03*
X457423Y529983D03*
Y543899D03*
X461239Y1420649D03*
X471530Y1414650D03*
X459520Y1557437D03*
X457220Y1594495D03*
X459900Y1614582D03*
X460710Y1619602D03*
X465500Y1632442D03*
X466910Y1643242D03*
X467430Y1661242D03*
Y1666242D03*
X464586Y1674991D03*
X486370Y262952D03*
X474310Y293022D03*
X474460Y382405D03*
X485673Y370314D03*
X480174Y370316D03*
X482720Y387370D03*
X479451Y424709D03*
X484201Y426959D03*
X474169Y464696D03*
X479169D03*
X487110Y1399562D03*
X478180Y1454892D03*
X504040Y374320D03*
X500670Y370180D03*
X494720Y370337D03*
X504040Y385560D03*
X490810Y387640D03*
X500220Y391362D03*
X502040Y411905D03*
X492970Y409252D03*
X489201Y424959D03*
X494701Y426959D03*
X493169Y464696D03*
X498169D03*
X488169D03*
X503169D03*
X498423Y511249D03*
X493950Y523893D03*
X498923Y517983D03*
X494423Y514983D03*
X493987Y530097D03*
X499215Y527188D03*
X499123Y538283D03*
X500070Y1424140D03*
X513260Y78242D03*
X518250Y370250D03*
X510720Y370361D03*
X508690Y399850D03*
X517460Y399960D03*
X510220Y416970D03*
X517184Y475952D03*
X522228Y78079D03*
X534565Y139862D03*
X526730Y178803D03*
X536489Y264692D03*
X520830Y376860D03*
X535910Y370450D03*
X527720Y370430D03*
X520890Y387900D03*
X525670Y399850D03*
X533720Y400160D03*
X520760Y417110D03*
X529960Y417620D03*
X530630Y478492D03*
X534990Y481051D03*
X531400Y465696D03*
X535810Y468255D03*
X531380Y470814D03*
X530490Y483610D03*
X535080Y491292D03*
X534890Y486169D03*
X535444Y498578D03*
X546900Y127788D03*
X546461Y135734D03*
X547600Y155028D03*
X544720Y171362D03*
X544820Y161362D03*
X544720Y183921D03*
X549306Y179934D03*
X544390Y236512D03*
X550390Y231742D03*
X542050Y231722D03*
X537720Y278212D03*
X552760Y300922D03*
X552583Y366842D03*
X546830Y403292D03*
X543240Y445136D03*
Y450136D03*
X567520Y87362D03*
X567507Y81049D03*
X562820Y84262D03*
X562783Y78299D03*
X564200Y135562D03*
X567500Y184862D03*
X554306Y179934D03*
X562440Y253826D03*
X562564Y259202D03*
X558240Y300872D03*
X557490Y361932D03*
X553210Y403652D03*
X564170Y403477D03*
X558590Y403597D03*
X572220Y83562D03*
X572231Y77862D03*
X578765Y152912D03*
X578720Y167112D03*
X585031Y215378D03*
X580320Y252173D03*
X575050Y383602D03*
X580629Y370896D03*
X576907Y374655D03*
X570700Y397162D03*
X569600Y403562D03*
X572430Y459232D03*
X576950Y462552D03*
X572400Y466192D03*
X576920Y469832D03*
X572379Y473373D03*
X576970Y475932D03*
X572540Y478492D03*
X577000Y481051D03*
X572520Y483532D03*
X572400Y488682D03*
X572380Y493802D03*
X583150Y509262D03*
X598190Y83462D03*
X592265Y77757D03*
X586068Y134531D03*
X585986Y124754D03*
X600071Y138202D03*
X596720Y164717D03*
X589956Y200878D03*
X596576Y195237D03*
X590900Y195562D03*
X589956Y206962D03*
X601230Y216482D03*
X595900Y216612D03*
X591420Y213922D03*
X592936Y298082D03*
X593265Y311693D03*
X593311Y304016D03*
X599661Y421362D03*
X601820Y439362D03*
X599900Y524862D03*
X617585Y97257D03*
X613020Y94162D03*
X603880Y93902D03*
X605090Y137542D03*
X603410Y132682D03*
X614000Y133862D03*
X617500Y129862D03*
X617660Y168965D03*
X613660Y168966D03*
X603981Y158281D03*
X607940Y173930D03*
Y178930D03*
X602000Y195162D03*
X607200Y194062D03*
X611200Y197262D03*
X612531Y212721D03*
X608995Y216257D03*
X604230Y257532D03*
X616790Y283292D03*
X608920D03*
X602795Y477362D03*
X610700Y485320D03*
X603779Y502082D03*
X629684Y77928D03*
X623290Y78482D03*
X629500Y134362D03*
X626699Y129862D03*
X620612Y133862D03*
X633500Y147862D03*
Y141362D03*
X626929Y163506D03*
X624101Y166335D03*
X629430Y200710D03*
X622064Y250202D03*
X621893Y259030D03*
X629870Y296338D03*
X631861Y290182D03*
X628603Y304016D03*
X624460Y465262D03*
Y470362D03*
X624470Y475462D03*
X626680Y525972D03*
X648258Y79502D03*
X643387Y83184D03*
X645230Y116302D03*
X640000Y154345D03*
X639982Y144844D03*
X637055Y159515D03*
X635820Y180570D03*
X641766Y180757D03*
X635820Y185570D03*
Y190570D03*
X634880Y249202D03*
X634820Y260202D03*
X640720Y423062D03*
X639545Y445195D03*
X639428Y480474D03*
X657165Y79131D03*
X658490Y139140D03*
X654390Y152972D03*
X654156Y169197D03*
X654370Y158572D03*
X654470Y163972D03*
X654310Y186192D03*
X654325Y174437D03*
X653210Y199320D03*
Y206320D03*
Y213320D03*
X655620Y410662D03*
Y415662D03*
Y430662D03*
Y425662D03*
Y420662D03*
X655820Y442662D03*
Y437662D03*
Y447662D03*
X655700Y464664D03*
X655820Y472662D03*
X655557Y477064D03*
X655500Y481862D03*
X662000Y1416500D03*
X663720Y1715362D03*
Y1726362D03*
X673987Y87662D03*
X672520Y121560D03*
X678520Y130640D03*
X682140Y393432D03*
X672820Y396522D03*
X676720Y493562D03*
X668647Y1637403D03*
X673593Y1655557D03*
X686210Y91492D03*
X683500Y381200D03*
X693300Y395362D03*
X687500Y399402D03*
X697930Y391282D03*
X695257Y499926D03*
X699174Y519473D03*
X686647Y1636667D03*
X691593Y1653972D03*
X687120Y1665862D03*
Y1676862D03*
X710450Y152512D03*
X702705Y379398D03*
X707220Y399362D03*
X708400Y392000D03*
X700185Y385010D03*
X711187Y493470D03*
X705220Y493362D03*
X714162Y1574333D03*
X713052Y1579683D03*
X713102Y1601307D03*
X714380Y1589960D03*
X712512Y1596338D03*
X711558Y1675700D03*
X719600Y105062D03*
X718053Y165297D03*
X729460Y399052D03*
X723350Y388952D03*
X722187Y493470D03*
X727187D03*
X717187D03*
X723450Y597072D03*
X731960Y1634110D03*
X731040Y1652930D03*
X738186Y398695D03*
X732187Y493470D03*
X738070Y493833D03*
X737600Y500178D03*
X759350Y116180D03*
X763740Y108400D03*
X753600Y143438D03*
X753500Y151312D03*
X764342Y162084D03*
X755900Y170562D03*
X756160Y267322D03*
X755960Y274322D03*
X750020Y410662D03*
X750120Y415712D03*
X750020Y420712D03*
X750080Y430712D03*
X750010Y425712D03*
X750020Y435792D03*
X750220Y447162D03*
X750290Y452162D03*
Y457162D03*
X750220Y472162D03*
Y467162D03*
Y477162D03*
X749880Y482202D03*
X749612Y1583023D03*
X749662Y1590733D03*
X755859Y1697330D03*
X758273Y1718740D03*
X780180Y133460D03*
X780260Y124600D03*
X779100Y142760D03*
X773900Y170064D03*
X774660Y267722D03*
Y282922D03*
Y275322D03*
X771490Y354942D03*
X765000Y354862D03*
X768720Y459862D03*
X769985Y525724D03*
X774152Y1576893D03*
Y1594893D03*
X793879Y194881D03*
X789942Y204724D03*
X793879Y214567D03*
X796800Y266800D03*
X794057Y301569D03*
X793896Y309026D03*
X789140Y380540D03*
X784278Y403212D03*
X786830Y411600D03*
X784730Y432682D03*
X787520Y510512D03*
Y524802D03*
X810810Y135132D03*
X810640Y128262D03*
X810480Y141762D03*
X805690Y188976D03*
Y220472D03*
X798204Y279146D03*
X811600Y378200D03*
X801800Y388800D03*
X799220Y423862D03*
X807530Y502232D03*
X807640Y519957D03*
X801652Y1578393D03*
X801653Y1598793D03*
X801652Y1604293D03*
X814114Y120773D03*
X822530Y125698D03*
X828614D03*
X817501Y194881D03*
Y214567D03*
X821438Y204724D03*
X814800Y264580D03*
X815060Y280072D03*
X813490Y273862D03*
X819500Y418300D03*
X819220Y425425D03*
X815310Y436050D03*
X827100Y471682D03*
Y479200D03*
X815902Y1578643D03*
X815509Y1600536D03*
X831539Y70643D03*
X834114Y135698D03*
X833614Y129198D03*
X839460Y146042D03*
X833320Y145912D03*
X831295Y171632D03*
X845220Y192862D03*
X839220D03*
X834920Y220303D03*
X843510Y228962D03*
X839080Y233252D03*
X838680Y224752D03*
X840063Y285022D03*
X840850Y278948D03*
X836064Y396620D03*
X835564Y389140D03*
X836290Y415562D03*
X836330Y405972D03*
X836260Y410760D03*
X829800Y429300D03*
X844500Y447100D03*
X844570Y469130D03*
X832620Y506082D03*
X832125Y521156D03*
X843652Y1578393D03*
X843653Y1598793D03*
X843652Y1604293D03*
X856629Y70793D03*
X846190Y145262D03*
X856430Y182260D03*
X849320Y196532D03*
X853340Y199932D03*
X855400Y204772D03*
X853842Y225002D03*
X849600Y228152D03*
X859564Y389140D03*
X859621Y395261D03*
X859876Y414276D03*
Y406812D03*
X854820Y437422D03*
X848900Y433400D03*
X851941Y503082D03*
X857902Y1578643D03*
X857509Y1600536D03*
X864967Y60983D03*
X866190Y163822D03*
X866220Y170862D03*
X866451Y175862D03*
X869900Y209562D03*
X868020Y264232D03*
X872820Y430963D03*
X863925Y737697D03*
X889350Y195489D03*
X893700Y201799D03*
X887142Y879195D03*
X892408Y879200D03*
X885652Y1578393D03*
X885653Y1598793D03*
X885652Y1604293D03*
X899500Y201899D03*
X897640Y915099D03*
X899902Y1578643D03*
X899509Y1600536D03*
X916545Y309459D03*
X911494Y321653D03*
X916545Y333847D03*
X923897Y445545D03*
X912288Y472430D03*
X920273Y972460D03*
X925723Y972420D03*
X921868Y999472D03*
X926464Y1001808D03*
X940933Y309459D03*
X928739Y304408D03*
Y338898D03*
X940933Y333847D03*
X938980Y980382D03*
X931083Y972420D03*
X939942Y991629D03*
X932220Y1001862D03*
X928152Y1579393D03*
Y1589893D03*
Y1594893D03*
X933979Y1661327D03*
X942100Y1671100D03*
X955430Y180139D03*
X945984Y321653D03*
X956920Y490462D03*
X950820Y489762D03*
X974120Y194129D03*
X967239Y320073D03*
X975720Y386862D03*
X975330Y396132D03*
X970788Y501230D03*
X964347Y501262D03*
X977479Y171040D03*
X977070Y211709D03*
X988500Y224653D03*
X991934Y368443D03*
X979559Y399362D03*
X983970Y392562D03*
X997460Y226019D03*
X1000009Y368081D03*
X1003293Y371455D03*
X997394Y415578D03*
X1001721Y421758D03*
X996154Y422700D03*
X1007249Y426399D03*
X1003235Y430097D03*
X1003220Y512862D03*
X1010388Y189009D03*
X1010976Y195562D03*
X1017163Y367963D03*
X1019300Y371830D03*
X1023762Y370425D03*
X1010736Y371866D03*
X1013168Y368145D03*
X1023330Y413692D03*
X1016520Y414362D03*
X1036278Y303993D03*
X1029239Y371893D03*
X1037334Y383729D03*
X1039952Y398756D03*
X1036659Y388000D03*
Y393000D03*
X1028330Y413692D03*
X1038330D03*
X1033330D03*
X1039065Y418999D03*
X1031065D03*
X1026065D03*
X1045847Y194881D03*
X1041910Y204724D03*
X1045847Y214567D03*
X1042334Y383729D03*
X1044952Y398756D03*
X1042687Y404063D03*
X1043330Y413692D03*
X1053410Y503402D03*
X1045720Y591672D03*
X1069469Y194881D03*
X1057658Y188976D03*
X1069469Y214567D03*
X1057658Y220472D03*
X1063330Y382062D03*
X1061470Y585862D03*
X1071957Y1659450D03*
X1075430Y68192D03*
X1079240Y72682D03*
X1087316Y78461D03*
X1073406Y204724D03*
X1077582Y390962D03*
X1078102Y1586860D03*
X1086457Y1644450D03*
X1084457Y1663950D03*
X1096272Y60182D03*
X1105316Y72266D03*
X1105423Y77559D03*
X1101500Y379235D03*
Y374235D03*
Y369235D03*
X1104902Y1586660D03*
X1105557Y1649250D03*
X1105457Y1664450D03*
X1096680Y1667260D03*
X1111970Y1607740D03*
Y1613140D03*
X1130163Y59940D03*
X1124858Y197309D03*
X1133720Y642862D03*
X1131220Y1599140D03*
X1138530Y1612150D03*
X1126940Y1612030D03*
X1138530Y1606750D03*
X1126940Y1606230D03*
X1129620Y1620851D03*
X1147722Y206345D03*
X1144620Y221652D03*
X1145500Y374235D03*
X1150140Y610362D03*
X1142187Y1582738D03*
X1152187D03*
X1144899Y1630878D03*
X1170665Y71388D03*
X1155823Y192102D03*
X1157445Y216982D03*
X1159460Y366025D03*
X1158300Y585862D03*
X1170740Y602132D03*
X1161595Y1574738D03*
Y1582738D03*
X1165100Y1633450D03*
X1163970Y1620600D03*
X1164000Y1625720D03*
X1169825Y1678062D03*
X1158825D03*
X1177310Y65769D03*
X1177234Y59978D03*
X1174545Y106767D03*
X1184510Y188962D03*
X1183460Y205342D03*
X1177570Y602052D03*
X1175217Y595762D03*
X1171595Y1582738D03*
X1174595Y1590738D03*
X1186790Y1613820D03*
X1180825Y1678062D03*
X1203700Y89400D03*
X1203050Y100750D03*
X1200590Y231532D03*
X1188810Y296088D03*
X1198436Y1546492D03*
Y1556192D03*
X1187720Y1558682D03*
X1202200Y1661580D03*
X1191395Y1678372D03*
X1203040Y1671240D03*
X1191235Y1723852D03*
X1202005Y1723897D03*
X1215070Y61580D03*
X1218220Y199862D03*
X1212805Y1724162D03*
X1225700Y108962D03*
X1227074Y119962D03*
X1236300Y168362D03*
X1229720Y197302D03*
X1233282Y201875D03*
X1221330Y216000D03*
X1231720Y217862D03*
Y209862D03*
X1232720Y377862D03*
X1243653Y59957D03*
X1240700Y89700D03*
X1251107Y98785D03*
X1238148Y138705D03*
X1245784Y155522D03*
X1239664Y164272D03*
X1249166Y176737D03*
X1248064Y185012D03*
X1242383Y177862D03*
X1237910Y173375D03*
X1242378Y222323D03*
X1261969Y169722D03*
X1255848Y178605D03*
X1262332Y192601D03*
X1262300Y207572D03*
X1255954Y212694D03*
X1256615Y205266D03*
X1258883Y280558D03*
X1264146Y277191D03*
Y282191D03*
X1266227Y764045D03*
X1284648Y265431D03*
X1283346Y281903D03*
X1270646Y277191D03*
Y282191D03*
X1280675Y277013D03*
X1284794Y272284D03*
X1279987Y287375D03*
X1297710Y68562D03*
X1297785Y63033D03*
X1298270Y76142D03*
X1296253Y100049D03*
X1286750Y101712D03*
X1300964Y91012D03*
X1291257Y105595D03*
X1287793Y95682D03*
X1296929Y116962D03*
X1288693Y283769D03*
X1308440Y86532D03*
X1305422Y100454D03*
X1312792Y113732D03*
X1313405Y108420D03*
X1302060Y113852D03*
X1311241Y125232D03*
X1304714Y265246D03*
X1304930Y278552D03*
X1305090Y284722D03*
X1305164Y272652D03*
X1329891Y87412D03*
X1317901Y95732D03*
X1318146Y110924D03*
X1323546Y113188D03*
X1325641Y118859D03*
X1321810Y125106D03*
X1331593Y125262D03*
X1347082Y120593D03*
X1337731Y121164D03*
X1381940Y104063D03*
X1368124Y114039D03*
X1377470Y1391032D03*
X1378660Y1428340D03*
X1388340Y104132D03*
X1394550Y104022D03*
X1391038Y178871D03*
X1395773Y177016D03*
X1396781Y182349D03*
X1392025Y184062D03*
X1391443Y223513D03*
X1394493Y230962D03*
X1398984Y234392D03*
X1390474Y1385142D03*
X1393957Y1395078D03*
X1387262Y1405157D03*
X1395907Y1430227D03*
X1398569Y1437860D03*
X1411875Y121234D03*
X1411837Y126967D03*
X1411685Y133004D03*
X1401640Y158194D03*
X1407290Y160650D03*
X1410833Y249912D03*
X1412194Y242692D03*
X1411094Y255322D03*
X1406461Y1383862D03*
X1408384Y1391779D03*
X1410477Y1440117D03*
X1410038Y1434670D03*
X1409483Y1593883D03*
X1403250Y1608192D03*
X1410500Y1633862D03*
X1414400Y1627200D03*
X1418034Y244822D03*
X1416694Y252432D03*
X1421480Y1415731D03*
X1419991Y1423404D03*
X1416272Y1433949D03*
X1421435Y1430415D03*
X1425850Y1516362D03*
X1426090Y1532182D03*
X1426240Y1543402D03*
X1415368Y1569131D03*
X1422680Y1593382D03*
X1428700Y1600600D03*
X1415730Y1611422D03*
X1431600Y1630300D03*
Y1625300D03*
X1428500Y1642362D03*
X1435013Y153882D03*
X1435220Y141942D03*
X1435013Y147636D03*
X1435060Y159212D03*
X1447340Y157402D03*
X1447200Y286400D03*
X1436270Y312592D03*
X1437666Y1421828D03*
X1447617Y1416417D03*
X1445530Y1524094D03*
X1445970Y1539914D03*
X1446210Y1551134D03*
X1447408Y1569037D03*
Y1564037D03*
X1442499Y1585323D03*
X1434220Y1595900D03*
X1446380Y1660462D03*
X1450270Y143022D03*
X1450720Y153362D03*
X1448820Y148092D03*
X1450720Y161862D03*
X1449740Y166912D03*
X1450720Y173862D03*
X1449700Y299067D03*
X1453900Y286400D03*
X1455692Y731401D03*
X1462194Y1399885D03*
X1462421Y1609800D03*
X1458890Y1648942D03*
X1452757Y1649112D03*
X1466356Y64062D03*
X1466383Y220108D03*
Y225330D03*
X1476070Y1423740D03*
X1464880Y1649112D03*
X1511200Y131862D03*
X1504360Y244592D03*
X1512244Y311522D03*
X1509420Y316192D03*
X1525940Y108192D03*
X1526930Y203740D03*
X1524853Y235376D03*
X1528860Y239792D03*
X1524840Y244842D03*
X1529150Y251402D03*
X1524810Y254652D03*
X1533630Y57052D03*
X1530910Y64900D03*
X1534367Y75003D03*
X1531429Y77832D03*
X1532500Y130362D03*
X1542230Y292732D03*
X1541568Y594020D03*
X1535007Y608685D03*
X1543895Y629286D03*
X1545610Y116180D03*
X1546813Y132712D03*
X1548938Y593832D03*
X1549590Y629295D03*
X1577365Y1417315D03*
X1576407Y1438525D03*
X1588550Y185702D03*
X1588720Y193962D03*
X1582340Y200611D03*
X1581830Y217482D03*
X1588100Y205442D03*
X1591830Y232482D03*
X1586830D03*
X1581830D03*
Y227482D03*
Y222482D03*
X1580240Y242232D03*
X1581810Y247902D03*
X1586647Y1433669D03*
X1595730Y205662D03*
X1604200Y234642D03*
X1596830Y232482D03*
Y237482D03*
X1613466Y114472D03*
X1634339Y121224D03*
Y116224D03*
Y131224D03*
X1654900Y195935D03*
X1654610Y405002D03*
X1646010Y423702D03*
X1653610D03*
X1672596Y220541D03*
X1664866Y225162D03*
X1661610Y405202D03*
X1661210Y423702D03*
X1674630Y521222D03*
X1672401Y556845D03*
X1668975Y559364D03*
X1669563Y552923D03*
X1678994Y217231D03*
X1680020Y420132D03*
X1685935Y504815D03*
X1681910Y559380D03*
X1675706Y559419D03*
X1676453Y1561557D03*
X1706100Y57052D03*
X1705798Y154052D03*
X1704625Y165909D03*
X1704600Y171656D03*
X1705920Y159812D03*
X1698592Y561310D03*
X1702130Y1385722D03*
X1705960Y1377442D03*
X1694248Y1500862D03*
Y1520362D03*
Y1541362D03*
X1694453Y1560821D03*
X1721240Y57422D03*
X1716230Y57202D03*
X1711140D03*
X1716910Y120432D03*
X1716600Y113622D03*
X1717100Y377962D03*
X1709590Y374282D03*
Y369282D03*
X1709680Y545432D03*
X1717880Y687680D03*
X1726600Y57232D03*
X1728310Y88442D03*
X1731470Y358022D03*
X1738480Y358082D03*
X1735870Y387082D03*
X1728860Y387032D03*
X1731150Y427410D03*
X1734420Y475672D03*
X1731120Y495912D03*
X1735010Y500178D03*
X1741886Y123728D03*
X1751222Y291276D03*
X1745910Y363112D03*
X1745490Y357002D03*
X1746120Y368132D03*
X1745910Y373522D03*
X1742770Y387112D03*
X1742947Y413323D03*
X1743170Y400460D03*
X1766490Y169122D03*
X1759220Y382952D03*
Y377452D03*
X1761720Y438342D03*
X1777598Y308286D03*
X1780667Y303994D03*
X1783608Y464140D03*
X1779740Y459942D03*
X1784010Y453904D03*
X1778430Y466699D03*
X1795346Y372732D03*
X1800030Y390411D03*
X1800980Y433132D03*
X1795060Y433182D03*
X1795161Y472622D03*
X1797720Y477852D03*
X1819450Y145070D03*
X1808110Y161427D03*
X1818274Y362293D03*
Y385293D03*
X1811404Y403225D03*
X1806460Y433002D03*
X1818700Y433182D03*
X1820790Y439462D03*
X1820650Y446226D03*
X1821580Y464140D03*
X1820790Y451344D03*
X1820840Y456463D03*
X1825210Y153961D03*
X1826080Y163660D03*
X1836657Y177243D03*
X1830080Y188482D03*
X1826308Y374586D03*
X1824404Y403225D03*
X1823904Y427432D03*
X1826525Y439697D03*
X1826340Y445972D03*
X1826200Y456482D03*
X1827430Y461581D03*
X1826520Y451292D03*
X1843830Y159800D03*
X1889250Y1843218D03*
X1906004Y1851586D03*
X1913834Y1850536D03*
X1924795Y1842075D03*
X1924635Y1852355D03*
X1937505Y1842525D03*
X1937655Y1853285D03*
X1958420Y1842549D03*
X1964170Y1842429D03*
X1955295Y1853985D03*
X1962935Y1853905D03*
X1978235Y1848699D03*
G54D281*
X1295929Y166699D03*
Y162999D03*
Y159299D03*
Y185199D03*
Y181499D03*
Y177799D03*
Y174099D03*
Y170399D03*
Y196299D03*
Y192599D03*
Y188899D03*
Y199999D03*
Y214799D03*
Y211099D03*
Y207399D03*
Y203699D03*
Y222199D03*
Y218499D03*
X1305544Y168549D03*
X1311955D03*
X1299134D03*
X1302340Y166699D03*
X1308749D03*
X1305544Y164849D03*
X1311955D03*
X1299134D03*
X1302340Y162999D03*
X1308749D03*
X1305544Y161149D03*
X1311955D03*
X1299134D03*
X1302340Y159299D03*
X1308749D03*
X1305544Y157449D03*
X1311955D03*
X1299134D03*
X1302340Y185199D03*
X1308749D03*
X1305544Y183349D03*
X1311955D03*
X1299134D03*
X1302340Y181499D03*
X1308749D03*
X1305544Y179649D03*
X1311955D03*
X1299134D03*
X1302340Y177799D03*
X1308749D03*
X1305544Y175949D03*
X1311955D03*
X1299134D03*
X1302340Y174099D03*
X1308749D03*
X1305544Y172249D03*
X1311955D03*
X1299134D03*
X1302340Y170399D03*
X1308749D03*
X1302340Y196299D03*
X1308749D03*
X1305544Y194449D03*
X1311955D03*
X1299134D03*
X1302340Y192599D03*
X1308749D03*
X1305544Y190749D03*
X1311955D03*
X1299134D03*
X1302340Y188899D03*
X1308749D03*
X1305544Y187049D03*
X1311955D03*
X1299134D03*
X1302340Y199999D03*
X1308749D03*
X1305544Y198149D03*
X1311955D03*
X1299134D03*
X1305544Y216649D03*
X1311955D03*
X1299134D03*
X1302340Y214799D03*
X1308749D03*
X1305544Y212949D03*
X1311955D03*
X1299134D03*
X1302340Y211099D03*
X1308749D03*
X1305544Y209249D03*
X1311955D03*
X1299134D03*
X1302340Y207399D03*
X1308749D03*
X1305544Y205549D03*
X1311955D03*
X1299134D03*
X1302340Y203699D03*
X1308749D03*
X1305544Y201849D03*
X1311955D03*
X1299134D03*
X1305544Y224049D03*
X1311955D03*
X1299134D03*
X1302340Y222199D03*
X1308749D03*
X1305544Y220349D03*
X1311955D03*
X1299134D03*
X1302340Y218499D03*
X1308749D03*
X1318364Y168549D03*
X1324775D03*
X1315160Y166699D03*
X1321570D03*
X1327979D03*
X1318364Y164849D03*
X1324775D03*
X1315160Y162999D03*
X1321570D03*
X1327979D03*
X1318364Y161149D03*
X1324775D03*
X1315160Y159299D03*
X1321570D03*
X1327979D03*
X1318364Y157449D03*
X1324775D03*
X1316927Y184449D03*
X1320077D03*
X1323227D03*
X1326377D03*
X1329527D03*
X1316927Y181299D03*
X1320077D03*
X1323227D03*
X1326377D03*
X1329527D03*
X1316927Y178149D03*
X1320077D03*
X1323227D03*
X1326377D03*
X1329527D03*
X1315160Y174099D03*
X1321570D03*
X1327979D03*
X1318364Y172249D03*
X1324775D03*
X1315160Y170399D03*
X1321570D03*
X1327979D03*
X1316927Y197049D03*
X1320077D03*
X1323227D03*
X1326377D03*
X1329527D03*
X1316927Y193899D03*
X1320077D03*
X1323227D03*
X1326377D03*
X1329527D03*
X1316927Y190749D03*
X1320077D03*
X1323227D03*
X1326377D03*
X1329527D03*
X1316927Y187599D03*
X1320077D03*
X1323227D03*
X1326377D03*
X1329527D03*
X1316927Y200199D03*
X1320077D03*
X1323227D03*
X1326377D03*
X1329527D03*
X1318364Y216649D03*
X1324775D03*
X1315160Y214799D03*
X1321570D03*
X1327979D03*
X1318364Y212949D03*
X1324775D03*
X1315160Y211099D03*
X1321570D03*
X1327979D03*
X1318364Y209249D03*
X1324775D03*
X1315160Y207399D03*
X1321570D03*
X1327979D03*
X1316927Y203349D03*
X1320077D03*
X1323227D03*
X1326377D03*
X1329527D03*
X1318364Y224049D03*
X1324775D03*
X1315160Y222199D03*
X1321570D03*
X1327979D03*
X1318364Y220349D03*
X1324775D03*
X1315160Y218499D03*
X1321570D03*
X1327979D03*
X1331184Y168549D03*
X1337594D03*
X1344005D03*
X1334390Y166699D03*
X1340799D03*
X1347210D03*
X1331184Y164849D03*
X1337594D03*
X1344005D03*
X1334390Y162999D03*
X1340799D03*
X1347210D03*
X1331184Y161149D03*
X1337594D03*
X1344005D03*
X1334390Y159299D03*
X1340799D03*
X1347210D03*
X1331184Y157449D03*
X1337594D03*
X1344005D03*
X1332677Y184449D03*
X1335827D03*
X1340799Y185199D03*
X1347210D03*
X1344005Y183349D03*
X1332677Y181299D03*
X1335827D03*
X1340799Y181499D03*
X1347210D03*
X1344005Y179649D03*
X1332677Y178149D03*
X1335827D03*
X1340799Y177799D03*
X1347210D03*
X1344005Y175949D03*
X1334390Y174099D03*
X1340799D03*
X1347210D03*
X1331184Y172249D03*
X1337594D03*
X1344005D03*
X1334390Y170399D03*
X1340799D03*
X1347210D03*
X1332677Y197049D03*
X1335827D03*
X1340799Y196299D03*
X1347210D03*
X1332677Y193899D03*
X1335827D03*
X1344005Y194449D03*
X1340799Y192599D03*
X1347210D03*
X1332677Y190749D03*
X1335827D03*
X1344005D03*
X1340799Y188899D03*
X1347210D03*
X1332677Y187599D03*
X1335827D03*
X1344005Y187049D03*
X1332677Y200199D03*
X1335827D03*
X1340799Y199999D03*
X1347210D03*
X1344005Y198149D03*
X1331184Y216649D03*
X1337594D03*
X1344005D03*
X1334390Y214799D03*
X1340799D03*
X1347210D03*
X1331184Y212949D03*
X1337594D03*
X1344005D03*
X1334390Y211099D03*
X1340799D03*
X1347210D03*
X1331184Y209249D03*
X1337594D03*
X1344005D03*
X1334390Y207399D03*
X1340799D03*
X1347210D03*
X1344005Y205549D03*
X1332677Y203349D03*
X1335827D03*
X1340799Y203699D03*
X1347210D03*
X1344005Y201849D03*
X1331184Y224049D03*
X1337594D03*
X1344005D03*
X1334390Y222199D03*
X1340799D03*
X1347210D03*
X1331184Y220349D03*
X1337594D03*
X1344005D03*
X1334390Y218499D03*
X1340799D03*
X1347210D03*
X1350414Y168549D03*
X1356825D03*
X1353620Y166699D03*
X1350414Y164849D03*
X1356825D03*
X1353620Y162999D03*
X1350414Y161149D03*
X1356825D03*
X1353620Y159299D03*
X1350414Y157449D03*
X1356825D03*
X1353620Y185199D03*
X1350414Y183349D03*
X1356825D03*
X1353620Y181499D03*
X1350414Y179649D03*
X1356825D03*
X1353620Y177799D03*
X1350414Y175949D03*
X1356825D03*
X1353620Y174099D03*
X1350414Y172249D03*
X1356825D03*
X1353620Y170399D03*
Y196299D03*
X1350414Y194449D03*
X1356825D03*
X1353620Y192599D03*
X1350414Y190749D03*
X1356825D03*
X1353620Y188899D03*
X1350414Y187049D03*
X1356825D03*
X1353620Y199999D03*
X1350414Y198149D03*
X1356825D03*
X1350414Y216649D03*
X1356825D03*
X1353620Y214799D03*
X1350414Y212949D03*
X1356825D03*
X1353620Y211099D03*
X1350414Y209249D03*
X1356825D03*
X1353620Y207399D03*
X1350414Y205549D03*
X1356825D03*
X1353620Y203699D03*
X1350414Y201849D03*
X1356825D03*
X1350414Y224049D03*
X1356825D03*
X1353620Y222199D03*
X1350414Y220349D03*
X1356825D03*
X1353620Y218499D03*
G54D191*
X679353Y413289D03*
X676203D03*
X673054D03*
X669904D03*
X679353Y429037D03*
Y425888D03*
Y422738D03*
Y419588D03*
Y416439D03*
X676203Y429037D03*
Y425888D03*
Y422738D03*
Y419588D03*
Y416439D03*
X673054Y429037D03*
Y425888D03*
Y422738D03*
Y419588D03*
Y416439D03*
X669904Y429037D03*
Y425888D03*
Y422738D03*
Y419588D03*
Y416439D03*
X679353Y444785D03*
Y441636D03*
Y438486D03*
Y435336D03*
Y432187D03*
X676203Y444785D03*
Y441636D03*
Y438486D03*
Y435336D03*
Y432187D03*
X673054Y444785D03*
Y441636D03*
Y438486D03*
Y435336D03*
Y432187D03*
X669904Y444785D03*
Y441636D03*
Y438486D03*
Y435336D03*
Y432187D03*
X679353Y460533D03*
Y457384D03*
Y454234D03*
Y451084D03*
Y447935D03*
X676203Y460533D03*
Y457384D03*
Y454234D03*
Y451084D03*
Y447935D03*
X673054Y460533D03*
Y457384D03*
Y454234D03*
Y451084D03*
Y447935D03*
X669904Y460533D03*
Y457384D03*
Y454234D03*
Y451084D03*
Y447935D03*
X679353Y476281D03*
Y473132D03*
Y469982D03*
Y466832D03*
Y463683D03*
X676203Y476281D03*
Y473132D03*
Y469982D03*
Y466832D03*
Y463683D03*
X673054Y476281D03*
Y473132D03*
Y469982D03*
Y466832D03*
Y463683D03*
X669904Y476281D03*
Y473132D03*
Y469982D03*
Y466832D03*
Y463683D03*
X679353Y479431D03*
X676203D03*
X673054D03*
X669904D03*
X695101Y413289D03*
X691951D03*
X688802D03*
X685652D03*
X682503D03*
X695101Y429037D03*
Y425888D03*
Y422738D03*
Y419588D03*
Y416439D03*
X691951Y429037D03*
Y425888D03*
Y422738D03*
Y419588D03*
Y416439D03*
X688802Y429037D03*
Y425888D03*
Y422738D03*
Y419588D03*
Y416439D03*
X685652Y429037D03*
Y425888D03*
Y422738D03*
Y419588D03*
Y416439D03*
X682503Y429037D03*
Y425888D03*
Y422738D03*
Y419588D03*
Y416439D03*
X695101Y444785D03*
Y441636D03*
Y438486D03*
Y435336D03*
Y432187D03*
X691951Y444785D03*
Y441636D03*
Y438486D03*
Y435336D03*
Y432187D03*
X688802Y444785D03*
Y441636D03*
Y438486D03*
Y435336D03*
Y432187D03*
X685652Y444785D03*
Y441636D03*
Y438486D03*
Y435336D03*
Y432187D03*
X682503Y444785D03*
Y441636D03*
Y438486D03*
Y435336D03*
Y432187D03*
X695101Y460533D03*
Y457384D03*
Y454234D03*
Y451084D03*
Y447935D03*
X691951Y460533D03*
Y457384D03*
Y454234D03*
Y451084D03*
Y447935D03*
X688802Y460533D03*
Y457384D03*
Y454234D03*
Y451084D03*
Y447935D03*
X685652Y460533D03*
Y457384D03*
Y454234D03*
Y451084D03*
Y447935D03*
X682503Y460533D03*
Y457384D03*
Y454234D03*
Y451084D03*
Y447935D03*
X695101Y476281D03*
Y473132D03*
Y469982D03*
Y466832D03*
Y463683D03*
X691951Y476281D03*
Y473132D03*
Y469982D03*
Y466832D03*
Y463683D03*
X688802Y476281D03*
Y473132D03*
Y469982D03*
Y466832D03*
Y463683D03*
X685652Y476281D03*
Y473132D03*
Y469982D03*
Y466832D03*
Y463683D03*
X682503Y476281D03*
Y473132D03*
Y469982D03*
Y466832D03*
Y463683D03*
X695101Y479431D03*
X691951D03*
X688802D03*
X685652D03*
X682503D03*
X710849Y413289D03*
X707699D03*
X704550D03*
X701400D03*
X698251D03*
X710849Y429037D03*
Y425888D03*
Y422738D03*
Y419588D03*
Y416439D03*
X707699Y429037D03*
Y425888D03*
Y422738D03*
Y419588D03*
Y416439D03*
X704550Y429037D03*
Y425888D03*
Y422738D03*
Y419588D03*
Y416439D03*
X701400Y429037D03*
Y425888D03*
Y422738D03*
Y419588D03*
Y416439D03*
X698251Y429037D03*
Y425888D03*
Y422738D03*
Y419588D03*
Y416439D03*
X710849Y444785D03*
Y441636D03*
Y438486D03*
Y435336D03*
Y432187D03*
X707699Y444785D03*
Y441636D03*
Y438486D03*
Y435336D03*
Y432187D03*
X704550Y444785D03*
Y441636D03*
Y438486D03*
Y435336D03*
Y432187D03*
X701400Y444785D03*
Y441636D03*
Y438486D03*
Y435336D03*
Y432187D03*
X698251Y444785D03*
Y441636D03*
Y438486D03*
Y435336D03*
Y432187D03*
X710849Y460533D03*
Y457384D03*
Y454234D03*
Y451084D03*
Y447935D03*
X707699Y460533D03*
Y457384D03*
Y454234D03*
Y451084D03*
Y447935D03*
X704550Y460533D03*
Y457384D03*
Y454234D03*
Y451084D03*
Y447935D03*
X701400Y460533D03*
Y457384D03*
Y454234D03*
Y451084D03*
Y447935D03*
X698251Y460533D03*
Y457384D03*
Y454234D03*
Y451084D03*
Y447935D03*
X710849Y476281D03*
Y473132D03*
Y469982D03*
Y466832D03*
Y463683D03*
X707699Y476281D03*
Y473132D03*
Y469982D03*
Y466832D03*
Y463683D03*
X704550Y476281D03*
Y473132D03*
Y469982D03*
Y466832D03*
Y463683D03*
X701400Y476281D03*
Y473132D03*
Y469982D03*
Y466832D03*
Y463683D03*
X698251Y476281D03*
Y473132D03*
Y469982D03*
Y466832D03*
Y463683D03*
X710849Y479431D03*
X707699D03*
X704550D03*
X701400D03*
X698251D03*
X726597Y413289D03*
X723447D03*
X720298D03*
X717148D03*
X713999D03*
X726597Y429037D03*
Y425888D03*
Y422738D03*
Y419588D03*
Y416439D03*
X723447Y429037D03*
Y425888D03*
Y422738D03*
Y419588D03*
Y416439D03*
X720298Y429037D03*
Y425888D03*
Y422738D03*
Y419588D03*
Y416439D03*
X717148Y429037D03*
Y425888D03*
Y422738D03*
Y419588D03*
Y416439D03*
X713999Y429037D03*
Y425888D03*
Y422738D03*
Y419588D03*
Y416439D03*
X726597Y444785D03*
Y441636D03*
Y438486D03*
Y435336D03*
Y432187D03*
X723447Y444785D03*
Y441636D03*
Y438486D03*
Y435336D03*
Y432187D03*
X720298Y444785D03*
Y441636D03*
Y438486D03*
Y435336D03*
Y432187D03*
X717148Y444785D03*
Y441636D03*
Y438486D03*
Y435336D03*
Y432187D03*
X713999Y444785D03*
Y441636D03*
Y438486D03*
Y435336D03*
Y432187D03*
X726597Y460533D03*
Y457384D03*
Y454234D03*
Y451084D03*
Y447935D03*
X723447Y460533D03*
Y457384D03*
Y454234D03*
Y451084D03*
Y447935D03*
X720298Y460533D03*
Y457384D03*
Y454234D03*
Y451084D03*
Y447935D03*
X717148Y460533D03*
Y457384D03*
Y454234D03*
Y451084D03*
Y447935D03*
X713999Y460533D03*
Y457384D03*
Y454234D03*
Y451084D03*
Y447935D03*
X726597Y476281D03*
Y473132D03*
Y469982D03*
Y466832D03*
Y463683D03*
X723447Y476281D03*
Y473132D03*
Y469982D03*
Y466832D03*
Y463683D03*
X720298Y476281D03*
Y473132D03*
Y469982D03*
Y466832D03*
Y463683D03*
X717148Y476281D03*
Y473132D03*
Y469982D03*
Y466832D03*
Y463683D03*
X713999Y476281D03*
Y473132D03*
Y469982D03*
Y466832D03*
Y463683D03*
X726597Y479431D03*
X723447D03*
X720298D03*
X717148D03*
X713999D03*
X736046Y413289D03*
X732896D03*
X729747D03*
X736046Y429037D03*
Y425888D03*
Y422738D03*
Y419588D03*
Y416439D03*
X732896Y429037D03*
Y425888D03*
Y422738D03*
Y419588D03*
Y416439D03*
X729747Y429037D03*
Y425888D03*
Y422738D03*
Y419588D03*
Y416439D03*
X736046Y444785D03*
Y441636D03*
Y438486D03*
Y435336D03*
Y432187D03*
X732896Y444785D03*
Y441636D03*
Y438486D03*
Y435336D03*
Y432187D03*
X729747Y444785D03*
Y441636D03*
Y438486D03*
Y435336D03*
Y432187D03*
X736046Y460533D03*
Y457384D03*
Y454234D03*
Y451084D03*
Y447935D03*
X732896Y460533D03*
Y457384D03*
Y454234D03*
Y451084D03*
Y447935D03*
X729747Y460533D03*
Y457384D03*
Y454234D03*
Y451084D03*
Y447935D03*
X736046Y476281D03*
Y473132D03*
Y469982D03*
Y466832D03*
Y463683D03*
X732896Y476281D03*
Y473132D03*
Y469982D03*
Y466832D03*
Y463683D03*
X729747Y476281D03*
Y473132D03*
Y469982D03*
Y466832D03*
Y463683D03*
X736046Y479431D03*
X732896D03*
X729747D03*
G54D273*
X1278150Y135612D03*
G54D129*
X274301Y115216D03*
X707457Y119341D03*
X1749422Y116340D03*
G54D81*
X145624Y386885D03*
Y389385D03*
Y391885D03*
Y394385D03*
Y396885D03*
Y399385D03*
Y401885D03*
Y404385D03*
X166530Y396885D03*
Y394385D03*
Y391885D03*
Y389385D03*
Y386885D03*
Y404385D03*
Y401885D03*
Y399385D03*
G54D291*
X1595750Y128005D03*
Y159305D03*
X1613466Y128005D03*
Y159305D03*
G54D174*
X493760Y1406144D03*
X496122Y1416380D03*
X493760D03*
X1469901Y1406144D03*
X1472263Y1416380D03*
X1469901D03*
G54D72*
X102982Y405071D03*
X109982D03*
X141545Y694807D03*
X141339Y702835D03*
X141363Y710840D03*
X141387Y717660D03*
X148545Y694807D03*
X148339Y702835D03*
X155187Y717660D03*
X155163Y710840D03*
X148363D03*
X148387Y717660D03*
X162187D03*
X162163Y710840D03*
X177043Y1409915D03*
X187866Y410549D03*
X180866D03*
X184043Y1409915D03*
X225347Y1420975D03*
X218347D03*
X225086Y1409915D03*
X218086D03*
X225347Y1427783D03*
X218347D03*
X255965Y70636D03*
X255669Y78930D03*
X244518Y667750D03*
X251518D03*
X262965Y70636D03*
X262669Y78930D03*
X286300Y210812D03*
X293300D03*
X411430Y1157520D03*
X418430D03*
X411430Y1165570D03*
X418430D03*
X430930Y1157520D03*
X423930D03*
X436430D03*
Y1165570D03*
X430930D03*
X423930D03*
X443430Y1157520D03*
X448930D03*
X443430Y1165570D03*
X448930D03*
X455930Y1157520D03*
X461430D03*
X468430D03*
X455930Y1165570D03*
X461430D03*
X468430D03*
X501082Y1381027D03*
X494082D03*
X501123Y1389027D03*
X494123D03*
X501123Y1397027D03*
X494123D03*
X507350Y97542D03*
X514350D03*
X685720Y83362D03*
X692720D03*
X697662Y1409940D03*
X690662D03*
X740860Y1401205D03*
X733860D03*
X739210Y1418365D03*
X732210D03*
X739200Y1410025D03*
X732200D03*
X855576Y234068D03*
X862576D03*
X1119440Y1566630D03*
X1111440D03*
X1115440Y1575430D03*
X1150354Y1446244D03*
X1157354D03*
X1195500Y182362D03*
X1188500D03*
X1195000Y198362D03*
X1188000D03*
X1200582Y1436732D03*
X1193582D03*
X1198552Y1453022D03*
X1191552D03*
X1198592Y1446212D03*
X1191592D03*
X1292008Y54121D03*
X1285008D03*
X1292008Y62321D03*
X1285008D03*
X1387720Y1157520D03*
X1394720D03*
X1387720Y1165570D03*
X1394720D03*
X1407220Y1157520D03*
X1400220D03*
X1412720D03*
X1407220Y1165570D03*
X1400220D03*
X1412720D03*
X1425220Y1157520D03*
X1419720D03*
Y1165570D03*
X1425220D03*
X1432220Y1157520D03*
X1437720D03*
X1444720D03*
X1437720Y1165570D03*
X1444720D03*
X1432220D03*
X1478658Y316356D03*
X1477223Y1381027D03*
X1470223D03*
X1477264Y1389027D03*
X1470264D03*
X1477264Y1397027D03*
X1470264D03*
X1485658Y316356D03*
X1602455Y620832D03*
X1609455D03*
X1651828Y1443536D03*
X1658828D03*
X1702057Y1435332D03*
X1695057D03*
X1700597Y1451935D03*
X1693597D03*
X1700317Y1443505D03*
X1693317D03*
X1718649Y1501870D03*
Y1509920D03*
X1729326Y71930D03*
X1736326D03*
X1729100Y80474D03*
X1736100D03*
X1725649Y1501870D03*
Y1509920D03*
X1755295Y716472D03*
X1755271Y708121D03*
X1755319Y724523D03*
X1747245Y1457671D03*
X1740245D03*
X1753145Y1482171D03*
Y1489371D03*
X1762477Y699940D03*
X1755477D03*
X1762295Y716472D03*
X1762271Y708121D03*
X1762319Y724523D03*
X1760145Y1482171D03*
Y1489371D03*
G54D90*
X155807Y1403338D03*
X157579D03*
X159351D03*
X171752D03*
X169981D03*
X168209D03*
X166437D03*
X164666D03*
X161122D03*
X162894D03*
X207183Y572606D03*
Y606606D03*
Y640606D03*
X208124Y1403338D03*
X206352D03*
X204580D03*
X202809D03*
X193950D03*
X195722D03*
X197494D03*
X199265D03*
X201037D03*
X216042Y572606D03*
X214270D03*
X212498D03*
X210727D03*
X208955D03*
X216042Y606606D03*
X214270D03*
X212498D03*
X210727D03*
X208955D03*
X216042Y640606D03*
X214270D03*
X212498D03*
X210727D03*
X208955D03*
X209895Y1403338D03*
X289206Y149291D03*
X287237D03*
X285269D03*
X283300D03*
Y160315D03*
X285269D03*
X287237D03*
X289206D03*
X322192Y1361484D03*
X320420D03*
X318649D03*
X309790D03*
X311562D03*
X313334D03*
X315105D03*
X316877D03*
X325735D03*
X323964D03*
X354320Y1338686D03*
X352548D03*
X350777D03*
X341918D03*
X343690D03*
X345462D03*
X347233D03*
X349005D03*
X357863D03*
X356092D03*
X386448Y1325260D03*
X384676D03*
X382905D03*
X374046D03*
X375818D03*
X377590D03*
X379361D03*
X381133D03*
X389991D03*
X388220D03*
X418576D03*
X416804D03*
X415033D03*
X406174D03*
X407946D03*
X409718D03*
X411489D03*
X413261D03*
X422119D03*
X420348D03*
X450704D03*
X448932D03*
X447161D03*
X438302D03*
X440074D03*
X441846D03*
X443617D03*
X445389D03*
X454247D03*
X452476D03*
X484604D03*
X482832D03*
X481060D03*
X479289D03*
X470430D03*
X472202D03*
X473974D03*
X475745D03*
X477517D03*
X486375D03*
X516732Y1338686D03*
X514960D03*
X513188D03*
X511417D03*
X502558D03*
X504330D03*
X506102D03*
X507873D03*
X509645D03*
X518503D03*
X548860Y1361484D03*
X547088D03*
X545316D03*
X543545D03*
X534686D03*
X536458D03*
X538230D03*
X540001D03*
X541773D03*
X550631D03*
X598203Y200466D03*
Y211490D03*
X604109Y200466D03*
X602140D03*
X600172D03*
Y211490D03*
X602140D03*
X604109D03*
X680056Y1403363D03*
X678285D03*
X669426D03*
X671198D03*
X672970D03*
X674741D03*
X676513D03*
X685371D03*
X683600D03*
X681828D03*
X707569D03*
X709341D03*
X711113D03*
X723514D03*
X721743D03*
X719971D03*
X718199D03*
X716428D03*
X712884D03*
X714656D03*
X826467Y131386D03*
X824498D03*
X822530D03*
X820561D03*
Y142410D03*
X822530D03*
X824498D03*
X826467D03*
X850432Y208879D03*
X848463D03*
X846495D03*
X844526D03*
Y219903D03*
X846495D03*
X848463D03*
X850432D03*
X1129118Y1439667D03*
X1130890D03*
X1132662D03*
X1134433D03*
X1145063D03*
X1143292D03*
X1141520D03*
X1139748D03*
X1137977D03*
X1136205D03*
X1167261D03*
X1183206D03*
X1181435D03*
X1179663D03*
X1177891D03*
X1176120D03*
X1169033D03*
X1170805D03*
X1172576D03*
X1174348D03*
X1171728Y1630732D03*
X1173697D03*
X1175665D03*
X1177634D03*
Y1619708D03*
X1175665D03*
X1173697D03*
X1171728D03*
X1296681Y1361720D03*
X1294910D03*
X1286051D03*
X1287823D03*
X1289595D03*
X1291366D03*
X1293138D03*
X1301996D03*
X1300225D03*
X1298453D03*
X1330461Y1338686D03*
X1328689D03*
X1326918D03*
X1318059D03*
X1319831D03*
X1321603D03*
X1323374D03*
X1325146D03*
X1334004D03*
X1332233D03*
X1362589Y1325260D03*
X1360817D03*
X1359046D03*
X1350187D03*
X1351959D03*
X1353731D03*
X1355502D03*
X1357274D03*
X1366132D03*
X1364361D03*
X1394717D03*
X1392945D03*
X1391174D03*
X1382315D03*
X1384087D03*
X1385859D03*
X1387630D03*
X1389402D03*
X1398260D03*
X1396489D03*
X1426845D03*
X1425073D03*
X1423302D03*
X1414443D03*
X1416215D03*
X1417987D03*
X1419758D03*
X1421530D03*
X1430388D03*
X1428617D03*
X1460745D03*
X1458973D03*
X1457201D03*
X1455430D03*
X1446571D03*
X1448343D03*
X1450115D03*
X1451886D03*
X1453658D03*
X1462516D03*
X1492873Y1338686D03*
X1491101D03*
X1489329D03*
X1487558D03*
X1478699D03*
X1480471D03*
X1482243D03*
X1484014D03*
X1485786D03*
X1494644D03*
X1525001Y1361484D03*
X1523229D03*
X1521457D03*
X1519686D03*
X1510827D03*
X1512599D03*
X1514371D03*
X1516142D03*
X1517914D03*
X1526772D03*
X1637931Y647976D03*
X1639703D03*
X1637931Y681976D03*
X1639703D03*
X1637931Y715976D03*
X1639703D03*
X1639451Y1436959D03*
X1630592D03*
X1632364D03*
X1634136D03*
X1635907D03*
X1637679D03*
X1641475Y647976D03*
X1643246D03*
X1645018D03*
X1646790D03*
X1641475Y681976D03*
X1643246D03*
X1645018D03*
X1646790D03*
X1641475Y715976D03*
X1643246D03*
X1645018D03*
X1646790D03*
X1646537Y1436959D03*
X1644766D03*
X1642994D03*
X1641222D03*
X1668735D03*
X1670507D03*
X1672279D03*
X1684680D03*
X1682909D03*
X1681137D03*
X1679365D03*
X1677594D03*
X1674050D03*
X1675822D03*
X1735976Y364872D03*
X1734008D03*
X1732039D03*
Y375896D03*
X1734008D03*
X1735976D03*
X1737945Y364872D03*
Y375896D03*
G54D147*
X362889Y217622D03*
X371551Y221362D03*
X362889Y225102D03*
X513979Y444062D03*
X522641Y440322D03*
Y447802D03*
X660941Y110412D03*
X652279Y106672D03*
Y114152D03*
X843669Y374622D03*
Y382102D03*
X852331Y378362D03*
X1769520Y433793D03*
X1778182Y430053D03*
Y437533D03*
G54D165*
X442578Y1579509D03*
X440019D03*
X437460D03*
Y1586989D03*
X440019D03*
X442578D03*
X598661Y489622D03*
Y497102D03*
X604779Y426622D03*
X602220D03*
X599661D03*
Y434102D03*
X604779D03*
X603779Y489622D03*
X601220D03*
X603779Y497102D03*
X1213016Y1661115D03*
X1210457D03*
X1207898D03*
Y1668595D03*
X1210457D03*
X1213016D03*
G54D18*
X25981Y387783D03*
Y394475D03*
X31099D03*
Y387783D03*
X593299Y152575D03*
Y145883D03*
X588181D03*
Y152575D03*
G54D219*
X837875Y525849D03*
X834922D03*
Y527817D03*
X837875Y529786D03*
Y527817D03*
G54D237*
X963586Y1595126D03*
Y1612842D03*
X995198Y1595142D03*
Y1612858D03*
X1026798Y1595142D03*
Y1612858D03*
X1058398Y1595142D03*
Y1612858D03*
G54D27*
X44967Y416860D03*
Y413710D03*
Y416860D03*
Y420010D03*
X60189Y410770D03*
Y413920D03*
Y417070D03*
Y413920D03*
X50339Y416945D03*
Y413795D03*
Y416945D03*
Y420095D03*
X65533Y410890D03*
Y414040D03*
Y417190D03*
Y414040D03*
X75585Y1517581D03*
Y1514431D03*
Y1517581D03*
Y1520731D03*
X78456Y1560677D03*
Y1557527D03*
Y1560677D03*
Y1563827D03*
X73389Y1560672D03*
Y1563822D03*
Y1560672D03*
Y1557522D03*
X80652Y1514436D03*
Y1517586D03*
D03*
X93571Y1517237D03*
Y1514087D03*
Y1517237D03*
X88426D03*
Y1514087D03*
Y1517237D03*
X80652Y1520736D03*
X93571Y1520387D03*
X88426D03*
X102250Y1560978D03*
Y1564128D03*
Y1567278D03*
Y1564128D03*
X97183Y1567273D03*
Y1564123D03*
Y1560973D03*
Y1564123D03*
X238297Y123968D03*
Y127118D03*
X499680Y85717D03*
Y88867D03*
X612740Y177372D03*
Y180522D03*
X612736Y177350D03*
Y174200D03*
X631025Y174144D03*
Y170994D03*
Y177294D03*
Y174144D03*
X625596D03*
Y170994D03*
Y177294D03*
Y174144D03*
X618352Y177412D03*
Y180562D03*
Y177412D03*
Y174262D03*
X680600Y369837D03*
Y366687D03*
Y372987D03*
Y369837D03*
X695600D03*
Y366687D03*
Y372987D03*
Y369837D03*
X690600D03*
Y366687D03*
Y372987D03*
Y369837D03*
X685600D03*
Y366687D03*
Y372987D03*
Y369837D03*
X710600D03*
Y366687D03*
Y372987D03*
Y369837D03*
X705600D03*
Y366687D03*
Y372987D03*
Y369837D03*
X700600D03*
Y366687D03*
Y372987D03*
Y369837D03*
X715600D03*
Y366687D03*
Y372987D03*
Y369837D03*
X1016770Y229573D03*
Y226423D03*
X1713418Y125092D03*
Y128242D03*
G54D246*
X991369Y379186D03*
Y381154D03*
Y383123D03*
Y385091D03*
Y387060D03*
Y389028D03*
Y390997D03*
Y392965D03*
Y394934D03*
Y396902D03*
Y398871D03*
Y400839D03*
Y402808D03*
Y404776D03*
X1021881Y379186D03*
Y394934D03*
Y392965D03*
Y390997D03*
Y389028D03*
Y387060D03*
Y385091D03*
Y383123D03*
Y381154D03*
Y404776D03*
Y402808D03*
Y400839D03*
Y398871D03*
Y396902D03*
G54D54*
X94311Y710347D03*
Y706411D03*
Y708379D03*
X87619Y706411D03*
Y710347D03*
X1701051Y710537D03*
Y714473D03*
X1707743D03*
Y710537D03*
Y712505D03*
G54D309*
X1795857Y1510765D03*
G54D282*
X1285767Y165146D03*
Y161207D03*
Y184841D03*
Y180902D03*
Y176963D03*
Y173024D03*
Y169085D03*
Y196657D03*
Y192718D03*
Y188780D03*
Y200596D03*
Y216352D03*
Y212413D03*
Y208474D03*
Y204535D03*
Y220291D03*
X1366987Y165146D03*
Y161207D03*
Y184841D03*
Y180902D03*
Y176963D03*
Y173024D03*
Y169085D03*
Y196657D03*
Y192718D03*
Y188780D03*
Y200596D03*
Y216352D03*
Y212413D03*
Y208474D03*
Y204535D03*
Y220291D03*
G54D264*
X1179922Y1537244D03*
G54D45*
X77416Y1541244D03*
G54D156*
X401767Y1415210D03*
G54D138*
X317642Y1308834D03*
Y1318086D03*
X349650Y1285800D03*
Y1295052D03*
X381731Y1272718D03*
Y1281970D03*
X413909Y1272718D03*
Y1281970D03*
X446256Y1272718D03*
Y1281970D03*
X478433Y1272718D03*
Y1281970D03*
X510620Y1285899D03*
Y1295151D03*
X542985Y1308569D03*
Y1317821D03*
X1293783Y1308834D03*
Y1318086D03*
X1325791Y1285800D03*
Y1295052D03*
X1357872Y1272718D03*
Y1281970D03*
X1390050Y1272718D03*
Y1281970D03*
X1422397Y1272718D03*
Y1281970D03*
X1454574Y1272718D03*
Y1281970D03*
X1486761Y1285899D03*
Y1295151D03*
X1519126Y1308569D03*
Y1317821D03*
G54D63*
X91786Y1533173D03*
X90211D03*
X88636D03*
X87061D03*
X85487D03*
X83912D03*
X82337D03*
X80762D03*
G54D255*
X1030333Y291567D03*
X1288040Y1365989D03*
X1320136Y1343344D03*
X1512904Y1365814D03*
G54D183*
X572690Y1323203D03*
Y1341313D03*
X1263605Y1322514D03*
Y1340624D03*
G54D36*
X59272Y1318588D03*
Y1322328D03*
Y1326068D03*
X69508Y1318588D03*
Y1326068D03*
X1753305Y1323508D03*
Y1316028D03*
X1743069D03*
Y1319768D03*
Y1323508D03*
G54D192*
X694225Y144488D03*
Y225984D03*
G54D228*
X925189Y499086D03*
G54D292*
X1633305Y638527D03*
Y672527D03*
Y706527D03*
G54D64*
X79187Y1533173D03*
G54D274*
X1280249Y133513D03*
G54D166*
X441990Y1627592D03*
G54D73*
X105967Y421490D03*
Y424049D03*
Y426608D03*
Y429167D03*
Y431727D03*
Y434286D03*
Y436845D03*
Y439404D03*
X128015Y429167D03*
Y426608D03*
Y424049D03*
Y421490D03*
Y439404D03*
Y436845D03*
Y434286D03*
Y431727D03*
G54D139*
X322500Y1391830D03*
X537477Y1395413D03*
X1133779Y1653543D03*
X1298642Y1391830D03*
X1513618Y1395413D03*
G54D157*
X417052Y234167D03*
X409178D03*
X417052Y239285D03*
Y236726D03*
X409178D03*
Y239285D03*
X531523Y129243D03*
Y131802D03*
Y134361D03*
Y147243D03*
Y149802D03*
Y152361D03*
X530978Y162167D03*
Y164726D03*
Y167285D03*
X539397Y134361D03*
Y131802D03*
Y129243D03*
Y152361D03*
Y149802D03*
Y147243D03*
X538852Y167285D03*
Y164726D03*
Y162167D03*
X579247Y133101D03*
Y130542D03*
Y127983D03*
X571373D03*
Y130542D03*
Y133101D03*
X577147Y147291D03*
Y144732D03*
Y142173D03*
X569273D03*
Y144732D03*
Y147291D03*
G54D91*
X160197Y1396941D03*
X198340D03*
X314180Y1355087D03*
X346308Y1332289D03*
X378436Y1318863D03*
X410564D03*
X442692D03*
X474820D03*
X506948Y1332289D03*
X539076Y1355087D03*
X673816Y1396966D03*
X711959D03*
X1133508Y1433270D03*
X1171651D03*
X1290441Y1355323D03*
X1322449Y1332289D03*
X1354577Y1318863D03*
X1386705D03*
X1418833D03*
X1450961D03*
X1483089Y1332289D03*
X1515217Y1355087D03*
X1634982Y1430562D03*
X1673125D03*
G54D265*
X1209735Y79660D03*
Y87140D03*
X1208885Y100060D03*
Y103800D03*
Y107540D03*
X1219065Y83400D03*
X1219515Y100060D03*
Y107540D03*
G54D19*
X38346Y1420330D03*
X117932Y605380D03*
X763601Y605413D03*
X1094074Y605380D03*
X1739706Y605455D03*
X1819208Y1420330D03*
G54D37*
X61771Y1631013D03*
X59212D03*
X56653D03*
Y1654045D03*
X59212D03*
X61771D03*
X77126Y1631013D03*
X74567D03*
X72008D03*
X69449D03*
X66889D03*
X64330D03*
Y1654045D03*
X66889D03*
X69449D03*
X72008D03*
X74567D03*
X77126D03*
X79685Y1631013D03*
Y1654045D03*
G54D175*
X489429Y1404569D03*
X500453Y1417955D03*
X1465570Y1404569D03*
X1476594Y1417955D03*
G54D184*
X599552Y288661D03*
Y291220D03*
Y293779D03*
Y296338D03*
Y298897D03*
Y301457D03*
Y304016D03*
Y306575D03*
Y309134D03*
Y311693D03*
X621992Y298897D03*
Y296338D03*
Y293779D03*
Y291220D03*
Y288661D03*
Y311693D03*
Y309134D03*
Y306575D03*
Y304016D03*
Y301457D03*
G54D46*
X93400Y280203D03*
Y282762D03*
Y285321D03*
Y297703D03*
Y300262D03*
Y302821D03*
X100880Y282762D03*
Y280203D03*
Y285321D03*
Y297703D03*
Y302821D03*
Y300262D03*
X412386Y1547487D03*
Y1550046D03*
X419866D03*
Y1547487D03*
X412386Y1552605D03*
X419866D03*
X575124Y257291D03*
Y252173D03*
X567644D03*
Y254732D03*
Y257291D03*
X591355Y164717D03*
X583875D03*
Y167276D03*
X591355Y169835D03*
X583875D03*
X609419Y252407D03*
Y254966D03*
Y257525D03*
X616899D03*
Y254966D03*
Y252407D03*
X832084Y471682D03*
Y474241D03*
Y476800D03*
X839564D03*
Y474241D03*
Y471682D03*
X838530Y500523D03*
Y505641D03*
X846010D03*
Y503082D03*
Y500523D03*
X1092381Y73343D03*
Y78461D03*
X1099861D03*
Y75902D03*
Y73343D03*
X1298814Y52503D03*
Y55062D03*
Y57621D03*
X1306294Y52503D03*
Y57621D03*
X1427940Y1585323D03*
Y1587882D03*
Y1590441D03*
X1435420D03*
Y1585323D03*
X1798179Y405497D03*
Y408056D03*
Y410615D03*
X1798168Y418775D03*
Y421334D03*
Y423893D03*
X1812549Y371171D03*
Y366053D03*
X1805069D03*
Y368612D03*
Y371171D03*
X1813109Y390411D03*
Y385293D03*
X1805629D03*
Y387852D03*
Y390411D03*
X1805659Y410615D03*
Y408056D03*
Y405497D03*
X1805648Y423893D03*
Y421334D03*
Y418775D03*
X1830565Y182361D03*
Y177243D03*
X1823085D03*
Y179802D03*
Y182361D03*
G54D247*
X1004657Y379678D03*
X1002688D03*
X1000719D03*
X998751D03*
X996782D03*
Y404284D03*
X998751D03*
X1000719D03*
X1002688D03*
X1004657D03*
X1016468Y379678D03*
X1014499D03*
X1012531D03*
X1010562D03*
X1008593D03*
X1006625D03*
Y404284D03*
X1008593D03*
X1010562D03*
X1012531D03*
X1014499D03*
X1016468D03*
G54D283*
X1302744Y148170D03*
X1306683D03*
X1310621D03*
X1298805D03*
X1302744Y233328D03*
X1306683D03*
X1310621D03*
X1298805D03*
X1314560Y148170D03*
X1318499D03*
X1322438D03*
X1326377D03*
X1330316D03*
X1314560Y233328D03*
X1318499D03*
X1322438D03*
X1326377D03*
X1330316D03*
X1334255Y148170D03*
X1338194D03*
X1342133D03*
X1346071D03*
X1334255Y233328D03*
X1338194D03*
X1342133D03*
X1346071D03*
X1350010Y148170D03*
X1353949D03*
X1350010Y233328D03*
X1353949D03*
G54D55*
X94705Y712316D03*
X1708137Y716442D03*
G54D148*
X366075Y1378501D03*
Y1411375D03*
X1338716Y1378571D03*
Y1411445D03*
G54D256*
X1055563Y253771D03*
X1080759D03*
G54D82*
X139961Y514305D03*
X484294Y1415339D03*
X1460804Y1415333D03*
X1653854Y644285D03*
X1689755Y541673D03*
G54D193*
X705760Y-26500D03*
Y-16500D03*
D03*
Y-6500D03*
X730760Y-26500D03*
Y-16500D03*
D03*
Y-6500D03*
X822720Y3500D03*
Y13500D03*
D03*
Y23500D03*
X847720Y3500D03*
Y13500D03*
D03*
Y23500D03*
X973180Y-26500D03*
Y-16500D03*
D03*
Y-6500D03*
Y3500D03*
Y13500D03*
Y23500D03*
Y13500D03*
X998180Y-26500D03*
Y-16500D03*
D03*
Y-6500D03*
Y3500D03*
Y13500D03*
Y23500D03*
Y13500D03*
X1015152Y-26511D03*
Y-36511D03*
Y-26511D03*
Y-16511D03*
D03*
Y-6511D03*
D03*
Y3489D03*
D03*
Y13489D03*
D03*
Y23489D03*
X1040152Y-26511D03*
Y-36511D03*
Y-26511D03*
Y-16511D03*
D03*
Y-6511D03*
D03*
Y3489D03*
D03*
Y13489D03*
D03*
Y23489D03*
X1282572Y-36511D03*
Y-26511D03*
D03*
Y-16511D03*
D03*
Y-6511D03*
Y3489D03*
Y-6511D03*
Y3489D03*
Y13489D03*
Y23489D03*
Y13489D03*
X1307572Y-36511D03*
Y-26511D03*
D03*
Y-16511D03*
D03*
Y-6511D03*
Y3489D03*
Y-6511D03*
Y3489D03*
Y13489D03*
Y23489D03*
Y13489D03*
X1324471Y-26511D03*
Y-36511D03*
Y-26511D03*
Y-16511D03*
D03*
Y-6511D03*
D03*
Y3489D03*
D03*
Y13489D03*
D03*
Y23489D03*
X1349471Y-26511D03*
Y-36511D03*
Y-26511D03*
Y-16511D03*
D03*
Y-6511D03*
D03*
Y3489D03*
D03*
Y13489D03*
D03*
Y23489D03*
X1474931Y-36511D03*
Y-26511D03*
D03*
Y-16511D03*
D03*
Y-6511D03*
Y3489D03*
Y-6511D03*
Y3489D03*
Y13489D03*
Y23489D03*
Y13489D03*
X1499931Y-36511D03*
Y-26511D03*
D03*
Y-16511D03*
D03*
Y-6511D03*
Y3489D03*
Y-6511D03*
Y3489D03*
Y13489D03*
Y23489D03*
Y13489D03*
X1565236Y184783D03*
Y264035D03*
G54D229*
X914362Y494165D03*
X916331D03*
X914362Y492196D03*
X916331D03*
X914362Y490228D03*
X916331D03*
X918299D03*
X920268D03*
X922236D03*
X914362Y488259D03*
X916331D03*
X918299D03*
X920268D03*
X922236D03*
X914362Y509913D03*
X916331D03*
X918299D03*
X920268D03*
X922236D03*
X914362Y507944D03*
X916331D03*
X918299D03*
X920268D03*
X922236D03*
X914362Y505976D03*
X916331D03*
X914362Y504007D03*
X916331D03*
X914362Y502039D03*
X916331D03*
X914362Y500070D03*
X916331D03*
X914362Y498102D03*
X916331D03*
X914362Y496133D03*
X916331D03*
X934047Y494165D03*
X936016D03*
X934047Y492196D03*
X936016D03*
X924205Y490228D03*
X926173D03*
X928142D03*
X930110D03*
X932079D03*
X934047D03*
X936016D03*
X924205Y488259D03*
X926173D03*
X928142D03*
X930110D03*
X932079D03*
X934047D03*
X936016D03*
X924205Y509913D03*
X926173D03*
X928142D03*
X930110D03*
X932079D03*
X934047D03*
X936016D03*
X924205Y507944D03*
X926173D03*
X928142D03*
X930110D03*
X932079D03*
X934047D03*
X936016D03*
X934047Y505976D03*
X936016D03*
X934047Y504007D03*
X936016D03*
X934047Y502039D03*
X936016D03*
X934047Y500070D03*
X936016D03*
X934047Y498102D03*
X936016D03*
X934047Y496133D03*
X936016D03*
G54D28*
X40120Y744554D03*
Y1000853D03*
Y1287664D03*
X69820Y744554D03*
Y1000853D03*
Y1287664D03*
X99520Y744554D03*
Y1000853D03*
Y1287664D03*
X129220Y744554D03*
Y1000853D03*
Y1287664D03*
X158920Y744554D03*
Y1000853D03*
Y1287664D03*
X188620Y744554D03*
Y1000853D03*
Y1287664D03*
X218320Y744554D03*
Y1000853D03*
Y1287664D03*
X248020Y744554D03*
Y1000853D03*
Y1287664D03*
X633320Y744554D03*
Y1000853D03*
Y1287664D03*
X663020Y744554D03*
Y1000853D03*
Y1287664D03*
X692720Y744554D03*
Y1000853D03*
Y1287664D03*
X722420Y744554D03*
Y1000853D03*
Y1287664D03*
X752120Y744554D03*
Y1000853D03*
Y1287664D03*
X781820Y744554D03*
Y1000853D03*
Y1287664D03*
X811520Y744554D03*
Y1000853D03*
Y1287664D03*
X841220Y744554D03*
Y1000853D03*
Y1287664D03*
X1016262Y744554D03*
Y1000853D03*
Y1287664D03*
X1045962Y744554D03*
Y1000853D03*
Y1287664D03*
X1075662Y744554D03*
Y1000853D03*
Y1287664D03*
X1105362Y744554D03*
Y1000853D03*
Y1287664D03*
X1135062Y744554D03*
Y1000853D03*
Y1287664D03*
X1164762Y744554D03*
Y1000853D03*
Y1287664D03*
X1194462Y744554D03*
Y1000853D03*
Y1287664D03*
X1224162Y744554D03*
Y1000853D03*
Y1287664D03*
X1609462Y744554D03*
Y1000853D03*
Y1287664D03*
X1639162Y744554D03*
Y1000853D03*
Y1287664D03*
X1668862Y744554D03*
Y1000853D03*
Y1287664D03*
X1698562Y744554D03*
Y1000853D03*
Y1287664D03*
X1728262Y744554D03*
Y1000853D03*
Y1287664D03*
X1757962Y744554D03*
Y1000853D03*
Y1287664D03*
X1787662Y744554D03*
Y1000853D03*
Y1287664D03*
X1817362Y744554D03*
Y1000853D03*
Y1287664D03*
G54D238*
X969075Y150629D03*
Y166377D03*
G54D275*
X1285787Y127643D03*
G54D29*
X48191Y766798D03*
Y770144D03*
X32049Y766798D03*
Y770144D03*
X48191Y773491D03*
Y776837D03*
Y780184D03*
Y783530D03*
Y786877D03*
X32049Y773491D03*
Y776837D03*
Y780184D03*
Y783530D03*
Y786877D03*
X48191Y790223D03*
Y793570D03*
Y796916D03*
Y800263D03*
Y803609D03*
X32049Y790223D03*
Y793570D03*
Y796916D03*
Y800263D03*
Y803609D03*
X48191Y806955D03*
Y810302D03*
Y813648D03*
Y816995D03*
Y820341D03*
X32049Y806955D03*
Y810302D03*
Y813648D03*
Y816995D03*
Y820341D03*
X48191Y823688D03*
Y827034D03*
Y830381D03*
Y833727D03*
X32049Y823688D03*
Y827034D03*
Y830381D03*
Y833727D03*
X48191Y837074D03*
Y840420D03*
Y843766D03*
Y847113D03*
Y850459D03*
X32049Y837074D03*
Y840420D03*
Y843766D03*
Y847113D03*
Y850459D03*
X48191Y853806D03*
Y857152D03*
Y860499D03*
Y863845D03*
Y867192D03*
X32049Y853806D03*
Y857152D03*
Y860499D03*
Y863845D03*
Y867192D03*
X48191Y870538D03*
Y873885D03*
Y877231D03*
Y880577D03*
Y883924D03*
X32049Y870538D03*
Y873885D03*
Y877231D03*
Y880577D03*
Y883924D03*
X48191Y887270D03*
Y890617D03*
Y893963D03*
Y897310D03*
Y900656D03*
X32049Y887270D03*
Y890617D03*
Y893963D03*
Y897310D03*
Y900656D03*
X48191Y904003D03*
Y907349D03*
Y910696D03*
Y914042D03*
Y917389D03*
X32049Y904003D03*
Y907349D03*
Y910696D03*
Y914042D03*
Y917389D03*
X48191Y920735D03*
Y924081D03*
Y927428D03*
Y930774D03*
Y934121D03*
X32049Y920735D03*
Y924081D03*
Y927428D03*
Y930774D03*
Y934121D03*
X48191Y937467D03*
Y940814D03*
Y944160D03*
Y947507D03*
X32049Y937467D03*
Y940814D03*
Y944160D03*
Y947507D03*
X48191Y950853D03*
Y954200D03*
Y957546D03*
Y960892D03*
Y964239D03*
X32049Y950853D03*
Y954200D03*
Y957546D03*
Y960892D03*
Y964239D03*
X48191Y967585D03*
Y970932D03*
Y974278D03*
Y977625D03*
Y980971D03*
X32049Y967585D03*
Y970932D03*
Y974278D03*
Y977625D03*
Y980971D03*
X48191Y984318D03*
Y987664D03*
Y991011D03*
Y994357D03*
X32049Y984318D03*
Y987664D03*
Y991011D03*
Y994357D03*
X48191Y1017782D03*
Y1021129D03*
Y1024475D03*
Y1027822D03*
Y1031168D03*
X32049Y1017782D03*
Y1021129D03*
Y1024475D03*
Y1027822D03*
Y1031168D03*
X48191Y1034515D03*
Y1037861D03*
Y1041207D03*
Y1044554D03*
Y1047900D03*
X32049Y1034515D03*
Y1037861D03*
Y1041207D03*
Y1044554D03*
Y1047900D03*
X48191Y1051247D03*
Y1054593D03*
Y1057940D03*
Y1061286D03*
X32049Y1051247D03*
Y1054593D03*
Y1057940D03*
Y1061286D03*
X48191Y1064633D03*
Y1067979D03*
Y1071326D03*
Y1074672D03*
Y1078018D03*
X32049Y1064633D03*
Y1067979D03*
Y1071326D03*
Y1074672D03*
Y1078018D03*
X48191Y1081365D03*
Y1084711D03*
Y1088058D03*
Y1091404D03*
Y1094751D03*
X32049Y1081365D03*
Y1084711D03*
Y1088058D03*
Y1091404D03*
Y1094751D03*
X48191Y1098097D03*
Y1101444D03*
Y1104790D03*
Y1108137D03*
Y1111483D03*
X32049Y1098097D03*
Y1101444D03*
Y1104790D03*
Y1108137D03*
Y1111483D03*
X48191Y1114829D03*
Y1118176D03*
Y1121522D03*
Y1124869D03*
Y1128215D03*
X32049Y1114829D03*
Y1118176D03*
Y1121522D03*
Y1124869D03*
Y1128215D03*
X48191Y1131562D03*
Y1134908D03*
Y1138255D03*
Y1141601D03*
Y1144948D03*
X32049Y1131562D03*
Y1134908D03*
Y1138255D03*
Y1141601D03*
Y1144948D03*
X48191Y1148294D03*
Y1151641D03*
Y1154987D03*
Y1158333D03*
Y1161680D03*
X32049Y1148294D03*
Y1151641D03*
Y1154987D03*
Y1158333D03*
Y1161680D03*
X48191Y1165026D03*
Y1168373D03*
Y1171719D03*
Y1175066D03*
X32049Y1165026D03*
Y1168373D03*
Y1171719D03*
Y1175066D03*
X48191Y1178412D03*
Y1181759D03*
Y1185105D03*
Y1188452D03*
Y1191798D03*
X32049Y1178412D03*
Y1181759D03*
Y1185105D03*
Y1188452D03*
Y1191798D03*
X48191Y1195144D03*
Y1198491D03*
Y1201837D03*
Y1205184D03*
Y1208530D03*
X32049Y1195144D03*
Y1198491D03*
Y1201837D03*
Y1205184D03*
Y1208530D03*
X48191Y1211877D03*
Y1215223D03*
Y1218570D03*
Y1221916D03*
Y1225263D03*
X32049Y1211877D03*
Y1215223D03*
Y1218570D03*
Y1221916D03*
Y1225263D03*
X48191Y1228609D03*
Y1231955D03*
Y1235302D03*
Y1238648D03*
Y1241995D03*
X32049Y1228609D03*
Y1231955D03*
Y1235302D03*
Y1238648D03*
Y1241995D03*
X48191Y1245341D03*
Y1248688D03*
Y1252034D03*
Y1255381D03*
Y1258727D03*
X32049Y1245341D03*
Y1248688D03*
Y1252034D03*
Y1255381D03*
Y1258727D03*
X48191Y1262074D03*
Y1265420D03*
X32049Y1262074D03*
Y1265420D03*
X61749Y766798D03*
Y770144D03*
Y773491D03*
Y776837D03*
Y780184D03*
Y783530D03*
Y786877D03*
Y790223D03*
Y793570D03*
Y796916D03*
Y800263D03*
Y803609D03*
Y806955D03*
Y810302D03*
Y813648D03*
Y816995D03*
Y820341D03*
Y823688D03*
Y827034D03*
Y830381D03*
Y833727D03*
Y837074D03*
Y840420D03*
Y843766D03*
Y847113D03*
Y850459D03*
Y853806D03*
Y857152D03*
Y860499D03*
Y863845D03*
Y867192D03*
Y870538D03*
Y873885D03*
Y877231D03*
Y880577D03*
Y883924D03*
Y887270D03*
Y890617D03*
Y893963D03*
Y897310D03*
Y900656D03*
Y904003D03*
Y907349D03*
Y910696D03*
Y914042D03*
Y917389D03*
Y920735D03*
Y924081D03*
Y927428D03*
Y930774D03*
Y934121D03*
Y937467D03*
Y940814D03*
Y944160D03*
Y947507D03*
Y950853D03*
Y954200D03*
Y957546D03*
Y960892D03*
Y964239D03*
Y967585D03*
Y970932D03*
Y974278D03*
Y977625D03*
Y980971D03*
Y984318D03*
Y987664D03*
Y991011D03*
Y994357D03*
Y1017782D03*
Y1021129D03*
Y1024475D03*
Y1027822D03*
Y1031168D03*
Y1034515D03*
Y1037861D03*
Y1041207D03*
Y1044554D03*
Y1047900D03*
Y1051247D03*
Y1054593D03*
Y1057940D03*
Y1061286D03*
Y1064633D03*
Y1067979D03*
Y1071326D03*
Y1074672D03*
Y1078018D03*
Y1081365D03*
Y1084711D03*
Y1088058D03*
Y1091404D03*
Y1094751D03*
Y1098097D03*
Y1101444D03*
Y1104790D03*
Y1108137D03*
Y1111483D03*
Y1114829D03*
Y1118176D03*
Y1121522D03*
Y1124869D03*
Y1128215D03*
Y1131562D03*
Y1134908D03*
Y1138255D03*
Y1141601D03*
Y1144948D03*
Y1148294D03*
Y1151641D03*
Y1154987D03*
Y1158333D03*
Y1161680D03*
Y1165026D03*
Y1168373D03*
Y1171719D03*
Y1175066D03*
Y1178412D03*
Y1181759D03*
Y1185105D03*
Y1188452D03*
Y1191798D03*
Y1195144D03*
Y1198491D03*
Y1201837D03*
Y1205184D03*
Y1208530D03*
Y1211877D03*
Y1215223D03*
Y1218570D03*
Y1221916D03*
Y1225263D03*
Y1228609D03*
Y1231955D03*
Y1235302D03*
Y1238648D03*
Y1241995D03*
Y1245341D03*
Y1248688D03*
Y1252034D03*
Y1255381D03*
Y1258727D03*
Y1262074D03*
Y1265420D03*
X77891Y766798D03*
Y770144D03*
Y773491D03*
Y776837D03*
Y780184D03*
Y783530D03*
Y786877D03*
Y790223D03*
Y793570D03*
Y796916D03*
Y800263D03*
Y803609D03*
Y806955D03*
Y810302D03*
Y813648D03*
Y816995D03*
Y820341D03*
Y823688D03*
Y827034D03*
Y830381D03*
Y833727D03*
Y837074D03*
Y840420D03*
Y843766D03*
Y847113D03*
Y850459D03*
Y853806D03*
Y857152D03*
Y860499D03*
Y863845D03*
Y867192D03*
Y870538D03*
Y873885D03*
Y877231D03*
Y880577D03*
Y883924D03*
Y887270D03*
Y890617D03*
Y893963D03*
Y897310D03*
Y900656D03*
Y904003D03*
Y907349D03*
Y910696D03*
Y914042D03*
Y917389D03*
Y920735D03*
Y924081D03*
Y927428D03*
Y930774D03*
Y934121D03*
Y937467D03*
Y940814D03*
Y944160D03*
Y947507D03*
Y950853D03*
Y954200D03*
Y957546D03*
Y960892D03*
Y964239D03*
Y967585D03*
Y970932D03*
Y974278D03*
Y977625D03*
Y980971D03*
Y984318D03*
Y987664D03*
Y991011D03*
Y994357D03*
Y1017782D03*
Y1021129D03*
Y1024475D03*
Y1027822D03*
Y1031168D03*
Y1034515D03*
Y1037861D03*
Y1041207D03*
Y1044554D03*
Y1047900D03*
Y1051247D03*
Y1054593D03*
Y1057940D03*
Y1061286D03*
Y1064633D03*
Y1067979D03*
Y1071326D03*
Y1074672D03*
Y1078018D03*
Y1081365D03*
Y1084711D03*
Y1088058D03*
Y1091404D03*
Y1094751D03*
Y1098097D03*
Y1101444D03*
Y1104790D03*
Y1108137D03*
Y1111483D03*
Y1114829D03*
Y1118176D03*
Y1121522D03*
Y1124869D03*
Y1128215D03*
Y1131562D03*
Y1134908D03*
Y1138255D03*
Y1141601D03*
Y1144948D03*
Y1148294D03*
Y1151641D03*
Y1154987D03*
Y1158333D03*
Y1161680D03*
Y1165026D03*
Y1168373D03*
Y1171719D03*
Y1175066D03*
Y1178412D03*
Y1181759D03*
Y1185105D03*
Y1188452D03*
Y1191798D03*
Y1195144D03*
Y1198491D03*
Y1201837D03*
Y1205184D03*
Y1208530D03*
Y1211877D03*
Y1215223D03*
Y1218570D03*
Y1221916D03*
Y1225263D03*
Y1228609D03*
Y1231955D03*
Y1235302D03*
Y1238648D03*
Y1241995D03*
Y1245341D03*
Y1248688D03*
Y1252034D03*
Y1255381D03*
Y1258727D03*
Y1262074D03*
Y1265420D03*
X91449Y766798D03*
Y770144D03*
Y773491D03*
Y776837D03*
Y780184D03*
Y783530D03*
Y786877D03*
Y790223D03*
Y793570D03*
Y796916D03*
Y800263D03*
Y803609D03*
Y806955D03*
Y810302D03*
Y813648D03*
Y816995D03*
Y820341D03*
Y823688D03*
Y827034D03*
Y830381D03*
Y833727D03*
Y837074D03*
Y840420D03*
Y843766D03*
Y847113D03*
Y850459D03*
Y853806D03*
Y857152D03*
Y860499D03*
Y863845D03*
Y867192D03*
Y870538D03*
Y873885D03*
Y877231D03*
Y880577D03*
Y883924D03*
Y887270D03*
Y890617D03*
Y893963D03*
Y897310D03*
Y900656D03*
Y904003D03*
Y907349D03*
Y910696D03*
Y914042D03*
Y917389D03*
Y920735D03*
Y924081D03*
Y927428D03*
Y930774D03*
Y934121D03*
Y937467D03*
Y940814D03*
Y944160D03*
Y947507D03*
Y950853D03*
Y954200D03*
Y957546D03*
Y960892D03*
Y964239D03*
Y967585D03*
Y970932D03*
Y974278D03*
Y977625D03*
Y980971D03*
Y984318D03*
Y987664D03*
Y991011D03*
Y994357D03*
Y1017782D03*
Y1021129D03*
Y1024475D03*
Y1027822D03*
Y1031168D03*
Y1034515D03*
Y1037861D03*
Y1041207D03*
Y1044554D03*
Y1047900D03*
Y1051247D03*
Y1054593D03*
Y1057940D03*
Y1061286D03*
Y1064633D03*
Y1067979D03*
Y1071326D03*
Y1074672D03*
Y1078018D03*
Y1081365D03*
Y1084711D03*
Y1088058D03*
Y1091404D03*
Y1094751D03*
Y1098097D03*
Y1101444D03*
Y1104790D03*
Y1108137D03*
Y1111483D03*
Y1114829D03*
Y1118176D03*
Y1121522D03*
Y1124869D03*
Y1128215D03*
Y1131562D03*
Y1134908D03*
Y1138255D03*
Y1141601D03*
Y1144948D03*
Y1148294D03*
Y1151641D03*
Y1154987D03*
Y1158333D03*
Y1161680D03*
Y1165026D03*
Y1168373D03*
Y1171719D03*
Y1175066D03*
Y1178412D03*
Y1181759D03*
Y1185105D03*
Y1188452D03*
Y1191798D03*
Y1195144D03*
Y1198491D03*
Y1201837D03*
Y1205184D03*
Y1208530D03*
Y1211877D03*
Y1215223D03*
Y1218570D03*
Y1221916D03*
Y1225263D03*
Y1228609D03*
Y1231955D03*
Y1235302D03*
Y1238648D03*
Y1241995D03*
Y1245341D03*
Y1248688D03*
Y1252034D03*
Y1255381D03*
Y1258727D03*
Y1262074D03*
Y1265420D03*
X107591Y766798D03*
Y770144D03*
Y773491D03*
Y776837D03*
Y780184D03*
Y783530D03*
Y786877D03*
Y790223D03*
Y793570D03*
Y796916D03*
Y800263D03*
Y803609D03*
Y806955D03*
Y810302D03*
Y813648D03*
Y816995D03*
Y820341D03*
Y823688D03*
Y827034D03*
Y830381D03*
Y833727D03*
Y837074D03*
Y840420D03*
Y843766D03*
Y847113D03*
Y850459D03*
Y853806D03*
Y857152D03*
Y860499D03*
Y863845D03*
Y867192D03*
Y870538D03*
Y873885D03*
Y877231D03*
Y880577D03*
Y883924D03*
Y887270D03*
Y890617D03*
Y893963D03*
Y897310D03*
Y900656D03*
Y904003D03*
Y907349D03*
Y910696D03*
Y914042D03*
Y917389D03*
Y920735D03*
Y924081D03*
Y927428D03*
Y930774D03*
Y934121D03*
Y937467D03*
Y940814D03*
Y944160D03*
Y947507D03*
Y950853D03*
Y954200D03*
Y957546D03*
Y960892D03*
Y964239D03*
Y967585D03*
Y970932D03*
Y974278D03*
Y977625D03*
Y980971D03*
Y984318D03*
Y987664D03*
Y991011D03*
Y994357D03*
Y1017782D03*
Y1021129D03*
Y1024475D03*
Y1027822D03*
Y1031168D03*
Y1034515D03*
Y1037861D03*
Y1041207D03*
Y1044554D03*
Y1047900D03*
Y1051247D03*
Y1054593D03*
Y1057940D03*
Y1061286D03*
Y1064633D03*
Y1067979D03*
Y1071326D03*
Y1074672D03*
Y1078018D03*
Y1081365D03*
Y1084711D03*
Y1088058D03*
Y1091404D03*
Y1094751D03*
Y1098097D03*
Y1101444D03*
Y1104790D03*
Y1108137D03*
Y1111483D03*
Y1114829D03*
Y1118176D03*
Y1121522D03*
Y1124869D03*
Y1128215D03*
Y1131562D03*
Y1134908D03*
Y1138255D03*
Y1141601D03*
Y1144948D03*
Y1148294D03*
Y1151641D03*
Y1154987D03*
Y1158333D03*
Y1161680D03*
Y1165026D03*
Y1168373D03*
Y1171719D03*
Y1175066D03*
Y1178412D03*
Y1181759D03*
Y1185105D03*
Y1188452D03*
Y1191798D03*
Y1195144D03*
Y1198491D03*
Y1201837D03*
Y1205184D03*
Y1208530D03*
Y1211877D03*
Y1215223D03*
Y1218570D03*
Y1221916D03*
Y1225263D03*
Y1228609D03*
Y1231955D03*
Y1235302D03*
Y1238648D03*
Y1241995D03*
Y1245341D03*
Y1248688D03*
Y1252034D03*
Y1255381D03*
Y1258727D03*
Y1262074D03*
Y1265420D03*
X121149Y766798D03*
Y770144D03*
Y773491D03*
Y776837D03*
Y780184D03*
Y783530D03*
Y786877D03*
Y790223D03*
Y793570D03*
Y796916D03*
Y800263D03*
Y803609D03*
Y806955D03*
Y810302D03*
Y813648D03*
Y816995D03*
Y820341D03*
Y823688D03*
Y827034D03*
Y830381D03*
Y833727D03*
Y837074D03*
Y840420D03*
Y843766D03*
Y847113D03*
Y850459D03*
Y853806D03*
Y857152D03*
Y860499D03*
Y863845D03*
Y867192D03*
Y870538D03*
Y873885D03*
Y877231D03*
Y880577D03*
Y883924D03*
Y887270D03*
Y890617D03*
Y893963D03*
Y897310D03*
Y900656D03*
Y904003D03*
Y907349D03*
Y910696D03*
Y914042D03*
Y917389D03*
Y920735D03*
Y924081D03*
Y927428D03*
Y930774D03*
Y934121D03*
Y937467D03*
Y940814D03*
Y944160D03*
Y947507D03*
Y950853D03*
Y954200D03*
Y957546D03*
Y960892D03*
Y964239D03*
Y967585D03*
Y970932D03*
Y974278D03*
Y977625D03*
Y980971D03*
Y984318D03*
Y987664D03*
Y991011D03*
Y994357D03*
Y1017782D03*
Y1021129D03*
Y1024475D03*
Y1027822D03*
Y1031168D03*
Y1034515D03*
Y1037861D03*
Y1041207D03*
Y1044554D03*
Y1047900D03*
Y1051247D03*
Y1054593D03*
Y1057940D03*
Y1061286D03*
Y1064633D03*
Y1067979D03*
Y1071326D03*
Y1074672D03*
Y1078018D03*
Y1081365D03*
Y1084711D03*
Y1088058D03*
Y1091404D03*
Y1094751D03*
Y1098097D03*
Y1101444D03*
Y1104790D03*
Y1108137D03*
Y1111483D03*
Y1114829D03*
Y1118176D03*
Y1121522D03*
Y1124869D03*
Y1128215D03*
Y1131562D03*
Y1134908D03*
Y1138255D03*
Y1141601D03*
Y1144948D03*
Y1148294D03*
Y1151641D03*
Y1154987D03*
Y1158333D03*
Y1161680D03*
Y1165026D03*
Y1168373D03*
Y1171719D03*
Y1175066D03*
Y1178412D03*
Y1181759D03*
Y1185105D03*
Y1188452D03*
Y1191798D03*
Y1195144D03*
Y1198491D03*
Y1201837D03*
Y1205184D03*
Y1208530D03*
Y1211877D03*
Y1215223D03*
Y1218570D03*
Y1221916D03*
Y1225263D03*
Y1228609D03*
Y1231955D03*
Y1235302D03*
Y1238648D03*
Y1241995D03*
Y1245341D03*
Y1248688D03*
Y1252034D03*
Y1255381D03*
Y1258727D03*
Y1262074D03*
Y1265420D03*
X137291Y766798D03*
Y770144D03*
Y773491D03*
Y776837D03*
Y780184D03*
Y783530D03*
Y786877D03*
Y790223D03*
Y793570D03*
Y796916D03*
Y800263D03*
Y803609D03*
Y806955D03*
Y810302D03*
Y813648D03*
Y816995D03*
Y820341D03*
Y823688D03*
Y827034D03*
Y830381D03*
Y833727D03*
Y837074D03*
Y840420D03*
Y843766D03*
Y847113D03*
Y850459D03*
Y853806D03*
Y857152D03*
Y860499D03*
Y863845D03*
Y867192D03*
Y870538D03*
Y873885D03*
Y877231D03*
Y880577D03*
Y883924D03*
Y887270D03*
Y890617D03*
Y893963D03*
Y897310D03*
Y900656D03*
Y904003D03*
Y907349D03*
Y910696D03*
Y914042D03*
Y917389D03*
Y920735D03*
Y924081D03*
Y927428D03*
Y930774D03*
Y934121D03*
Y937467D03*
Y940814D03*
Y944160D03*
Y947507D03*
Y950853D03*
Y954200D03*
Y957546D03*
Y960892D03*
Y964239D03*
Y967585D03*
Y970932D03*
Y974278D03*
Y977625D03*
Y980971D03*
Y984318D03*
Y987664D03*
Y991011D03*
Y994357D03*
Y1017782D03*
Y1021129D03*
Y1024475D03*
Y1027822D03*
Y1031168D03*
Y1034515D03*
Y1037861D03*
Y1041207D03*
Y1044554D03*
Y1047900D03*
Y1051247D03*
Y1054593D03*
Y1057940D03*
Y1061286D03*
Y1064633D03*
Y1067979D03*
Y1071326D03*
Y1074672D03*
Y1078018D03*
Y1081365D03*
Y1084711D03*
Y1088058D03*
Y1091404D03*
Y1094751D03*
Y1098097D03*
Y1101444D03*
Y1104790D03*
Y1108137D03*
Y1111483D03*
Y1114829D03*
Y1118176D03*
Y1121522D03*
Y1124869D03*
Y1128215D03*
Y1131562D03*
Y1134908D03*
Y1138255D03*
Y1141601D03*
Y1144948D03*
Y1148294D03*
Y1151641D03*
Y1154987D03*
Y1158333D03*
Y1161680D03*
Y1165026D03*
Y1168373D03*
Y1171719D03*
Y1175066D03*
Y1178412D03*
Y1181759D03*
Y1185105D03*
Y1188452D03*
Y1191798D03*
Y1195144D03*
Y1198491D03*
Y1201837D03*
Y1205184D03*
Y1208530D03*
Y1211877D03*
Y1215223D03*
Y1218570D03*
Y1221916D03*
Y1225263D03*
Y1228609D03*
Y1231955D03*
Y1235302D03*
Y1238648D03*
Y1241995D03*
Y1245341D03*
Y1248688D03*
Y1252034D03*
Y1255381D03*
Y1258727D03*
Y1262074D03*
Y1265420D03*
X150849Y766798D03*
Y770144D03*
Y773491D03*
Y776837D03*
Y780184D03*
Y783530D03*
Y786877D03*
Y790223D03*
Y793570D03*
Y796916D03*
Y800263D03*
Y803609D03*
Y806955D03*
Y810302D03*
Y813648D03*
Y816995D03*
Y820341D03*
Y823688D03*
Y827034D03*
Y830381D03*
Y833727D03*
Y837074D03*
Y840420D03*
Y843766D03*
Y847113D03*
Y850459D03*
Y853806D03*
Y857152D03*
Y860499D03*
Y863845D03*
Y867192D03*
Y870538D03*
Y873885D03*
Y877231D03*
Y880577D03*
Y883924D03*
Y887270D03*
Y890617D03*
Y893963D03*
Y897310D03*
Y900656D03*
Y904003D03*
Y907349D03*
Y910696D03*
Y914042D03*
Y917389D03*
Y920735D03*
Y924081D03*
Y927428D03*
Y930774D03*
Y934121D03*
Y937467D03*
Y940814D03*
Y944160D03*
Y947507D03*
Y950853D03*
Y954200D03*
Y957546D03*
Y960892D03*
Y964239D03*
Y967585D03*
Y970932D03*
Y974278D03*
Y977625D03*
Y980971D03*
Y984318D03*
Y987664D03*
Y991011D03*
Y994357D03*
Y1017782D03*
Y1021129D03*
Y1024475D03*
Y1027822D03*
Y1031168D03*
Y1034515D03*
Y1037861D03*
Y1041207D03*
Y1044554D03*
Y1047900D03*
Y1051247D03*
Y1054593D03*
Y1057940D03*
Y1061286D03*
Y1064633D03*
Y1067979D03*
Y1071326D03*
Y1074672D03*
Y1078018D03*
Y1081365D03*
Y1084711D03*
Y1088058D03*
Y1091404D03*
Y1094751D03*
Y1098097D03*
Y1101444D03*
Y1104790D03*
Y1108137D03*
Y1111483D03*
Y1114829D03*
Y1118176D03*
Y1121522D03*
Y1124869D03*
Y1128215D03*
Y1131562D03*
Y1134908D03*
Y1138255D03*
Y1141601D03*
Y1144948D03*
Y1148294D03*
Y1151641D03*
Y1154987D03*
Y1158333D03*
Y1161680D03*
Y1165026D03*
Y1168373D03*
Y1171719D03*
Y1175066D03*
Y1178412D03*
Y1181759D03*
Y1185105D03*
Y1188452D03*
Y1191798D03*
Y1195144D03*
Y1198491D03*
Y1201837D03*
Y1205184D03*
Y1208530D03*
Y1211877D03*
Y1215223D03*
Y1218570D03*
Y1221916D03*
Y1225263D03*
Y1228609D03*
Y1231955D03*
Y1235302D03*
Y1238648D03*
Y1241995D03*
Y1245341D03*
Y1248688D03*
Y1252034D03*
Y1255381D03*
Y1258727D03*
Y1262074D03*
Y1265420D03*
X166991Y766798D03*
Y770144D03*
Y773491D03*
Y776837D03*
Y780184D03*
Y783530D03*
Y786877D03*
Y790223D03*
Y793570D03*
Y796916D03*
Y800263D03*
Y803609D03*
Y806955D03*
Y810302D03*
Y813648D03*
Y816995D03*
Y820341D03*
Y823688D03*
Y827034D03*
Y830381D03*
Y833727D03*
Y837074D03*
Y840420D03*
Y843766D03*
Y847113D03*
Y850459D03*
Y853806D03*
Y857152D03*
Y860499D03*
Y863845D03*
Y867192D03*
Y870538D03*
Y873885D03*
Y877231D03*
Y880577D03*
Y883924D03*
Y887270D03*
Y890617D03*
Y893963D03*
Y897310D03*
Y900656D03*
Y904003D03*
Y907349D03*
Y910696D03*
Y914042D03*
Y917389D03*
Y920735D03*
Y924081D03*
Y927428D03*
Y930774D03*
Y934121D03*
Y937467D03*
Y940814D03*
Y944160D03*
Y947507D03*
Y950853D03*
Y954200D03*
Y957546D03*
Y960892D03*
Y964239D03*
Y967585D03*
Y970932D03*
Y974278D03*
Y977625D03*
Y980971D03*
Y984318D03*
Y987664D03*
Y991011D03*
Y994357D03*
Y1017782D03*
Y1021129D03*
Y1024475D03*
Y1027822D03*
Y1031168D03*
Y1034515D03*
Y1037861D03*
Y1041207D03*
Y1044554D03*
Y1047900D03*
Y1051247D03*
Y1054593D03*
Y1057940D03*
Y1061286D03*
Y1064633D03*
Y1067979D03*
Y1071326D03*
Y1074672D03*
Y1078018D03*
Y1081365D03*
Y1084711D03*
Y1088058D03*
Y1091404D03*
Y1094751D03*
Y1098097D03*
Y1101444D03*
Y1104790D03*
Y1108137D03*
Y1111483D03*
Y1114829D03*
Y1118176D03*
Y1121522D03*
Y1124869D03*
Y1128215D03*
Y1131562D03*
Y1134908D03*
Y1138255D03*
Y1141601D03*
Y1144948D03*
Y1148294D03*
Y1151641D03*
Y1154987D03*
Y1158333D03*
Y1161680D03*
Y1165026D03*
Y1168373D03*
Y1171719D03*
Y1175066D03*
Y1178412D03*
Y1181759D03*
Y1185105D03*
Y1188452D03*
Y1191798D03*
Y1195144D03*
Y1198491D03*
Y1201837D03*
Y1205184D03*
Y1208530D03*
Y1211877D03*
Y1215223D03*
Y1218570D03*
Y1221916D03*
Y1225263D03*
Y1228609D03*
Y1231955D03*
Y1235302D03*
Y1238648D03*
Y1241995D03*
Y1245341D03*
Y1248688D03*
Y1252034D03*
Y1255381D03*
Y1258727D03*
Y1262074D03*
Y1265420D03*
X180549Y766798D03*
Y770144D03*
Y773491D03*
Y776837D03*
Y780184D03*
Y783530D03*
Y786877D03*
Y790223D03*
Y793570D03*
Y796916D03*
Y800263D03*
Y803609D03*
Y806955D03*
Y810302D03*
Y813648D03*
Y816995D03*
Y820341D03*
Y823688D03*
Y827034D03*
Y830381D03*
Y833727D03*
Y837074D03*
Y840420D03*
Y843766D03*
Y847113D03*
Y850459D03*
Y853806D03*
Y857152D03*
Y860499D03*
Y863845D03*
Y867192D03*
Y870538D03*
Y873885D03*
Y877231D03*
Y880577D03*
Y883924D03*
Y887270D03*
Y890617D03*
Y893963D03*
Y897310D03*
Y900656D03*
Y904003D03*
Y907349D03*
Y910696D03*
Y914042D03*
Y917389D03*
Y920735D03*
Y924081D03*
Y927428D03*
Y930774D03*
Y934121D03*
Y937467D03*
Y940814D03*
Y944160D03*
Y947507D03*
Y950853D03*
Y954200D03*
Y957546D03*
Y960892D03*
Y964239D03*
Y967585D03*
Y970932D03*
Y974278D03*
Y977625D03*
Y980971D03*
Y984318D03*
Y987664D03*
Y991011D03*
Y994357D03*
Y1017782D03*
Y1021129D03*
Y1024475D03*
Y1027822D03*
Y1031168D03*
Y1034515D03*
Y1037861D03*
Y1041207D03*
Y1044554D03*
Y1047900D03*
Y1051247D03*
Y1054593D03*
Y1057940D03*
Y1061286D03*
Y1064633D03*
Y1067979D03*
Y1071326D03*
Y1074672D03*
Y1078018D03*
Y1081365D03*
Y1084711D03*
Y1088058D03*
Y1091404D03*
Y1094751D03*
Y1098097D03*
Y1101444D03*
Y1104790D03*
Y1108137D03*
Y1111483D03*
Y1114829D03*
Y1118176D03*
Y1121522D03*
Y1124869D03*
Y1128215D03*
Y1131562D03*
Y1134908D03*
Y1138255D03*
Y1141601D03*
Y1144948D03*
Y1148294D03*
Y1151641D03*
Y1154987D03*
Y1158333D03*
Y1161680D03*
Y1165026D03*
Y1168373D03*
Y1171719D03*
Y1175066D03*
Y1178412D03*
Y1181759D03*
Y1185105D03*
Y1188452D03*
Y1191798D03*
Y1195144D03*
Y1198491D03*
Y1201837D03*
Y1205184D03*
Y1208530D03*
Y1211877D03*
Y1215223D03*
Y1218570D03*
Y1221916D03*
Y1225263D03*
Y1228609D03*
Y1231955D03*
Y1235302D03*
Y1238648D03*
Y1241995D03*
Y1245341D03*
Y1248688D03*
Y1252034D03*
Y1255381D03*
Y1258727D03*
Y1262074D03*
Y1265420D03*
X210249Y766798D03*
Y770144D03*
X196691Y766798D03*
Y770144D03*
X210249Y773491D03*
Y776837D03*
Y780184D03*
Y783530D03*
Y786877D03*
X196691Y773491D03*
Y776837D03*
Y780184D03*
Y783530D03*
Y786877D03*
X210249Y790223D03*
Y793570D03*
Y796916D03*
Y800263D03*
Y803609D03*
X196691Y790223D03*
Y793570D03*
Y796916D03*
Y800263D03*
Y803609D03*
X210249Y806955D03*
Y810302D03*
Y813648D03*
Y816995D03*
Y820341D03*
X196691Y806955D03*
Y810302D03*
Y813648D03*
Y816995D03*
Y820341D03*
X210249Y823688D03*
Y827034D03*
Y830381D03*
Y833727D03*
X196691Y823688D03*
Y827034D03*
Y830381D03*
Y833727D03*
X210249Y837074D03*
Y840420D03*
Y843766D03*
Y847113D03*
Y850459D03*
X196691Y837074D03*
Y840420D03*
Y843766D03*
Y847113D03*
Y850459D03*
X210249Y853806D03*
Y857152D03*
Y860499D03*
Y863845D03*
Y867192D03*
X196691Y853806D03*
Y857152D03*
Y860499D03*
Y863845D03*
Y867192D03*
X210249Y870538D03*
Y873885D03*
Y877231D03*
Y880577D03*
Y883924D03*
X196691Y870538D03*
Y873885D03*
Y877231D03*
Y880577D03*
Y883924D03*
X210249Y887270D03*
Y890617D03*
Y893963D03*
Y897310D03*
Y900656D03*
X196691Y887270D03*
Y890617D03*
Y893963D03*
Y897310D03*
Y900656D03*
X210249Y904003D03*
Y907349D03*
Y910696D03*
Y914042D03*
Y917389D03*
X196691Y904003D03*
Y907349D03*
Y910696D03*
Y914042D03*
Y917389D03*
X210249Y920735D03*
Y924081D03*
Y927428D03*
Y930774D03*
Y934121D03*
X196691Y920735D03*
Y924081D03*
Y927428D03*
Y930774D03*
Y934121D03*
X210249Y937467D03*
Y940814D03*
Y944160D03*
Y947507D03*
X196691Y937467D03*
Y940814D03*
Y944160D03*
Y947507D03*
X210249Y950853D03*
Y954200D03*
Y957546D03*
Y960892D03*
Y964239D03*
X196691Y950853D03*
Y954200D03*
Y957546D03*
Y960892D03*
Y964239D03*
X210249Y967585D03*
Y970932D03*
Y974278D03*
Y977625D03*
Y980971D03*
X196691Y967585D03*
Y970932D03*
Y974278D03*
Y977625D03*
Y980971D03*
X210249Y984318D03*
Y987664D03*
Y991011D03*
Y994357D03*
X196691Y984318D03*
Y987664D03*
Y991011D03*
Y994357D03*
X210249Y1017782D03*
Y1021129D03*
Y1024475D03*
Y1027822D03*
Y1031168D03*
X196691Y1017782D03*
Y1021129D03*
Y1024475D03*
Y1027822D03*
Y1031168D03*
X210249Y1034515D03*
Y1037861D03*
Y1041207D03*
Y1044554D03*
Y1047900D03*
X196691Y1034515D03*
Y1037861D03*
Y1041207D03*
Y1044554D03*
Y1047900D03*
X210249Y1051247D03*
Y1054593D03*
Y1057940D03*
Y1061286D03*
X196691Y1051247D03*
Y1054593D03*
Y1057940D03*
Y1061286D03*
X210249Y1064633D03*
Y1067979D03*
Y1071326D03*
Y1074672D03*
Y1078018D03*
X196691Y1064633D03*
Y1067979D03*
Y1071326D03*
Y1074672D03*
Y1078018D03*
X210249Y1081365D03*
Y1084711D03*
Y1088058D03*
Y1091404D03*
Y1094751D03*
X196691Y1081365D03*
Y1084711D03*
Y1088058D03*
Y1091404D03*
Y1094751D03*
X210249Y1098097D03*
Y1101444D03*
Y1104790D03*
Y1108137D03*
Y1111483D03*
X196691Y1098097D03*
Y1101444D03*
Y1104790D03*
Y1108137D03*
Y1111483D03*
X210249Y1114829D03*
Y1118176D03*
Y1121522D03*
Y1124869D03*
Y1128215D03*
X196691Y1114829D03*
Y1118176D03*
Y1121522D03*
Y1124869D03*
Y1128215D03*
X210249Y1131562D03*
Y1134908D03*
Y1138255D03*
Y1141601D03*
Y1144948D03*
X196691Y1131562D03*
Y1134908D03*
Y1138255D03*
Y1141601D03*
Y1144948D03*
X210249Y1148294D03*
Y1151641D03*
Y1154987D03*
Y1158333D03*
Y1161680D03*
X196691Y1148294D03*
Y1151641D03*
Y1154987D03*
Y1158333D03*
Y1161680D03*
X210249Y1165026D03*
Y1168373D03*
Y1171719D03*
Y1175066D03*
X196691Y1165026D03*
Y1168373D03*
Y1171719D03*
Y1175066D03*
X210249Y1178412D03*
Y1181759D03*
Y1185105D03*
Y1188452D03*
Y1191798D03*
X196691Y1178412D03*
Y1181759D03*
Y1185105D03*
Y1188452D03*
Y1191798D03*
X210249Y1195144D03*
Y1198491D03*
Y1201837D03*
Y1205184D03*
Y1208530D03*
X196691Y1195144D03*
Y1198491D03*
Y1201837D03*
Y1205184D03*
Y1208530D03*
X210249Y1211877D03*
Y1215223D03*
Y1218570D03*
Y1221916D03*
Y1225263D03*
X196691Y1211877D03*
Y1215223D03*
Y1218570D03*
Y1221916D03*
Y1225263D03*
X210249Y1228609D03*
Y1231955D03*
Y1235302D03*
Y1238648D03*
Y1241995D03*
X196691Y1228609D03*
Y1231955D03*
Y1235302D03*
Y1238648D03*
Y1241995D03*
X210249Y1245341D03*
Y1248688D03*
Y1252034D03*
Y1255381D03*
Y1258727D03*
X196691Y1245341D03*
Y1248688D03*
Y1252034D03*
Y1255381D03*
Y1258727D03*
X210249Y1262074D03*
Y1265420D03*
X196691Y1262074D03*
Y1265420D03*
X226391Y766798D03*
Y770144D03*
Y773491D03*
Y776837D03*
Y780184D03*
Y783530D03*
Y786877D03*
Y790223D03*
Y793570D03*
Y796916D03*
Y800263D03*
Y803609D03*
Y806955D03*
Y810302D03*
Y813648D03*
Y816995D03*
Y820341D03*
Y823688D03*
Y827034D03*
Y830381D03*
Y833727D03*
Y837074D03*
Y840420D03*
Y843766D03*
Y847113D03*
Y850459D03*
Y853806D03*
Y857152D03*
Y860499D03*
Y863845D03*
Y867192D03*
Y870538D03*
Y873885D03*
Y877231D03*
Y880577D03*
Y883924D03*
Y887270D03*
Y890617D03*
Y893963D03*
Y897310D03*
Y900656D03*
Y904003D03*
Y907349D03*
Y910696D03*
Y914042D03*
Y917389D03*
Y920735D03*
Y924081D03*
Y927428D03*
Y930774D03*
Y934121D03*
Y937467D03*
Y940814D03*
Y944160D03*
Y947507D03*
Y950853D03*
Y954200D03*
Y957546D03*
Y960892D03*
Y964239D03*
Y967585D03*
Y970932D03*
Y974278D03*
Y977625D03*
Y980971D03*
Y984318D03*
Y987664D03*
Y991011D03*
Y994357D03*
Y1017782D03*
Y1021129D03*
Y1024475D03*
Y1027822D03*
Y1031168D03*
Y1034515D03*
Y1037861D03*
Y1041207D03*
Y1044554D03*
Y1047900D03*
Y1051247D03*
Y1054593D03*
Y1057940D03*
Y1061286D03*
Y1064633D03*
Y1067979D03*
Y1071326D03*
Y1074672D03*
Y1078018D03*
Y1081365D03*
Y1084711D03*
Y1088058D03*
Y1091404D03*
Y1094751D03*
Y1098097D03*
Y1101444D03*
Y1104790D03*
Y1108137D03*
Y1111483D03*
Y1114829D03*
Y1118176D03*
Y1121522D03*
Y1124869D03*
Y1128215D03*
Y1131562D03*
Y1134908D03*
Y1138255D03*
Y1141601D03*
Y1144948D03*
Y1148294D03*
Y1151641D03*
Y1154987D03*
Y1158333D03*
Y1161680D03*
Y1165026D03*
Y1168373D03*
Y1171719D03*
Y1175066D03*
Y1178412D03*
Y1181759D03*
Y1185105D03*
Y1188452D03*
Y1191798D03*
Y1195144D03*
Y1198491D03*
Y1201837D03*
Y1205184D03*
Y1208530D03*
Y1211877D03*
Y1215223D03*
Y1218570D03*
Y1221916D03*
Y1225263D03*
Y1228609D03*
Y1231955D03*
Y1235302D03*
Y1238648D03*
Y1241995D03*
Y1245341D03*
Y1248688D03*
Y1252034D03*
Y1255381D03*
Y1258727D03*
Y1262074D03*
Y1265420D03*
X239949Y766798D03*
Y770144D03*
Y773491D03*
Y776837D03*
Y780184D03*
Y783530D03*
Y786877D03*
Y790223D03*
Y793570D03*
Y796916D03*
Y800263D03*
Y803609D03*
Y806955D03*
Y810302D03*
Y813648D03*
Y816995D03*
Y820341D03*
Y823688D03*
Y827034D03*
Y830381D03*
Y833727D03*
Y837074D03*
Y840420D03*
Y843766D03*
Y847113D03*
Y850459D03*
Y853806D03*
Y857152D03*
Y860499D03*
Y863845D03*
Y867192D03*
Y870538D03*
Y873885D03*
Y877231D03*
Y880577D03*
Y883924D03*
Y887270D03*
Y890617D03*
Y893963D03*
Y897310D03*
Y900656D03*
Y904003D03*
Y907349D03*
Y910696D03*
Y914042D03*
Y917389D03*
Y920735D03*
Y924081D03*
Y927428D03*
Y930774D03*
Y934121D03*
Y937467D03*
Y940814D03*
Y944160D03*
Y947507D03*
Y950853D03*
Y954200D03*
Y957546D03*
Y960892D03*
Y964239D03*
Y967585D03*
Y970932D03*
Y974278D03*
Y977625D03*
Y980971D03*
Y984318D03*
Y987664D03*
Y991011D03*
Y994357D03*
Y1017782D03*
Y1021129D03*
Y1024475D03*
Y1027822D03*
Y1031168D03*
Y1034515D03*
Y1037861D03*
Y1041207D03*
Y1044554D03*
Y1047900D03*
Y1051247D03*
Y1054593D03*
Y1057940D03*
Y1061286D03*
Y1064633D03*
Y1067979D03*
Y1071326D03*
Y1074672D03*
Y1078018D03*
Y1081365D03*
Y1084711D03*
Y1088058D03*
Y1091404D03*
Y1094751D03*
Y1098097D03*
Y1101444D03*
Y1104790D03*
Y1108137D03*
Y1111483D03*
Y1114829D03*
Y1118176D03*
Y1121522D03*
Y1124869D03*
Y1128215D03*
Y1131562D03*
Y1134908D03*
Y1138255D03*
Y1141601D03*
Y1144948D03*
Y1148294D03*
Y1151641D03*
Y1154987D03*
Y1158333D03*
Y1161680D03*
Y1165026D03*
Y1168373D03*
Y1171719D03*
Y1175066D03*
Y1178412D03*
Y1181759D03*
Y1185105D03*
Y1188452D03*
Y1191798D03*
Y1195144D03*
Y1198491D03*
Y1201837D03*
Y1205184D03*
Y1208530D03*
Y1211877D03*
Y1215223D03*
Y1218570D03*
Y1221916D03*
Y1225263D03*
Y1228609D03*
Y1231955D03*
Y1235302D03*
Y1238648D03*
Y1241995D03*
Y1245341D03*
Y1248688D03*
Y1252034D03*
Y1255381D03*
Y1258727D03*
Y1262074D03*
Y1265420D03*
X256091Y766798D03*
Y770144D03*
Y773491D03*
Y776837D03*
Y780184D03*
Y783530D03*
Y786877D03*
Y790223D03*
Y793570D03*
Y796916D03*
Y800263D03*
Y803609D03*
Y806955D03*
Y810302D03*
Y813648D03*
Y816995D03*
Y820341D03*
Y823688D03*
Y827034D03*
Y830381D03*
Y833727D03*
Y837074D03*
Y840420D03*
Y843766D03*
Y847113D03*
Y850459D03*
Y853806D03*
Y857152D03*
Y860499D03*
Y863845D03*
Y867192D03*
Y870538D03*
Y873885D03*
Y877231D03*
Y880577D03*
Y883924D03*
Y887270D03*
Y890617D03*
Y893963D03*
Y897310D03*
Y900656D03*
Y904003D03*
Y907349D03*
Y910696D03*
Y914042D03*
Y917389D03*
Y920735D03*
Y924081D03*
Y927428D03*
Y930774D03*
Y934121D03*
Y937467D03*
Y940814D03*
Y944160D03*
Y947507D03*
Y950853D03*
Y954200D03*
Y957546D03*
Y960892D03*
Y964239D03*
Y967585D03*
Y970932D03*
Y974278D03*
Y977625D03*
Y980971D03*
Y984318D03*
Y987664D03*
Y991011D03*
Y994357D03*
Y1017782D03*
Y1021129D03*
Y1024475D03*
Y1027822D03*
Y1031168D03*
Y1034515D03*
Y1037861D03*
Y1041207D03*
Y1044554D03*
Y1047900D03*
Y1051247D03*
Y1054593D03*
Y1057940D03*
Y1061286D03*
Y1064633D03*
Y1067979D03*
Y1071326D03*
Y1074672D03*
Y1078018D03*
Y1081365D03*
Y1084711D03*
Y1088058D03*
Y1091404D03*
Y1094751D03*
Y1098097D03*
Y1101444D03*
Y1104790D03*
Y1108137D03*
Y1111483D03*
Y1114829D03*
Y1118176D03*
Y1121522D03*
Y1124869D03*
Y1128215D03*
Y1131562D03*
Y1134908D03*
Y1138255D03*
Y1141601D03*
Y1144948D03*
Y1148294D03*
Y1151641D03*
Y1154987D03*
Y1158333D03*
Y1161680D03*
Y1165026D03*
Y1168373D03*
Y1171719D03*
Y1175066D03*
Y1178412D03*
Y1181759D03*
Y1185105D03*
Y1188452D03*
Y1191798D03*
Y1195144D03*
Y1198491D03*
Y1201837D03*
Y1205184D03*
Y1208530D03*
Y1211877D03*
Y1215223D03*
Y1218570D03*
Y1221916D03*
Y1225263D03*
Y1228609D03*
Y1231955D03*
Y1235302D03*
Y1238648D03*
Y1241995D03*
Y1245341D03*
Y1248688D03*
Y1252034D03*
Y1255381D03*
Y1258727D03*
Y1262074D03*
Y1265420D03*
X625249Y766798D03*
Y770144D03*
Y773491D03*
Y776837D03*
Y780184D03*
Y783530D03*
Y786877D03*
Y790223D03*
Y793570D03*
Y796916D03*
Y800263D03*
Y803609D03*
Y806955D03*
Y810302D03*
Y813648D03*
Y816995D03*
Y820341D03*
Y823688D03*
Y827034D03*
Y830381D03*
Y833727D03*
Y837074D03*
Y840420D03*
Y843766D03*
Y847113D03*
Y850459D03*
Y853806D03*
Y857152D03*
Y860499D03*
Y863845D03*
Y867192D03*
Y870538D03*
Y873885D03*
Y877231D03*
Y880577D03*
Y883924D03*
Y887270D03*
Y890617D03*
Y893963D03*
Y897310D03*
Y900656D03*
Y904003D03*
Y907349D03*
Y910696D03*
Y914042D03*
Y917389D03*
Y920735D03*
Y924081D03*
Y927428D03*
Y930774D03*
Y934121D03*
Y937467D03*
Y940814D03*
Y944160D03*
Y947507D03*
Y950853D03*
Y954200D03*
Y957546D03*
Y960892D03*
Y964239D03*
Y967585D03*
Y970932D03*
Y974278D03*
Y977625D03*
Y980971D03*
Y984318D03*
Y987664D03*
Y991011D03*
Y994357D03*
Y1017782D03*
Y1021129D03*
Y1024475D03*
Y1027822D03*
Y1031168D03*
Y1034515D03*
Y1037861D03*
Y1041207D03*
Y1044554D03*
Y1047900D03*
Y1051247D03*
Y1054593D03*
Y1057940D03*
Y1061286D03*
Y1064633D03*
Y1067979D03*
Y1071326D03*
Y1074672D03*
Y1078018D03*
Y1081365D03*
Y1084711D03*
Y1088058D03*
Y1091404D03*
Y1094751D03*
Y1098097D03*
Y1101444D03*
Y1104790D03*
Y1108137D03*
Y1111483D03*
Y1114829D03*
Y1118176D03*
Y1121522D03*
Y1124869D03*
Y1128215D03*
Y1131562D03*
Y1134908D03*
Y1138255D03*
Y1141601D03*
Y1144948D03*
Y1148294D03*
Y1151641D03*
Y1154987D03*
Y1158333D03*
Y1161680D03*
Y1165026D03*
Y1168373D03*
Y1171719D03*
Y1175066D03*
Y1178412D03*
Y1181759D03*
Y1185105D03*
Y1188452D03*
Y1191798D03*
Y1195144D03*
Y1198491D03*
Y1201837D03*
Y1205184D03*
Y1208530D03*
Y1211877D03*
Y1215223D03*
Y1218570D03*
Y1221916D03*
Y1225263D03*
Y1228609D03*
Y1231955D03*
Y1235302D03*
Y1238648D03*
Y1241995D03*
Y1245341D03*
Y1248688D03*
Y1252034D03*
Y1255381D03*
Y1258727D03*
Y1262074D03*
Y1265420D03*
X641391Y766798D03*
Y770144D03*
Y773491D03*
Y776837D03*
Y780184D03*
Y783530D03*
Y786877D03*
Y790223D03*
Y793570D03*
Y796916D03*
Y800263D03*
Y803609D03*
Y806955D03*
Y810302D03*
Y813648D03*
Y816995D03*
Y820341D03*
Y823688D03*
Y827034D03*
Y830381D03*
Y833727D03*
Y837074D03*
Y840420D03*
Y843766D03*
Y847113D03*
Y850459D03*
Y853806D03*
Y857152D03*
Y860499D03*
Y863845D03*
Y867192D03*
Y870538D03*
Y873885D03*
Y877231D03*
Y880577D03*
Y883924D03*
Y887270D03*
Y890617D03*
Y893963D03*
Y897310D03*
Y900656D03*
Y904003D03*
Y907349D03*
Y910696D03*
Y914042D03*
Y917389D03*
Y920735D03*
Y924081D03*
Y927428D03*
Y930774D03*
Y934121D03*
Y937467D03*
Y940814D03*
Y944160D03*
Y947507D03*
Y950853D03*
Y954200D03*
Y957546D03*
Y960892D03*
Y964239D03*
Y967585D03*
Y970932D03*
Y974278D03*
Y977625D03*
Y980971D03*
Y984318D03*
Y987664D03*
Y991011D03*
Y994357D03*
Y1017782D03*
Y1021129D03*
Y1024475D03*
Y1027822D03*
Y1031168D03*
Y1034515D03*
Y1037861D03*
Y1041207D03*
Y1044554D03*
Y1047900D03*
Y1051247D03*
Y1054593D03*
Y1057940D03*
Y1061286D03*
Y1064633D03*
Y1067979D03*
Y1071326D03*
Y1074672D03*
Y1078018D03*
Y1081365D03*
Y1084711D03*
Y1088058D03*
Y1091404D03*
Y1094751D03*
Y1098097D03*
Y1101444D03*
Y1104790D03*
Y1108137D03*
Y1111483D03*
Y1114829D03*
Y1118176D03*
Y1121522D03*
Y1124869D03*
Y1128215D03*
Y1131562D03*
Y1134908D03*
Y1138255D03*
Y1141601D03*
Y1144948D03*
Y1148294D03*
Y1151641D03*
Y1154987D03*
Y1158333D03*
Y1161680D03*
Y1165026D03*
Y1168373D03*
Y1171719D03*
Y1175066D03*
Y1178412D03*
Y1181759D03*
Y1185105D03*
Y1188452D03*
Y1191798D03*
Y1195144D03*
Y1198491D03*
Y1201837D03*
Y1205184D03*
Y1208530D03*
Y1211877D03*
Y1215223D03*
Y1218570D03*
Y1221916D03*
Y1225263D03*
Y1228609D03*
Y1231955D03*
Y1235302D03*
Y1238648D03*
Y1241995D03*
Y1245341D03*
Y1248688D03*
Y1252034D03*
Y1255381D03*
Y1258727D03*
Y1262074D03*
Y1265420D03*
X654949Y766798D03*
Y770144D03*
Y773491D03*
Y776837D03*
Y780184D03*
Y783530D03*
Y786877D03*
Y790223D03*
Y793570D03*
Y796916D03*
Y800263D03*
Y803609D03*
Y806955D03*
Y810302D03*
Y813648D03*
Y816995D03*
Y820341D03*
Y823688D03*
Y827034D03*
Y830381D03*
Y833727D03*
Y837074D03*
Y840420D03*
Y843766D03*
Y847113D03*
Y850459D03*
Y853806D03*
Y857152D03*
Y860499D03*
Y863845D03*
Y867192D03*
Y870538D03*
Y873885D03*
Y877231D03*
Y880577D03*
Y883924D03*
Y887270D03*
Y890617D03*
Y893963D03*
Y897310D03*
Y900656D03*
Y904003D03*
Y907349D03*
Y910696D03*
Y914042D03*
Y917389D03*
Y920735D03*
Y924081D03*
Y927428D03*
Y930774D03*
Y934121D03*
Y937467D03*
Y940814D03*
Y944160D03*
Y947507D03*
Y950853D03*
Y954200D03*
Y957546D03*
Y960892D03*
Y964239D03*
Y967585D03*
Y970932D03*
Y974278D03*
Y977625D03*
Y980971D03*
Y984318D03*
Y987664D03*
Y991011D03*
Y994357D03*
Y1017782D03*
Y1021129D03*
Y1024475D03*
Y1027822D03*
Y1031168D03*
Y1034515D03*
Y1037861D03*
Y1041207D03*
Y1044554D03*
Y1047900D03*
Y1051247D03*
Y1054593D03*
Y1057940D03*
Y1061286D03*
Y1064633D03*
Y1067979D03*
Y1071326D03*
Y1074672D03*
Y1078018D03*
Y1081365D03*
Y1084711D03*
Y1088058D03*
Y1091404D03*
Y1094751D03*
Y1098097D03*
Y1101444D03*
Y1104790D03*
Y1108137D03*
Y1111483D03*
Y1114829D03*
Y1118176D03*
Y1121522D03*
Y1124869D03*
Y1128215D03*
Y1131562D03*
Y1134908D03*
Y1138255D03*
Y1141601D03*
Y1144948D03*
Y1148294D03*
Y1151641D03*
Y1154987D03*
Y1158333D03*
Y1161680D03*
Y1165026D03*
Y1168373D03*
Y1171719D03*
Y1175066D03*
Y1178412D03*
Y1181759D03*
Y1185105D03*
Y1188452D03*
Y1191798D03*
Y1195144D03*
Y1198491D03*
Y1201837D03*
Y1205184D03*
Y1208530D03*
Y1211877D03*
Y1215223D03*
Y1218570D03*
Y1221916D03*
Y1225263D03*
Y1228609D03*
Y1231955D03*
Y1235302D03*
Y1238648D03*
Y1241995D03*
Y1245341D03*
Y1248688D03*
Y1252034D03*
Y1255381D03*
Y1258727D03*
Y1262074D03*
Y1265420D03*
X671091Y766798D03*
Y770144D03*
Y773491D03*
Y776837D03*
Y780184D03*
Y783530D03*
Y786877D03*
Y790223D03*
Y793570D03*
Y796916D03*
Y800263D03*
Y803609D03*
Y806955D03*
Y810302D03*
Y813648D03*
Y816995D03*
Y820341D03*
Y823688D03*
Y827034D03*
Y830381D03*
Y833727D03*
Y837074D03*
Y840420D03*
Y843766D03*
Y847113D03*
Y850459D03*
Y853806D03*
Y857152D03*
Y860499D03*
Y863845D03*
Y867192D03*
Y870538D03*
Y873885D03*
Y877231D03*
Y880577D03*
Y883924D03*
Y887270D03*
Y890617D03*
Y893963D03*
Y897310D03*
Y900656D03*
Y904003D03*
Y907349D03*
Y910696D03*
Y914042D03*
Y917389D03*
Y920735D03*
Y924081D03*
Y927428D03*
Y930774D03*
Y934121D03*
Y937467D03*
Y940814D03*
Y944160D03*
Y947507D03*
Y950853D03*
Y954200D03*
Y957546D03*
Y960892D03*
Y964239D03*
Y967585D03*
Y970932D03*
Y974278D03*
Y977625D03*
Y980971D03*
Y984318D03*
Y987664D03*
Y991011D03*
Y994357D03*
Y1017782D03*
Y1021129D03*
Y1024475D03*
Y1027822D03*
Y1031168D03*
Y1034515D03*
Y1037861D03*
Y1041207D03*
Y1044554D03*
Y1047900D03*
Y1051247D03*
Y1054593D03*
Y1057940D03*
Y1061286D03*
Y1064633D03*
Y1067979D03*
Y1071326D03*
Y1074672D03*
Y1078018D03*
Y1081365D03*
Y1084711D03*
Y1088058D03*
Y1091404D03*
Y1094751D03*
Y1098097D03*
Y1101444D03*
Y1104790D03*
Y1108137D03*
Y1111483D03*
Y1114829D03*
Y1118176D03*
Y1121522D03*
Y1124869D03*
Y1128215D03*
Y1131562D03*
Y1134908D03*
Y1138255D03*
Y1141601D03*
Y1144948D03*
Y1148294D03*
Y1151641D03*
Y1154987D03*
Y1158333D03*
Y1161680D03*
Y1165026D03*
Y1168373D03*
Y1171719D03*
Y1175066D03*
Y1178412D03*
Y1181759D03*
Y1185105D03*
Y1188452D03*
Y1191798D03*
Y1195144D03*
Y1198491D03*
Y1201837D03*
Y1205184D03*
Y1208530D03*
Y1211877D03*
Y1215223D03*
Y1218570D03*
Y1221916D03*
Y1225263D03*
Y1228609D03*
Y1231955D03*
Y1235302D03*
Y1238648D03*
Y1241995D03*
Y1245341D03*
Y1248688D03*
Y1252034D03*
Y1255381D03*
Y1258727D03*
Y1262074D03*
Y1265420D03*
X684649Y766798D03*
Y770144D03*
Y773491D03*
Y776837D03*
Y780184D03*
Y783530D03*
Y786877D03*
Y790223D03*
Y793570D03*
Y796916D03*
Y800263D03*
Y803609D03*
Y806955D03*
Y810302D03*
Y813648D03*
Y816995D03*
Y820341D03*
Y823688D03*
Y827034D03*
Y830381D03*
Y833727D03*
Y837074D03*
Y840420D03*
Y843766D03*
Y847113D03*
Y850459D03*
Y853806D03*
Y857152D03*
Y860499D03*
Y863845D03*
Y867192D03*
Y870538D03*
Y873885D03*
Y877231D03*
Y880577D03*
Y883924D03*
Y887270D03*
Y890617D03*
Y893963D03*
Y897310D03*
Y900656D03*
Y904003D03*
Y907349D03*
Y910696D03*
Y914042D03*
Y917389D03*
Y920735D03*
Y924081D03*
Y927428D03*
Y930774D03*
Y934121D03*
Y937467D03*
Y940814D03*
Y944160D03*
Y947507D03*
Y950853D03*
Y954200D03*
Y957546D03*
Y960892D03*
Y964239D03*
Y967585D03*
Y970932D03*
Y974278D03*
Y977625D03*
Y980971D03*
Y984318D03*
Y987664D03*
Y991011D03*
Y994357D03*
Y1017782D03*
Y1021129D03*
Y1024475D03*
Y1027822D03*
Y1031168D03*
Y1034515D03*
Y1037861D03*
Y1041207D03*
Y1044554D03*
Y1047900D03*
Y1051247D03*
Y1054593D03*
Y1057940D03*
Y1061286D03*
Y1064633D03*
Y1067979D03*
Y1071326D03*
Y1074672D03*
Y1078018D03*
Y1081365D03*
Y1084711D03*
Y1088058D03*
Y1091404D03*
Y1094751D03*
Y1098097D03*
Y1101444D03*
Y1104790D03*
Y1108137D03*
Y1111483D03*
Y1114829D03*
Y1118176D03*
Y1121522D03*
Y1124869D03*
Y1128215D03*
Y1131562D03*
Y1134908D03*
Y1138255D03*
Y1141601D03*
Y1144948D03*
Y1148294D03*
Y1151641D03*
Y1154987D03*
Y1158333D03*
Y1161680D03*
Y1165026D03*
Y1168373D03*
Y1171719D03*
Y1175066D03*
Y1178412D03*
Y1181759D03*
Y1185105D03*
Y1188452D03*
Y1191798D03*
Y1195144D03*
Y1198491D03*
Y1201837D03*
Y1205184D03*
Y1208530D03*
Y1211877D03*
Y1215223D03*
Y1218570D03*
Y1221916D03*
Y1225263D03*
Y1228609D03*
Y1231955D03*
Y1235302D03*
Y1238648D03*
Y1241995D03*
Y1245341D03*
Y1248688D03*
Y1252034D03*
Y1255381D03*
Y1258727D03*
Y1262074D03*
Y1265420D03*
X714349Y766798D03*
Y770144D03*
X700791Y766798D03*
Y770144D03*
X714349Y773491D03*
Y776837D03*
Y780184D03*
Y783530D03*
Y786877D03*
X700791Y773491D03*
Y776837D03*
Y780184D03*
Y783530D03*
Y786877D03*
X714349Y790223D03*
Y793570D03*
Y796916D03*
Y800263D03*
Y803609D03*
X700791Y790223D03*
Y793570D03*
Y796916D03*
Y800263D03*
Y803609D03*
X714349Y806955D03*
Y810302D03*
Y813648D03*
Y816995D03*
Y820341D03*
X700791Y806955D03*
Y810302D03*
Y813648D03*
Y816995D03*
Y820341D03*
X714349Y823688D03*
Y827034D03*
Y830381D03*
Y833727D03*
X700791Y823688D03*
Y827034D03*
Y830381D03*
Y833727D03*
X714349Y837074D03*
Y840420D03*
Y843766D03*
Y847113D03*
Y850459D03*
X700791Y837074D03*
Y840420D03*
Y843766D03*
Y847113D03*
Y850459D03*
X714349Y853806D03*
Y857152D03*
Y860499D03*
Y863845D03*
Y867192D03*
X700791Y853806D03*
Y857152D03*
Y860499D03*
Y863845D03*
Y867192D03*
X714349Y870538D03*
Y873885D03*
Y877231D03*
Y880577D03*
Y883924D03*
X700791Y870538D03*
Y873885D03*
Y877231D03*
Y880577D03*
Y883924D03*
X714349Y887270D03*
Y890617D03*
Y893963D03*
Y897310D03*
Y900656D03*
X700791Y887270D03*
Y890617D03*
Y893963D03*
Y897310D03*
Y900656D03*
X714349Y904003D03*
Y907349D03*
Y910696D03*
Y914042D03*
Y917389D03*
X700791Y904003D03*
Y907349D03*
Y910696D03*
Y914042D03*
Y917389D03*
X714349Y920735D03*
Y924081D03*
Y927428D03*
Y930774D03*
Y934121D03*
X700791Y920735D03*
Y924081D03*
Y927428D03*
Y930774D03*
Y934121D03*
X714349Y937467D03*
Y940814D03*
Y944160D03*
Y947507D03*
X700791Y937467D03*
Y940814D03*
Y944160D03*
Y947507D03*
X714349Y950853D03*
Y954200D03*
Y957546D03*
Y960892D03*
Y964239D03*
X700791Y950853D03*
Y954200D03*
Y957546D03*
Y960892D03*
Y964239D03*
X714349Y967585D03*
Y970932D03*
Y974278D03*
Y977625D03*
Y980971D03*
X700791Y967585D03*
Y970932D03*
Y974278D03*
Y977625D03*
Y980971D03*
X714349Y984318D03*
Y987664D03*
Y991011D03*
Y994357D03*
X700791Y984318D03*
Y987664D03*
Y991011D03*
Y994357D03*
X714349Y1017782D03*
Y1021129D03*
Y1024475D03*
Y1027822D03*
Y1031168D03*
X700791Y1017782D03*
Y1021129D03*
Y1024475D03*
Y1027822D03*
Y1031168D03*
X714349Y1034515D03*
Y1037861D03*
Y1041207D03*
Y1044554D03*
Y1047900D03*
X700791Y1034515D03*
Y1037861D03*
Y1041207D03*
Y1044554D03*
Y1047900D03*
X714349Y1051247D03*
Y1054593D03*
Y1057940D03*
Y1061286D03*
X700791Y1051247D03*
Y1054593D03*
Y1057940D03*
Y1061286D03*
X714349Y1064633D03*
Y1067979D03*
Y1071326D03*
Y1074672D03*
Y1078018D03*
X700791Y1064633D03*
Y1067979D03*
Y1071326D03*
Y1074672D03*
Y1078018D03*
X714349Y1081365D03*
Y1084711D03*
Y1088058D03*
Y1091404D03*
Y1094751D03*
X700791Y1081365D03*
Y1084711D03*
Y1088058D03*
Y1091404D03*
Y1094751D03*
X714349Y1098097D03*
Y1101444D03*
Y1104790D03*
Y1108137D03*
Y1111483D03*
X700791Y1098097D03*
Y1101444D03*
Y1104790D03*
Y1108137D03*
Y1111483D03*
X714349Y1114829D03*
Y1118176D03*
Y1121522D03*
Y1124869D03*
Y1128215D03*
X700791Y1114829D03*
Y1118176D03*
Y1121522D03*
Y1124869D03*
Y1128215D03*
X714349Y1131562D03*
Y1134908D03*
Y1138255D03*
Y1141601D03*
Y1144948D03*
X700791Y1131562D03*
Y1134908D03*
Y1138255D03*
Y1141601D03*
Y1144948D03*
X714349Y1148294D03*
Y1151641D03*
Y1154987D03*
Y1158333D03*
Y1161680D03*
X700791Y1148294D03*
Y1151641D03*
Y1154987D03*
Y1158333D03*
Y1161680D03*
X714349Y1165026D03*
Y1168373D03*
Y1171719D03*
Y1175066D03*
X700791Y1165026D03*
Y1168373D03*
Y1171719D03*
Y1175066D03*
X714349Y1178412D03*
Y1181759D03*
Y1185105D03*
Y1188452D03*
Y1191798D03*
X700791Y1178412D03*
Y1181759D03*
Y1185105D03*
Y1188452D03*
Y1191798D03*
X714349Y1195144D03*
Y1198491D03*
Y1201837D03*
Y1205184D03*
Y1208530D03*
X700791Y1195144D03*
Y1198491D03*
Y1201837D03*
Y1205184D03*
Y1208530D03*
X714349Y1211877D03*
Y1215223D03*
Y1218570D03*
Y1221916D03*
Y1225263D03*
X700791Y1211877D03*
Y1215223D03*
Y1218570D03*
Y1221916D03*
Y1225263D03*
X714349Y1228609D03*
Y1231955D03*
Y1235302D03*
Y1238648D03*
Y1241995D03*
X700791Y1228609D03*
Y1231955D03*
Y1235302D03*
Y1238648D03*
Y1241995D03*
X714349Y1245341D03*
Y1248688D03*
Y1252034D03*
Y1255381D03*
Y1258727D03*
X700791Y1245341D03*
Y1248688D03*
Y1252034D03*
Y1255381D03*
Y1258727D03*
X714349Y1262074D03*
Y1265420D03*
X700791Y1262074D03*
Y1265420D03*
X730491Y766798D03*
Y770144D03*
Y773491D03*
Y776837D03*
Y780184D03*
Y783530D03*
Y786877D03*
Y790223D03*
Y793570D03*
Y796916D03*
Y800263D03*
Y803609D03*
Y806955D03*
Y810302D03*
Y813648D03*
Y816995D03*
Y820341D03*
Y823688D03*
Y827034D03*
Y830381D03*
Y833727D03*
Y837074D03*
Y840420D03*
Y843766D03*
Y847113D03*
Y850459D03*
Y853806D03*
Y857152D03*
Y860499D03*
Y863845D03*
Y867192D03*
Y870538D03*
Y873885D03*
Y877231D03*
Y880577D03*
Y883924D03*
Y887270D03*
Y890617D03*
Y893963D03*
Y897310D03*
Y900656D03*
Y904003D03*
Y907349D03*
Y910696D03*
Y914042D03*
Y917389D03*
Y920735D03*
Y924081D03*
Y927428D03*
Y930774D03*
Y934121D03*
Y937467D03*
Y940814D03*
Y944160D03*
Y947507D03*
Y950853D03*
Y954200D03*
Y957546D03*
Y960892D03*
Y964239D03*
Y967585D03*
Y970932D03*
Y974278D03*
Y977625D03*
Y980971D03*
Y984318D03*
Y987664D03*
Y991011D03*
Y994357D03*
Y1017782D03*
Y1021129D03*
Y1024475D03*
Y1027822D03*
Y1031168D03*
Y1034515D03*
Y1037861D03*
Y1041207D03*
Y1044554D03*
Y1047900D03*
Y1051247D03*
Y1054593D03*
Y1057940D03*
Y1061286D03*
Y1064633D03*
Y1067979D03*
Y1071326D03*
Y1074672D03*
Y1078018D03*
Y1081365D03*
Y1084711D03*
Y1088058D03*
Y1091404D03*
Y1094751D03*
Y1098097D03*
Y1101444D03*
Y1104790D03*
Y1108137D03*
Y1111483D03*
Y1114829D03*
Y1118176D03*
Y1121522D03*
Y1124869D03*
Y1128215D03*
Y1131562D03*
Y1134908D03*
Y1138255D03*
Y1141601D03*
Y1144948D03*
Y1148294D03*
Y1151641D03*
Y1154987D03*
Y1158333D03*
Y1161680D03*
Y1165026D03*
Y1168373D03*
Y1171719D03*
Y1175066D03*
Y1178412D03*
Y1181759D03*
Y1185105D03*
Y1188452D03*
Y1191798D03*
Y1195144D03*
Y1198491D03*
Y1201837D03*
Y1205184D03*
Y1208530D03*
Y1211877D03*
Y1215223D03*
Y1218570D03*
Y1221916D03*
Y1225263D03*
Y1228609D03*
Y1231955D03*
Y1235302D03*
Y1238648D03*
Y1241995D03*
Y1245341D03*
Y1248688D03*
Y1252034D03*
Y1255381D03*
Y1258727D03*
Y1262074D03*
Y1265420D03*
X744049Y766798D03*
Y770144D03*
Y773491D03*
Y776837D03*
Y780184D03*
Y783530D03*
Y786877D03*
Y790223D03*
Y793570D03*
Y796916D03*
Y800263D03*
Y803609D03*
Y806955D03*
Y810302D03*
Y813648D03*
Y816995D03*
Y820341D03*
Y823688D03*
Y827034D03*
Y830381D03*
Y833727D03*
Y837074D03*
Y840420D03*
Y843766D03*
Y847113D03*
Y850459D03*
Y853806D03*
Y857152D03*
Y860499D03*
Y863845D03*
Y867192D03*
Y870538D03*
Y873885D03*
Y877231D03*
Y880577D03*
Y883924D03*
Y887270D03*
Y890617D03*
Y893963D03*
Y897310D03*
Y900656D03*
Y904003D03*
Y907349D03*
Y910696D03*
Y914042D03*
Y917389D03*
Y920735D03*
Y924081D03*
Y927428D03*
Y930774D03*
Y934121D03*
Y937467D03*
Y940814D03*
Y944160D03*
Y947507D03*
Y950853D03*
Y954200D03*
Y957546D03*
Y960892D03*
Y964239D03*
Y967585D03*
Y970932D03*
Y974278D03*
Y977625D03*
Y980971D03*
Y984318D03*
Y987664D03*
Y991011D03*
Y994357D03*
Y1017782D03*
Y1021129D03*
Y1024475D03*
Y1027822D03*
Y1031168D03*
Y1034515D03*
Y1037861D03*
Y1041207D03*
Y1044554D03*
Y1047900D03*
Y1051247D03*
Y1054593D03*
Y1057940D03*
Y1061286D03*
Y1064633D03*
Y1067979D03*
Y1071326D03*
Y1074672D03*
Y1078018D03*
Y1081365D03*
Y1084711D03*
Y1088058D03*
Y1091404D03*
Y1094751D03*
Y1098097D03*
Y1101444D03*
Y1104790D03*
Y1108137D03*
Y1111483D03*
Y1114829D03*
Y1118176D03*
Y1121522D03*
Y1124869D03*
Y1128215D03*
Y1131562D03*
Y1134908D03*
Y1138255D03*
Y1141601D03*
Y1144948D03*
Y1148294D03*
Y1151641D03*
Y1154987D03*
Y1158333D03*
Y1161680D03*
Y1165026D03*
Y1168373D03*
Y1171719D03*
Y1175066D03*
Y1178412D03*
Y1181759D03*
Y1185105D03*
Y1188452D03*
Y1191798D03*
Y1195144D03*
Y1198491D03*
Y1201837D03*
Y1205184D03*
Y1208530D03*
Y1211877D03*
Y1215223D03*
Y1218570D03*
Y1221916D03*
Y1225263D03*
Y1228609D03*
Y1231955D03*
Y1235302D03*
Y1238648D03*
Y1241995D03*
Y1245341D03*
Y1248688D03*
Y1252034D03*
Y1255381D03*
Y1258727D03*
Y1262074D03*
Y1265420D03*
X760191Y766798D03*
Y770144D03*
Y773491D03*
Y776837D03*
Y780184D03*
Y783530D03*
Y786877D03*
Y790223D03*
Y793570D03*
Y796916D03*
Y800263D03*
Y803609D03*
Y806955D03*
Y810302D03*
Y813648D03*
Y816995D03*
Y820341D03*
Y823688D03*
Y827034D03*
Y830381D03*
Y833727D03*
Y837074D03*
Y840420D03*
Y843766D03*
Y847113D03*
Y850459D03*
Y853806D03*
Y857152D03*
Y860499D03*
Y863845D03*
Y867192D03*
Y870538D03*
Y873885D03*
Y877231D03*
Y880577D03*
Y883924D03*
Y887270D03*
Y890617D03*
Y893963D03*
Y897310D03*
Y900656D03*
Y904003D03*
Y907349D03*
Y910696D03*
Y914042D03*
Y917389D03*
Y920735D03*
Y924081D03*
Y927428D03*
Y930774D03*
Y934121D03*
Y937467D03*
Y940814D03*
Y944160D03*
Y947507D03*
Y950853D03*
Y954200D03*
Y957546D03*
Y960892D03*
Y964239D03*
Y967585D03*
Y970932D03*
Y974278D03*
Y977625D03*
Y980971D03*
Y984318D03*
Y987664D03*
Y991011D03*
Y994357D03*
Y1017782D03*
Y1021129D03*
Y1024475D03*
Y1027822D03*
Y1031168D03*
Y1034515D03*
Y1037861D03*
Y1041207D03*
Y1044554D03*
Y1047900D03*
Y1051247D03*
Y1054593D03*
Y1057940D03*
Y1061286D03*
Y1064633D03*
Y1067979D03*
Y1071326D03*
Y1074672D03*
Y1078018D03*
Y1081365D03*
Y1084711D03*
Y1088058D03*
Y1091404D03*
Y1094751D03*
Y1098097D03*
Y1101444D03*
Y1104790D03*
Y1108137D03*
Y1111483D03*
Y1114829D03*
Y1118176D03*
Y1121522D03*
Y1124869D03*
Y1128215D03*
Y1131562D03*
Y1134908D03*
Y1138255D03*
Y1141601D03*
Y1144948D03*
Y1148294D03*
Y1151641D03*
Y1154987D03*
Y1158333D03*
Y1161680D03*
Y1165026D03*
Y1168373D03*
Y1171719D03*
Y1175066D03*
Y1178412D03*
Y1181759D03*
Y1185105D03*
Y1188452D03*
Y1191798D03*
Y1195144D03*
Y1198491D03*
Y1201837D03*
Y1205184D03*
Y1208530D03*
Y1211877D03*
Y1215223D03*
Y1218570D03*
Y1221916D03*
Y1225263D03*
Y1228609D03*
Y1231955D03*
Y1235302D03*
Y1238648D03*
Y1241995D03*
Y1245341D03*
Y1248688D03*
Y1252034D03*
Y1255381D03*
Y1258727D03*
Y1262074D03*
Y1265420D03*
X773749Y766798D03*
Y770144D03*
Y773491D03*
Y776837D03*
Y780184D03*
Y783530D03*
Y786877D03*
Y790223D03*
Y793570D03*
Y796916D03*
Y800263D03*
Y803609D03*
Y806955D03*
Y810302D03*
Y813648D03*
Y816995D03*
Y820341D03*
Y823688D03*
Y827034D03*
Y830381D03*
Y833727D03*
Y837074D03*
Y840420D03*
Y843766D03*
Y847113D03*
Y850459D03*
Y853806D03*
Y857152D03*
Y860499D03*
Y863845D03*
Y867192D03*
Y870538D03*
Y873885D03*
Y877231D03*
Y880577D03*
Y883924D03*
Y887270D03*
Y890617D03*
Y893963D03*
Y897310D03*
Y900656D03*
Y904003D03*
Y907349D03*
Y910696D03*
Y914042D03*
Y917389D03*
Y920735D03*
Y924081D03*
Y927428D03*
Y930774D03*
Y934121D03*
Y937467D03*
Y940814D03*
Y944160D03*
Y947507D03*
Y950853D03*
Y954200D03*
Y957546D03*
Y960892D03*
Y964239D03*
Y967585D03*
Y970932D03*
Y974278D03*
Y977625D03*
Y980971D03*
Y984318D03*
Y987664D03*
Y991011D03*
Y994357D03*
Y1017782D03*
Y1021129D03*
Y1024475D03*
Y1027822D03*
Y1031168D03*
Y1034515D03*
Y1037861D03*
Y1041207D03*
Y1044554D03*
Y1047900D03*
Y1051247D03*
Y1054593D03*
Y1057940D03*
Y1061286D03*
Y1064633D03*
Y1067979D03*
Y1071326D03*
Y1074672D03*
Y1078018D03*
Y1081365D03*
Y1084711D03*
Y1088058D03*
Y1091404D03*
Y1094751D03*
Y1098097D03*
Y1101444D03*
Y1104790D03*
Y1108137D03*
Y1111483D03*
Y1114829D03*
Y1118176D03*
Y1121522D03*
Y1124869D03*
Y1128215D03*
Y1131562D03*
Y1134908D03*
Y1138255D03*
Y1141601D03*
Y1144948D03*
Y1148294D03*
Y1151641D03*
Y1154987D03*
Y1158333D03*
Y1161680D03*
Y1165026D03*
Y1168373D03*
Y1171719D03*
Y1175066D03*
Y1178412D03*
Y1181759D03*
Y1185105D03*
Y1188452D03*
Y1191798D03*
Y1195144D03*
Y1198491D03*
Y1201837D03*
Y1205184D03*
Y1208530D03*
Y1211877D03*
Y1215223D03*
Y1218570D03*
Y1221916D03*
Y1225263D03*
Y1228609D03*
Y1231955D03*
Y1235302D03*
Y1238648D03*
Y1241995D03*
Y1245341D03*
Y1248688D03*
Y1252034D03*
Y1255381D03*
Y1258727D03*
Y1262074D03*
Y1265420D03*
X789891Y766798D03*
Y770144D03*
Y773491D03*
Y776837D03*
Y780184D03*
Y783530D03*
Y786877D03*
Y790223D03*
Y793570D03*
Y796916D03*
Y800263D03*
Y803609D03*
Y806955D03*
Y810302D03*
Y813648D03*
Y816995D03*
Y820341D03*
Y823688D03*
Y827034D03*
Y830381D03*
Y833727D03*
Y837074D03*
Y840420D03*
Y843766D03*
Y847113D03*
Y850459D03*
Y853806D03*
Y857152D03*
Y860499D03*
Y863845D03*
Y867192D03*
Y870538D03*
Y873885D03*
Y877231D03*
Y880577D03*
Y883924D03*
Y887270D03*
Y890617D03*
Y893963D03*
Y897310D03*
Y900656D03*
Y904003D03*
Y907349D03*
Y910696D03*
Y914042D03*
Y917389D03*
Y920735D03*
Y924081D03*
Y927428D03*
Y930774D03*
Y934121D03*
Y937467D03*
Y940814D03*
Y944160D03*
Y947507D03*
Y950853D03*
Y954200D03*
Y957546D03*
Y960892D03*
Y964239D03*
Y967585D03*
Y970932D03*
Y974278D03*
Y977625D03*
Y980971D03*
Y984318D03*
Y987664D03*
Y991011D03*
Y994357D03*
Y1017782D03*
Y1021129D03*
Y1024475D03*
Y1027822D03*
Y1031168D03*
Y1034515D03*
Y1037861D03*
Y1041207D03*
Y1044554D03*
Y1047900D03*
Y1051247D03*
Y1054593D03*
Y1057940D03*
Y1061286D03*
Y1064633D03*
Y1067979D03*
Y1071326D03*
Y1074672D03*
Y1078018D03*
Y1081365D03*
Y1084711D03*
Y1088058D03*
Y1091404D03*
Y1094751D03*
Y1098097D03*
Y1101444D03*
Y1104790D03*
Y1108137D03*
Y1111483D03*
Y1114829D03*
Y1118176D03*
Y1121522D03*
Y1124869D03*
Y1128215D03*
Y1131562D03*
Y1134908D03*
Y1138255D03*
Y1141601D03*
Y1144948D03*
Y1148294D03*
Y1151641D03*
Y1154987D03*
Y1158333D03*
Y1161680D03*
Y1165026D03*
Y1168373D03*
Y1171719D03*
Y1175066D03*
Y1178412D03*
Y1181759D03*
Y1185105D03*
Y1188452D03*
Y1191798D03*
Y1195144D03*
Y1198491D03*
Y1201837D03*
Y1205184D03*
Y1208530D03*
Y1211877D03*
Y1215223D03*
Y1218570D03*
Y1221916D03*
Y1225263D03*
Y1228609D03*
Y1231955D03*
Y1235302D03*
Y1238648D03*
Y1241995D03*
Y1245341D03*
Y1248688D03*
Y1252034D03*
Y1255381D03*
Y1258727D03*
Y1262074D03*
Y1265420D03*
X803449Y766798D03*
Y770144D03*
Y773491D03*
Y776837D03*
Y780184D03*
Y783530D03*
Y786877D03*
Y790223D03*
Y793570D03*
Y796916D03*
Y800263D03*
Y803609D03*
Y806955D03*
Y810302D03*
Y813648D03*
Y816995D03*
Y820341D03*
Y823688D03*
Y827034D03*
Y830381D03*
Y833727D03*
Y837074D03*
Y840420D03*
Y843766D03*
Y847113D03*
Y850459D03*
Y853806D03*
Y857152D03*
Y860499D03*
Y863845D03*
Y867192D03*
Y870538D03*
Y873885D03*
Y877231D03*
Y880577D03*
Y883924D03*
Y887270D03*
Y890617D03*
Y893963D03*
Y897310D03*
Y900656D03*
Y904003D03*
Y907349D03*
Y910696D03*
Y914042D03*
Y917389D03*
Y920735D03*
Y924081D03*
Y927428D03*
Y930774D03*
Y934121D03*
Y937467D03*
Y940814D03*
Y944160D03*
Y947507D03*
Y950853D03*
Y954200D03*
Y957546D03*
Y960892D03*
Y964239D03*
Y967585D03*
Y970932D03*
Y974278D03*
Y977625D03*
Y980971D03*
Y984318D03*
Y987664D03*
Y991011D03*
Y994357D03*
Y1017782D03*
Y1021129D03*
Y1024475D03*
Y1027822D03*
Y1031168D03*
Y1034515D03*
Y1037861D03*
Y1041207D03*
Y1044554D03*
Y1047900D03*
Y1051247D03*
Y1054593D03*
Y1057940D03*
Y1061286D03*
Y1064633D03*
Y1067979D03*
Y1071326D03*
Y1074672D03*
Y1078018D03*
Y1081365D03*
Y1084711D03*
Y1088058D03*
Y1091404D03*
Y1094751D03*
Y1098097D03*
Y1101444D03*
Y1104790D03*
Y1108137D03*
Y1111483D03*
Y1114829D03*
Y1118176D03*
Y1121522D03*
Y1124869D03*
Y1128215D03*
Y1131562D03*
Y1134908D03*
Y1138255D03*
Y1141601D03*
Y1144948D03*
Y1148294D03*
Y1151641D03*
Y1154987D03*
Y1158333D03*
Y1161680D03*
Y1165026D03*
Y1168373D03*
Y1171719D03*
Y1175066D03*
Y1178412D03*
Y1181759D03*
Y1185105D03*
Y1188452D03*
Y1191798D03*
Y1195144D03*
Y1198491D03*
Y1201837D03*
Y1205184D03*
Y1208530D03*
Y1211877D03*
Y1215223D03*
Y1218570D03*
Y1221916D03*
Y1225263D03*
Y1228609D03*
Y1231955D03*
Y1235302D03*
Y1238648D03*
Y1241995D03*
Y1245341D03*
Y1248688D03*
Y1252034D03*
Y1255381D03*
Y1258727D03*
Y1262074D03*
Y1265420D03*
X819591Y766798D03*
Y770144D03*
Y773491D03*
Y776837D03*
Y780184D03*
Y783530D03*
Y786877D03*
Y790223D03*
Y793570D03*
Y796916D03*
Y800263D03*
Y803609D03*
Y806955D03*
Y810302D03*
Y813648D03*
Y816995D03*
Y820341D03*
Y823688D03*
Y827034D03*
Y830381D03*
Y833727D03*
Y837074D03*
Y840420D03*
Y843766D03*
Y847113D03*
Y850459D03*
Y853806D03*
Y857152D03*
Y860499D03*
Y863845D03*
Y867192D03*
Y870538D03*
Y873885D03*
Y877231D03*
Y880577D03*
Y883924D03*
Y887270D03*
Y890617D03*
Y893963D03*
Y897310D03*
Y900656D03*
Y904003D03*
Y907349D03*
Y910696D03*
Y914042D03*
Y917389D03*
Y920735D03*
Y924081D03*
Y927428D03*
Y930774D03*
Y934121D03*
Y937467D03*
Y940814D03*
Y944160D03*
Y947507D03*
Y950853D03*
Y954200D03*
Y957546D03*
Y960892D03*
Y964239D03*
Y967585D03*
Y970932D03*
Y974278D03*
Y977625D03*
Y980971D03*
Y984318D03*
Y987664D03*
Y991011D03*
Y994357D03*
Y1017782D03*
Y1021129D03*
Y1024475D03*
Y1027822D03*
Y1031168D03*
Y1034515D03*
Y1037861D03*
Y1041207D03*
Y1044554D03*
Y1047900D03*
Y1051247D03*
Y1054593D03*
Y1057940D03*
Y1061286D03*
Y1064633D03*
Y1067979D03*
Y1071326D03*
Y1074672D03*
Y1078018D03*
Y1081365D03*
Y1084711D03*
Y1088058D03*
Y1091404D03*
Y1094751D03*
Y1098097D03*
Y1101444D03*
Y1104790D03*
Y1108137D03*
Y1111483D03*
Y1114829D03*
Y1118176D03*
Y1121522D03*
Y1124869D03*
Y1128215D03*
Y1131562D03*
Y1134908D03*
Y1138255D03*
Y1141601D03*
Y1144948D03*
Y1148294D03*
Y1151641D03*
Y1154987D03*
Y1158333D03*
Y1161680D03*
Y1165026D03*
Y1168373D03*
Y1171719D03*
Y1175066D03*
Y1178412D03*
Y1181759D03*
Y1185105D03*
Y1188452D03*
Y1191798D03*
Y1195144D03*
Y1198491D03*
Y1201837D03*
Y1205184D03*
Y1208530D03*
Y1211877D03*
Y1215223D03*
Y1218570D03*
Y1221916D03*
Y1225263D03*
Y1228609D03*
Y1231955D03*
Y1235302D03*
Y1238648D03*
Y1241995D03*
Y1245341D03*
Y1248688D03*
Y1252034D03*
Y1255381D03*
Y1258727D03*
Y1262074D03*
Y1265420D03*
X833149Y766798D03*
Y770144D03*
Y773491D03*
Y776837D03*
Y780184D03*
Y783530D03*
Y786877D03*
Y790223D03*
Y793570D03*
Y796916D03*
Y800263D03*
Y803609D03*
Y806955D03*
Y810302D03*
Y813648D03*
Y816995D03*
Y820341D03*
Y823688D03*
Y827034D03*
Y830381D03*
Y833727D03*
Y837074D03*
Y840420D03*
Y843766D03*
Y847113D03*
Y850459D03*
Y853806D03*
Y857152D03*
Y860499D03*
Y863845D03*
Y867192D03*
Y870538D03*
Y873885D03*
Y877231D03*
Y880577D03*
Y883924D03*
Y887270D03*
Y890617D03*
Y893963D03*
Y897310D03*
Y900656D03*
Y904003D03*
Y907349D03*
Y910696D03*
Y914042D03*
Y917389D03*
Y920735D03*
Y924081D03*
Y927428D03*
Y930774D03*
Y934121D03*
Y937467D03*
Y940814D03*
Y944160D03*
Y947507D03*
Y950853D03*
Y954200D03*
Y957546D03*
Y960892D03*
Y964239D03*
Y967585D03*
Y970932D03*
Y974278D03*
Y977625D03*
Y980971D03*
Y984318D03*
Y987664D03*
Y991011D03*
Y994357D03*
Y1017782D03*
Y1021129D03*
Y1024475D03*
Y1027822D03*
Y1031168D03*
Y1034515D03*
Y1037861D03*
Y1041207D03*
Y1044554D03*
Y1047900D03*
Y1051247D03*
Y1054593D03*
Y1057940D03*
Y1061286D03*
Y1064633D03*
Y1067979D03*
Y1071326D03*
Y1074672D03*
Y1078018D03*
Y1081365D03*
Y1084711D03*
Y1088058D03*
Y1091404D03*
Y1094751D03*
Y1098097D03*
Y1101444D03*
Y1104790D03*
Y1108137D03*
Y1111483D03*
Y1114829D03*
Y1118176D03*
Y1121522D03*
Y1124869D03*
Y1128215D03*
Y1131562D03*
Y1134908D03*
Y1138255D03*
Y1141601D03*
Y1144948D03*
Y1148294D03*
Y1151641D03*
Y1154987D03*
Y1158333D03*
Y1161680D03*
Y1165026D03*
Y1168373D03*
Y1171719D03*
Y1175066D03*
Y1178412D03*
Y1181759D03*
Y1185105D03*
Y1188452D03*
Y1191798D03*
Y1195144D03*
Y1198491D03*
Y1201837D03*
Y1205184D03*
Y1208530D03*
Y1211877D03*
Y1215223D03*
Y1218570D03*
Y1221916D03*
Y1225263D03*
Y1228609D03*
Y1231955D03*
Y1235302D03*
Y1238648D03*
Y1241995D03*
Y1245341D03*
Y1248688D03*
Y1252034D03*
Y1255381D03*
Y1258727D03*
Y1262074D03*
Y1265420D03*
X849291Y766798D03*
Y770144D03*
Y773491D03*
Y776837D03*
Y780184D03*
Y783530D03*
Y786877D03*
Y790223D03*
Y793570D03*
Y796916D03*
Y800263D03*
Y803609D03*
Y806955D03*
Y810302D03*
Y813648D03*
Y816995D03*
Y820341D03*
Y823688D03*
Y827034D03*
Y830381D03*
Y833727D03*
Y837074D03*
Y840420D03*
Y843766D03*
Y847113D03*
Y850459D03*
Y853806D03*
Y857152D03*
Y860499D03*
Y863845D03*
Y867192D03*
Y870538D03*
Y873885D03*
Y877231D03*
Y880577D03*
Y883924D03*
Y887270D03*
Y890617D03*
Y893963D03*
Y897310D03*
Y900656D03*
Y904003D03*
Y907349D03*
Y910696D03*
Y914042D03*
Y917389D03*
Y920735D03*
Y924081D03*
Y927428D03*
Y930774D03*
Y934121D03*
Y937467D03*
Y940814D03*
Y944160D03*
Y947507D03*
Y950853D03*
Y954200D03*
Y957546D03*
Y960892D03*
Y964239D03*
Y967585D03*
Y970932D03*
Y974278D03*
Y977625D03*
Y980971D03*
Y984318D03*
Y987664D03*
Y991011D03*
Y994357D03*
Y1017782D03*
Y1021129D03*
Y1024475D03*
Y1027822D03*
Y1031168D03*
Y1034515D03*
Y1037861D03*
Y1041207D03*
Y1044554D03*
Y1047900D03*
Y1051247D03*
Y1054593D03*
Y1057940D03*
Y1061286D03*
Y1064633D03*
Y1067979D03*
Y1071326D03*
Y1074672D03*
Y1078018D03*
Y1081365D03*
Y1084711D03*
Y1088058D03*
Y1091404D03*
Y1094751D03*
Y1098097D03*
Y1101444D03*
Y1104790D03*
Y1108137D03*
Y1111483D03*
Y1114829D03*
Y1118176D03*
Y1121522D03*
Y1124869D03*
Y1128215D03*
Y1131562D03*
Y1134908D03*
Y1138255D03*
Y1141601D03*
Y1144948D03*
Y1148294D03*
Y1151641D03*
Y1154987D03*
Y1158333D03*
Y1161680D03*
Y1165026D03*
Y1168373D03*
Y1171719D03*
Y1175066D03*
Y1178412D03*
Y1181759D03*
Y1185105D03*
Y1188452D03*
Y1191798D03*
Y1195144D03*
Y1198491D03*
Y1201837D03*
Y1205184D03*
Y1208530D03*
Y1211877D03*
Y1215223D03*
Y1218570D03*
Y1221916D03*
Y1225263D03*
Y1228609D03*
Y1231955D03*
Y1235302D03*
Y1238648D03*
Y1241995D03*
Y1245341D03*
Y1248688D03*
Y1252034D03*
Y1255381D03*
Y1258727D03*
Y1262074D03*
Y1265420D03*
X1008191Y766798D03*
Y770144D03*
Y773491D03*
Y776837D03*
Y780184D03*
Y783530D03*
Y786877D03*
Y790223D03*
Y793570D03*
Y796916D03*
Y800263D03*
Y803609D03*
Y806955D03*
Y810302D03*
Y813648D03*
Y816995D03*
Y820341D03*
Y823688D03*
Y827034D03*
Y830381D03*
Y833727D03*
Y837074D03*
Y840420D03*
Y843766D03*
Y847113D03*
Y850459D03*
Y853806D03*
Y857152D03*
Y860499D03*
Y863845D03*
Y867192D03*
Y870538D03*
Y873885D03*
Y877231D03*
Y880577D03*
Y883924D03*
Y887270D03*
Y890617D03*
Y893963D03*
Y897310D03*
Y900656D03*
Y904003D03*
Y907349D03*
Y910696D03*
Y914042D03*
Y917389D03*
Y920735D03*
Y924081D03*
Y927428D03*
Y930774D03*
Y934121D03*
Y937467D03*
Y940814D03*
Y944160D03*
Y947507D03*
Y950853D03*
Y954200D03*
Y957546D03*
Y960892D03*
Y964239D03*
Y967585D03*
Y970932D03*
Y974278D03*
Y977625D03*
Y980971D03*
Y984318D03*
Y987664D03*
Y991011D03*
Y994357D03*
Y1017782D03*
Y1021129D03*
Y1024475D03*
Y1027822D03*
Y1031168D03*
Y1034515D03*
Y1037861D03*
Y1041207D03*
Y1044554D03*
Y1047900D03*
Y1051247D03*
Y1054593D03*
Y1057940D03*
Y1061286D03*
Y1064633D03*
Y1067979D03*
Y1071326D03*
Y1074672D03*
Y1078018D03*
Y1081365D03*
Y1084711D03*
Y1088058D03*
Y1091404D03*
Y1094751D03*
Y1098097D03*
Y1101444D03*
Y1104790D03*
Y1108137D03*
Y1111483D03*
Y1114829D03*
Y1118176D03*
Y1121522D03*
Y1124869D03*
Y1128215D03*
Y1131562D03*
Y1134908D03*
Y1138255D03*
Y1141601D03*
Y1144948D03*
Y1148294D03*
Y1151641D03*
Y1154987D03*
Y1158333D03*
Y1161680D03*
Y1165026D03*
Y1168373D03*
Y1171719D03*
Y1175066D03*
Y1178412D03*
Y1181759D03*
Y1185105D03*
Y1188452D03*
Y1191798D03*
Y1195144D03*
Y1198491D03*
Y1201837D03*
Y1205184D03*
Y1208530D03*
Y1211877D03*
Y1215223D03*
Y1218570D03*
Y1221916D03*
Y1225263D03*
Y1228609D03*
Y1231955D03*
Y1235302D03*
Y1238648D03*
Y1241995D03*
Y1245341D03*
Y1248688D03*
Y1252034D03*
Y1255381D03*
Y1258727D03*
Y1262074D03*
Y1265420D03*
X1037891Y766798D03*
Y770144D03*
X1024333Y766798D03*
Y770144D03*
X1037891Y773491D03*
Y776837D03*
Y780184D03*
Y783530D03*
Y786877D03*
X1024333Y773491D03*
Y776837D03*
Y780184D03*
Y783530D03*
Y786877D03*
X1037891Y790223D03*
Y793570D03*
Y796916D03*
Y800263D03*
Y803609D03*
X1024333Y790223D03*
Y793570D03*
Y796916D03*
Y800263D03*
Y803609D03*
X1037891Y806955D03*
Y810302D03*
Y813648D03*
Y816995D03*
Y820341D03*
X1024333Y806955D03*
Y810302D03*
Y813648D03*
Y816995D03*
Y820341D03*
X1037891Y823688D03*
Y827034D03*
Y830381D03*
Y833727D03*
X1024333Y823688D03*
Y827034D03*
Y830381D03*
Y833727D03*
X1037891Y837074D03*
Y840420D03*
Y843766D03*
Y847113D03*
Y850459D03*
X1024333Y837074D03*
Y840420D03*
Y843766D03*
Y847113D03*
Y850459D03*
X1037891Y853806D03*
Y857152D03*
Y860499D03*
Y863845D03*
Y867192D03*
X1024333Y853806D03*
Y857152D03*
Y860499D03*
Y863845D03*
Y867192D03*
X1037891Y870538D03*
Y873885D03*
Y877231D03*
Y880577D03*
Y883924D03*
X1024333Y870538D03*
Y873885D03*
Y877231D03*
Y880577D03*
Y883924D03*
X1037891Y887270D03*
Y890617D03*
Y893963D03*
Y897310D03*
Y900656D03*
X1024333Y887270D03*
Y890617D03*
Y893963D03*
Y897310D03*
Y900656D03*
X1037891Y904003D03*
Y907349D03*
Y910696D03*
Y914042D03*
Y917389D03*
X1024333Y904003D03*
Y907349D03*
Y910696D03*
Y914042D03*
Y917389D03*
X1037891Y920735D03*
Y924081D03*
Y927428D03*
Y930774D03*
Y934121D03*
X1024333Y920735D03*
Y924081D03*
Y927428D03*
Y930774D03*
Y934121D03*
X1037891Y937467D03*
Y940814D03*
Y944160D03*
Y947507D03*
X1024333Y937467D03*
Y940814D03*
Y944160D03*
Y947507D03*
X1037891Y950853D03*
Y954200D03*
Y957546D03*
Y960892D03*
Y964239D03*
X1024333Y950853D03*
Y954200D03*
Y957546D03*
Y960892D03*
Y964239D03*
X1037891Y967585D03*
Y970932D03*
Y974278D03*
Y977625D03*
Y980971D03*
X1024333Y967585D03*
Y970932D03*
Y974278D03*
Y977625D03*
Y980971D03*
X1037891Y984318D03*
Y987664D03*
Y991011D03*
Y994357D03*
X1024333Y984318D03*
Y987664D03*
Y991011D03*
Y994357D03*
X1037891Y1017782D03*
Y1021129D03*
Y1024475D03*
Y1027822D03*
Y1031168D03*
X1024333Y1017782D03*
Y1021129D03*
Y1024475D03*
Y1027822D03*
Y1031168D03*
X1037891Y1034515D03*
Y1037861D03*
Y1041207D03*
Y1044554D03*
Y1047900D03*
X1024333Y1034515D03*
Y1037861D03*
Y1041207D03*
Y1044554D03*
Y1047900D03*
X1037891Y1051247D03*
Y1054593D03*
Y1057940D03*
Y1061286D03*
X1024333Y1051247D03*
Y1054593D03*
Y1057940D03*
Y1061286D03*
X1037891Y1064633D03*
Y1067979D03*
Y1071326D03*
Y1074672D03*
Y1078018D03*
X1024333Y1064633D03*
Y1067979D03*
Y1071326D03*
Y1074672D03*
Y1078018D03*
X1037891Y1081365D03*
Y1084711D03*
Y1088058D03*
Y1091404D03*
Y1094751D03*
X1024333Y1081365D03*
Y1084711D03*
Y1088058D03*
Y1091404D03*
Y1094751D03*
X1037891Y1098097D03*
Y1101444D03*
Y1104790D03*
Y1108137D03*
Y1111483D03*
X1024333Y1098097D03*
Y1101444D03*
Y1104790D03*
Y1108137D03*
Y1111483D03*
X1037891Y1114829D03*
Y1118176D03*
Y1121522D03*
Y1124869D03*
Y1128215D03*
X1024333Y1114829D03*
Y1118176D03*
Y1121522D03*
Y1124869D03*
Y1128215D03*
X1037891Y1131562D03*
Y1134908D03*
Y1138255D03*
Y1141601D03*
Y1144948D03*
X1024333Y1131562D03*
Y1134908D03*
Y1138255D03*
Y1141601D03*
Y1144948D03*
X1037891Y1148294D03*
Y1151641D03*
Y1154987D03*
Y1158333D03*
Y1161680D03*
X1024333Y1148294D03*
Y1151641D03*
Y1154987D03*
Y1158333D03*
Y1161680D03*
X1037891Y1165026D03*
Y1168373D03*
Y1171719D03*
Y1175066D03*
X1024333Y1165026D03*
Y1168373D03*
Y1171719D03*
Y1175066D03*
X1037891Y1178412D03*
Y1181759D03*
Y1185105D03*
Y1188452D03*
Y1191798D03*
X1024333Y1178412D03*
Y1181759D03*
Y1185105D03*
Y1188452D03*
Y1191798D03*
X1037891Y1195144D03*
Y1198491D03*
Y1201837D03*
Y1205184D03*
Y1208530D03*
X1024333Y1195144D03*
Y1198491D03*
Y1201837D03*
Y1205184D03*
Y1208530D03*
X1037891Y1211877D03*
Y1215223D03*
Y1218570D03*
Y1221916D03*
Y1225263D03*
X1024333Y1211877D03*
Y1215223D03*
Y1218570D03*
Y1221916D03*
Y1225263D03*
X1037891Y1228609D03*
Y1231955D03*
Y1235302D03*
Y1238648D03*
Y1241995D03*
X1024333Y1228609D03*
Y1231955D03*
Y1235302D03*
Y1238648D03*
Y1241995D03*
X1037891Y1245341D03*
Y1248688D03*
Y1252034D03*
Y1255381D03*
Y1258727D03*
X1024333Y1245341D03*
Y1248688D03*
Y1252034D03*
Y1255381D03*
Y1258727D03*
X1037891Y1262074D03*
Y1265420D03*
X1024333Y1262074D03*
Y1265420D03*
X1054033Y766798D03*
Y770144D03*
Y773491D03*
Y776837D03*
Y780184D03*
Y783530D03*
Y786877D03*
Y790223D03*
Y793570D03*
Y796916D03*
Y800263D03*
Y803609D03*
Y806955D03*
Y810302D03*
Y813648D03*
Y816995D03*
Y820341D03*
Y823688D03*
Y827034D03*
Y830381D03*
Y833727D03*
Y837074D03*
Y840420D03*
Y843766D03*
Y847113D03*
Y850459D03*
Y853806D03*
Y857152D03*
Y860499D03*
Y863845D03*
Y867192D03*
Y870538D03*
Y873885D03*
Y877231D03*
Y880577D03*
Y883924D03*
Y887270D03*
Y890617D03*
Y893963D03*
Y897310D03*
Y900656D03*
Y904003D03*
Y907349D03*
Y910696D03*
Y914042D03*
Y917389D03*
Y920735D03*
Y924081D03*
Y927428D03*
Y930774D03*
Y934121D03*
Y937467D03*
Y940814D03*
Y944160D03*
Y947507D03*
Y950853D03*
Y954200D03*
Y957546D03*
Y960892D03*
Y964239D03*
Y967585D03*
Y970932D03*
Y974278D03*
Y977625D03*
Y980971D03*
Y984318D03*
Y987664D03*
Y991011D03*
Y994357D03*
Y1017782D03*
Y1021129D03*
Y1024475D03*
Y1027822D03*
Y1031168D03*
Y1034515D03*
Y1037861D03*
Y1041207D03*
Y1044554D03*
Y1047900D03*
Y1051247D03*
Y1054593D03*
Y1057940D03*
Y1061286D03*
Y1064633D03*
Y1067979D03*
Y1071326D03*
Y1074672D03*
Y1078018D03*
Y1081365D03*
Y1084711D03*
Y1088058D03*
Y1091404D03*
Y1094751D03*
Y1098097D03*
Y1101444D03*
Y1104790D03*
Y1108137D03*
Y1111483D03*
Y1114829D03*
Y1118176D03*
Y1121522D03*
Y1124869D03*
Y1128215D03*
Y1131562D03*
Y1134908D03*
Y1138255D03*
Y1141601D03*
Y1144948D03*
Y1148294D03*
Y1151641D03*
Y1154987D03*
Y1158333D03*
Y1161680D03*
Y1165026D03*
Y1168373D03*
Y1171719D03*
Y1175066D03*
Y1178412D03*
Y1181759D03*
Y1185105D03*
Y1188452D03*
Y1191798D03*
Y1195144D03*
Y1198491D03*
Y1201837D03*
Y1205184D03*
Y1208530D03*
Y1211877D03*
Y1215223D03*
Y1218570D03*
Y1221916D03*
Y1225263D03*
Y1228609D03*
Y1231955D03*
Y1235302D03*
Y1238648D03*
Y1241995D03*
Y1245341D03*
Y1248688D03*
Y1252034D03*
Y1255381D03*
Y1258727D03*
Y1262074D03*
Y1265420D03*
X1067591Y766798D03*
Y770144D03*
Y773491D03*
Y776837D03*
Y780184D03*
Y783530D03*
Y786877D03*
Y790223D03*
Y793570D03*
Y796916D03*
Y800263D03*
Y803609D03*
Y806955D03*
Y810302D03*
Y813648D03*
Y816995D03*
Y820341D03*
Y823688D03*
Y827034D03*
Y830381D03*
Y833727D03*
Y837074D03*
Y840420D03*
Y843766D03*
Y847113D03*
Y850459D03*
Y853806D03*
Y857152D03*
Y860499D03*
Y863845D03*
Y867192D03*
Y870538D03*
Y873885D03*
Y877231D03*
Y880577D03*
Y883924D03*
Y887270D03*
Y890617D03*
Y893963D03*
Y897310D03*
Y900656D03*
Y904003D03*
Y907349D03*
Y910696D03*
Y914042D03*
Y917389D03*
Y920735D03*
Y924081D03*
Y927428D03*
Y930774D03*
Y934121D03*
Y937467D03*
Y940814D03*
Y944160D03*
Y947507D03*
Y950853D03*
Y954200D03*
Y957546D03*
Y960892D03*
Y964239D03*
Y967585D03*
Y970932D03*
Y974278D03*
Y977625D03*
Y980971D03*
Y984318D03*
Y987664D03*
Y991011D03*
Y994357D03*
Y1017782D03*
Y1021129D03*
Y1024475D03*
Y1027822D03*
Y1031168D03*
Y1034515D03*
Y1037861D03*
Y1041207D03*
Y1044554D03*
Y1047900D03*
Y1051247D03*
Y1054593D03*
Y1057940D03*
Y1061286D03*
Y1064633D03*
Y1067979D03*
Y1071326D03*
Y1074672D03*
Y1078018D03*
Y1081365D03*
Y1084711D03*
Y1088058D03*
Y1091404D03*
Y1094751D03*
Y1098097D03*
Y1101444D03*
Y1104790D03*
Y1108137D03*
Y1111483D03*
Y1114829D03*
Y1118176D03*
Y1121522D03*
Y1124869D03*
Y1128215D03*
Y1131562D03*
Y1134908D03*
Y1138255D03*
Y1141601D03*
Y1144948D03*
Y1148294D03*
Y1151641D03*
Y1154987D03*
Y1158333D03*
Y1161680D03*
Y1165026D03*
Y1168373D03*
Y1171719D03*
Y1175066D03*
Y1178412D03*
Y1181759D03*
Y1185105D03*
Y1188452D03*
Y1191798D03*
Y1195144D03*
Y1198491D03*
Y1201837D03*
Y1205184D03*
Y1208530D03*
Y1211877D03*
Y1215223D03*
Y1218570D03*
Y1221916D03*
Y1225263D03*
Y1228609D03*
Y1231955D03*
Y1235302D03*
Y1238648D03*
Y1241995D03*
Y1245341D03*
Y1248688D03*
Y1252034D03*
Y1255381D03*
Y1258727D03*
Y1262074D03*
Y1265420D03*
X1083733Y766798D03*
Y770144D03*
Y773491D03*
Y776837D03*
Y780184D03*
Y783530D03*
Y786877D03*
Y790223D03*
Y793570D03*
Y796916D03*
Y800263D03*
Y803609D03*
Y806955D03*
Y810302D03*
Y813648D03*
Y816995D03*
Y820341D03*
Y823688D03*
Y827034D03*
Y830381D03*
Y833727D03*
Y837074D03*
Y840420D03*
Y843766D03*
Y847113D03*
Y850459D03*
Y853806D03*
Y857152D03*
Y860499D03*
Y863845D03*
Y867192D03*
Y870538D03*
Y873885D03*
Y877231D03*
Y880577D03*
Y883924D03*
Y887270D03*
Y890617D03*
Y893963D03*
Y897310D03*
Y900656D03*
Y904003D03*
Y907349D03*
Y910696D03*
Y914042D03*
Y917389D03*
Y920735D03*
Y924081D03*
Y927428D03*
Y930774D03*
Y934121D03*
Y937467D03*
Y940814D03*
Y944160D03*
Y947507D03*
Y950853D03*
Y954200D03*
Y957546D03*
Y960892D03*
Y964239D03*
Y967585D03*
Y970932D03*
Y974278D03*
Y977625D03*
Y980971D03*
Y984318D03*
Y987664D03*
Y991011D03*
Y994357D03*
Y1017782D03*
Y1021129D03*
Y1024475D03*
Y1027822D03*
Y1031168D03*
Y1034515D03*
Y1037861D03*
Y1041207D03*
Y1044554D03*
Y1047900D03*
Y1051247D03*
Y1054593D03*
Y1057940D03*
Y1061286D03*
Y1064633D03*
Y1067979D03*
Y1071326D03*
Y1074672D03*
Y1078018D03*
Y1081365D03*
Y1084711D03*
Y1088058D03*
Y1091404D03*
Y1094751D03*
Y1098097D03*
Y1101444D03*
Y1104790D03*
Y1108137D03*
Y1111483D03*
Y1114829D03*
Y1118176D03*
Y1121522D03*
Y1124869D03*
Y1128215D03*
Y1131562D03*
Y1134908D03*
Y1138255D03*
Y1141601D03*
Y1144948D03*
Y1148294D03*
Y1151641D03*
Y1154987D03*
Y1158333D03*
Y1161680D03*
Y1165026D03*
Y1168373D03*
Y1171719D03*
Y1175066D03*
Y1178412D03*
Y1181759D03*
Y1185105D03*
Y1188452D03*
Y1191798D03*
Y1195144D03*
Y1198491D03*
Y1201837D03*
Y1205184D03*
Y1208530D03*
Y1211877D03*
Y1215223D03*
Y1218570D03*
Y1221916D03*
Y1225263D03*
Y1228609D03*
Y1231955D03*
Y1235302D03*
Y1238648D03*
Y1241995D03*
Y1245341D03*
Y1248688D03*
Y1252034D03*
Y1255381D03*
Y1258727D03*
Y1262074D03*
Y1265420D03*
X1097291Y766798D03*
Y770144D03*
Y773491D03*
Y776837D03*
Y780184D03*
Y783530D03*
Y786877D03*
Y790223D03*
Y793570D03*
Y796916D03*
Y800263D03*
Y803609D03*
Y806955D03*
Y810302D03*
Y813648D03*
Y816995D03*
Y820341D03*
Y823688D03*
Y827034D03*
Y830381D03*
Y833727D03*
Y837074D03*
Y840420D03*
Y843766D03*
Y847113D03*
Y850459D03*
Y853806D03*
Y857152D03*
Y860499D03*
Y863845D03*
Y867192D03*
Y870538D03*
Y873885D03*
Y877231D03*
Y880577D03*
Y883924D03*
Y887270D03*
Y890617D03*
Y893963D03*
Y897310D03*
Y900656D03*
Y904003D03*
Y907349D03*
Y910696D03*
Y914042D03*
Y917389D03*
Y920735D03*
Y924081D03*
Y927428D03*
Y930774D03*
Y934121D03*
Y937467D03*
Y940814D03*
Y944160D03*
Y947507D03*
Y950853D03*
Y954200D03*
Y957546D03*
Y960892D03*
Y964239D03*
Y967585D03*
Y970932D03*
Y974278D03*
Y977625D03*
Y980971D03*
Y984318D03*
Y987664D03*
Y991011D03*
Y994357D03*
Y1017782D03*
Y1021129D03*
Y1024475D03*
Y1027822D03*
Y1031168D03*
Y1034515D03*
Y1037861D03*
Y1041207D03*
Y1044554D03*
Y1047900D03*
Y1051247D03*
Y1054593D03*
Y1057940D03*
Y1061286D03*
Y1064633D03*
Y1067979D03*
Y1071326D03*
Y1074672D03*
Y1078018D03*
Y1081365D03*
Y1084711D03*
Y1088058D03*
Y1091404D03*
Y1094751D03*
Y1098097D03*
Y1101444D03*
Y1104790D03*
Y1108137D03*
Y1111483D03*
Y1114829D03*
Y1118176D03*
Y1121522D03*
Y1124869D03*
Y1128215D03*
Y1131562D03*
Y1134908D03*
Y1138255D03*
Y1141601D03*
Y1144948D03*
Y1148294D03*
Y1151641D03*
Y1154987D03*
Y1158333D03*
Y1161680D03*
Y1165026D03*
Y1168373D03*
Y1171719D03*
Y1175066D03*
Y1178412D03*
Y1181759D03*
Y1185105D03*
Y1188452D03*
Y1191798D03*
Y1195144D03*
Y1198491D03*
Y1201837D03*
Y1205184D03*
Y1208530D03*
Y1211877D03*
Y1215223D03*
Y1218570D03*
Y1221916D03*
Y1225263D03*
Y1228609D03*
Y1231955D03*
Y1235302D03*
Y1238648D03*
Y1241995D03*
Y1245341D03*
Y1248688D03*
Y1252034D03*
Y1255381D03*
Y1258727D03*
Y1262074D03*
Y1265420D03*
X1113433Y766798D03*
Y770144D03*
Y773491D03*
Y776837D03*
Y780184D03*
Y783530D03*
Y786877D03*
Y790223D03*
Y793570D03*
Y796916D03*
Y800263D03*
Y803609D03*
Y806955D03*
Y810302D03*
Y813648D03*
Y816995D03*
Y820341D03*
Y823688D03*
Y827034D03*
Y830381D03*
Y833727D03*
Y837074D03*
Y840420D03*
Y843766D03*
Y847113D03*
Y850459D03*
Y853806D03*
Y857152D03*
Y860499D03*
Y863845D03*
Y867192D03*
Y870538D03*
Y873885D03*
Y877231D03*
Y880577D03*
Y883924D03*
Y887270D03*
Y890617D03*
Y893963D03*
Y897310D03*
Y900656D03*
Y904003D03*
Y907349D03*
Y910696D03*
Y914042D03*
Y917389D03*
Y920735D03*
Y924081D03*
Y927428D03*
Y930774D03*
Y934121D03*
Y937467D03*
Y940814D03*
Y944160D03*
Y947507D03*
Y950853D03*
Y954200D03*
Y957546D03*
Y960892D03*
Y964239D03*
Y967585D03*
Y970932D03*
Y974278D03*
Y977625D03*
Y980971D03*
Y984318D03*
Y987664D03*
Y991011D03*
Y994357D03*
Y1017782D03*
Y1021129D03*
Y1024475D03*
Y1027822D03*
Y1031168D03*
Y1034515D03*
Y1037861D03*
Y1041207D03*
Y1044554D03*
Y1047900D03*
Y1051247D03*
Y1054593D03*
Y1057940D03*
Y1061286D03*
Y1064633D03*
Y1067979D03*
Y1071326D03*
Y1074672D03*
Y1078018D03*
Y1081365D03*
Y1084711D03*
Y1088058D03*
Y1091404D03*
Y1094751D03*
Y1098097D03*
Y1101444D03*
Y1104790D03*
Y1108137D03*
Y1111483D03*
Y1114829D03*
Y1118176D03*
Y1121522D03*
Y1124869D03*
Y1128215D03*
Y1131562D03*
Y1134908D03*
Y1138255D03*
Y1141601D03*
Y1144948D03*
Y1148294D03*
Y1151641D03*
Y1154987D03*
Y1158333D03*
Y1161680D03*
Y1165026D03*
Y1168373D03*
Y1171719D03*
Y1175066D03*
Y1178412D03*
Y1181759D03*
Y1185105D03*
Y1188452D03*
Y1191798D03*
Y1195144D03*
Y1198491D03*
Y1201837D03*
Y1205184D03*
Y1208530D03*
Y1211877D03*
Y1215223D03*
Y1218570D03*
Y1221916D03*
Y1225263D03*
Y1228609D03*
Y1231955D03*
Y1235302D03*
Y1238648D03*
Y1241995D03*
Y1245341D03*
Y1248688D03*
Y1252034D03*
Y1255381D03*
Y1258727D03*
Y1262074D03*
Y1265420D03*
X1126991Y766798D03*
Y770144D03*
Y773491D03*
Y776837D03*
Y780184D03*
Y783530D03*
Y786877D03*
Y790223D03*
Y793570D03*
Y796916D03*
Y800263D03*
Y803609D03*
Y806955D03*
Y810302D03*
Y813648D03*
Y816995D03*
Y820341D03*
Y823688D03*
Y827034D03*
Y830381D03*
Y833727D03*
Y837074D03*
Y840420D03*
Y843766D03*
Y847113D03*
Y850459D03*
Y853806D03*
Y857152D03*
Y860499D03*
Y863845D03*
Y867192D03*
Y870538D03*
Y873885D03*
Y877231D03*
Y880577D03*
Y883924D03*
Y887270D03*
Y890617D03*
Y893963D03*
Y897310D03*
Y900656D03*
Y904003D03*
Y907349D03*
Y910696D03*
Y914042D03*
Y917389D03*
Y920735D03*
Y924081D03*
Y927428D03*
Y930774D03*
Y934121D03*
Y937467D03*
Y940814D03*
Y944160D03*
Y947507D03*
Y950853D03*
Y954200D03*
Y957546D03*
Y960892D03*
Y964239D03*
Y967585D03*
Y970932D03*
Y974278D03*
Y977625D03*
Y980971D03*
Y984318D03*
Y987664D03*
Y991011D03*
Y994357D03*
Y1017782D03*
Y1021129D03*
Y1024475D03*
Y1027822D03*
Y1031168D03*
Y1034515D03*
Y1037861D03*
Y1041207D03*
Y1044554D03*
Y1047900D03*
Y1051247D03*
Y1054593D03*
Y1057940D03*
Y1061286D03*
Y1064633D03*
Y1067979D03*
Y1071326D03*
Y1074672D03*
Y1078018D03*
Y1081365D03*
Y1084711D03*
Y1088058D03*
Y1091404D03*
Y1094751D03*
Y1098097D03*
Y1101444D03*
Y1104790D03*
Y1108137D03*
Y1111483D03*
Y1114829D03*
Y1118176D03*
Y1121522D03*
Y1124869D03*
Y1128215D03*
Y1131562D03*
Y1134908D03*
Y1138255D03*
Y1141601D03*
Y1144948D03*
Y1148294D03*
Y1151641D03*
Y1154987D03*
Y1158333D03*
Y1161680D03*
Y1165026D03*
Y1168373D03*
Y1171719D03*
Y1175066D03*
Y1178412D03*
Y1181759D03*
Y1185105D03*
Y1188452D03*
Y1191798D03*
Y1195144D03*
Y1198491D03*
Y1201837D03*
Y1205184D03*
Y1208530D03*
Y1211877D03*
Y1215223D03*
Y1218570D03*
Y1221916D03*
Y1225263D03*
Y1228609D03*
Y1231955D03*
Y1235302D03*
Y1238648D03*
Y1241995D03*
Y1245341D03*
Y1248688D03*
Y1252034D03*
Y1255381D03*
Y1258727D03*
Y1262074D03*
Y1265420D03*
X1143133Y766798D03*
Y770144D03*
Y773491D03*
Y776837D03*
Y780184D03*
Y783530D03*
Y786877D03*
Y790223D03*
Y793570D03*
Y796916D03*
Y800263D03*
Y803609D03*
Y806955D03*
Y810302D03*
Y813648D03*
Y816995D03*
Y820341D03*
Y823688D03*
Y827034D03*
Y830381D03*
Y833727D03*
Y837074D03*
Y840420D03*
Y843766D03*
Y847113D03*
Y850459D03*
Y853806D03*
Y857152D03*
Y860499D03*
Y863845D03*
Y867192D03*
Y870538D03*
Y873885D03*
Y877231D03*
Y880577D03*
Y883924D03*
Y887270D03*
Y890617D03*
Y893963D03*
Y897310D03*
Y900656D03*
Y904003D03*
Y907349D03*
Y910696D03*
Y914042D03*
Y917389D03*
Y920735D03*
Y924081D03*
Y927428D03*
Y930774D03*
Y934121D03*
Y937467D03*
Y940814D03*
Y944160D03*
Y947507D03*
Y950853D03*
Y954200D03*
Y957546D03*
Y960892D03*
Y964239D03*
Y967585D03*
Y970932D03*
Y974278D03*
Y977625D03*
Y980971D03*
Y984318D03*
Y987664D03*
Y991011D03*
Y994357D03*
Y1017782D03*
Y1021129D03*
Y1024475D03*
Y1027822D03*
Y1031168D03*
Y1034515D03*
Y1037861D03*
Y1041207D03*
Y1044554D03*
Y1047900D03*
Y1051247D03*
Y1054593D03*
Y1057940D03*
Y1061286D03*
Y1064633D03*
Y1067979D03*
Y1071326D03*
Y1074672D03*
Y1078018D03*
Y1081365D03*
Y1084711D03*
Y1088058D03*
Y1091404D03*
Y1094751D03*
Y1098097D03*
Y1101444D03*
Y1104790D03*
Y1108137D03*
Y1111483D03*
Y1114829D03*
Y1118176D03*
Y1121522D03*
Y1124869D03*
Y1128215D03*
Y1131562D03*
Y1134908D03*
Y1138255D03*
Y1141601D03*
Y1144948D03*
Y1148294D03*
Y1151641D03*
Y1154987D03*
Y1158333D03*
Y1161680D03*
Y1165026D03*
Y1168373D03*
Y1171719D03*
Y1175066D03*
Y1178412D03*
Y1181759D03*
Y1185105D03*
Y1188452D03*
Y1191798D03*
Y1195144D03*
Y1198491D03*
Y1201837D03*
Y1205184D03*
Y1208530D03*
Y1211877D03*
Y1215223D03*
Y1218570D03*
Y1221916D03*
Y1225263D03*
Y1228609D03*
Y1231955D03*
Y1235302D03*
Y1238648D03*
Y1241995D03*
Y1245341D03*
Y1248688D03*
Y1252034D03*
Y1255381D03*
Y1258727D03*
Y1262074D03*
Y1265420D03*
X1156691Y766798D03*
Y770144D03*
Y773491D03*
Y776837D03*
Y780184D03*
Y783530D03*
Y786877D03*
Y790223D03*
Y793570D03*
Y796916D03*
Y800263D03*
Y803609D03*
Y806955D03*
Y810302D03*
Y813648D03*
Y816995D03*
Y820341D03*
Y823688D03*
Y827034D03*
Y830381D03*
Y833727D03*
Y837074D03*
Y840420D03*
Y843766D03*
Y847113D03*
Y850459D03*
Y853806D03*
Y857152D03*
Y860499D03*
Y863845D03*
Y867192D03*
Y870538D03*
Y873885D03*
Y877231D03*
Y880577D03*
Y883924D03*
Y887270D03*
Y890617D03*
Y893963D03*
Y897310D03*
Y900656D03*
Y904003D03*
Y907349D03*
Y910696D03*
Y914042D03*
Y917389D03*
Y920735D03*
Y924081D03*
Y927428D03*
Y930774D03*
Y934121D03*
Y937467D03*
Y940814D03*
Y944160D03*
Y947507D03*
Y950853D03*
Y954200D03*
Y957546D03*
Y960892D03*
Y964239D03*
Y967585D03*
Y970932D03*
Y974278D03*
Y977625D03*
Y980971D03*
Y984318D03*
Y987664D03*
Y991011D03*
Y994357D03*
Y1017782D03*
Y1021129D03*
Y1024475D03*
Y1027822D03*
Y1031168D03*
Y1034515D03*
Y1037861D03*
Y1041207D03*
Y1044554D03*
Y1047900D03*
Y1051247D03*
Y1054593D03*
Y1057940D03*
Y1061286D03*
Y1064633D03*
Y1067979D03*
Y1071326D03*
Y1074672D03*
Y1078018D03*
Y1081365D03*
Y1084711D03*
Y1088058D03*
Y1091404D03*
Y1094751D03*
Y1098097D03*
Y1101444D03*
Y1104790D03*
Y1108137D03*
Y1111483D03*
Y1114829D03*
Y1118176D03*
Y1121522D03*
Y1124869D03*
Y1128215D03*
Y1131562D03*
Y1134908D03*
Y1138255D03*
Y1141601D03*
Y1144948D03*
Y1148294D03*
Y1151641D03*
Y1154987D03*
Y1158333D03*
Y1161680D03*
Y1165026D03*
Y1168373D03*
Y1171719D03*
Y1175066D03*
Y1178412D03*
Y1181759D03*
Y1185105D03*
Y1188452D03*
Y1191798D03*
Y1195144D03*
Y1198491D03*
Y1201837D03*
Y1205184D03*
Y1208530D03*
Y1211877D03*
Y1215223D03*
Y1218570D03*
Y1221916D03*
Y1225263D03*
Y1228609D03*
Y1231955D03*
Y1235302D03*
Y1238648D03*
Y1241995D03*
Y1245341D03*
Y1248688D03*
Y1252034D03*
Y1255381D03*
Y1258727D03*
Y1262074D03*
Y1265420D03*
X1186391Y766798D03*
Y770144D03*
X1172833Y766798D03*
Y770144D03*
X1186391Y773491D03*
Y776837D03*
Y780184D03*
Y783530D03*
Y786877D03*
X1172833Y773491D03*
Y776837D03*
Y780184D03*
Y783530D03*
Y786877D03*
X1186391Y790223D03*
Y793570D03*
Y796916D03*
Y800263D03*
Y803609D03*
X1172833Y790223D03*
Y793570D03*
Y796916D03*
Y800263D03*
Y803609D03*
X1186391Y806955D03*
Y810302D03*
Y813648D03*
Y816995D03*
Y820341D03*
X1172833Y806955D03*
Y810302D03*
Y813648D03*
Y816995D03*
Y820341D03*
X1186391Y823688D03*
Y827034D03*
Y830381D03*
Y833727D03*
X1172833Y823688D03*
Y827034D03*
Y830381D03*
Y833727D03*
X1186391Y837074D03*
Y840420D03*
Y843766D03*
Y847113D03*
Y850459D03*
X1172833Y837074D03*
Y840420D03*
Y843766D03*
Y847113D03*
Y850459D03*
X1186391Y853806D03*
Y857152D03*
Y860499D03*
Y863845D03*
Y867192D03*
X1172833Y853806D03*
Y857152D03*
Y860499D03*
Y863845D03*
Y867192D03*
X1186391Y870538D03*
Y873885D03*
Y877231D03*
Y880577D03*
Y883924D03*
X1172833Y870538D03*
Y873885D03*
Y877231D03*
Y880577D03*
Y883924D03*
X1186391Y887270D03*
Y890617D03*
Y893963D03*
Y897310D03*
Y900656D03*
X1172833Y887270D03*
Y890617D03*
Y893963D03*
Y897310D03*
Y900656D03*
X1186391Y904003D03*
Y907349D03*
Y910696D03*
Y914042D03*
Y917389D03*
X1172833Y904003D03*
Y907349D03*
Y910696D03*
Y914042D03*
Y917389D03*
X1186391Y920735D03*
Y924081D03*
Y927428D03*
Y930774D03*
Y934121D03*
X1172833Y920735D03*
Y924081D03*
Y927428D03*
Y930774D03*
Y934121D03*
X1186391Y937467D03*
Y940814D03*
Y944160D03*
Y947507D03*
X1172833Y937467D03*
Y940814D03*
Y944160D03*
Y947507D03*
X1186391Y950853D03*
Y954200D03*
Y957546D03*
Y960892D03*
Y964239D03*
X1172833Y950853D03*
Y954200D03*
Y957546D03*
Y960892D03*
Y964239D03*
X1186391Y967585D03*
Y970932D03*
Y974278D03*
Y977625D03*
Y980971D03*
X1172833Y967585D03*
Y970932D03*
Y974278D03*
Y977625D03*
Y980971D03*
X1186391Y984318D03*
Y987664D03*
Y991011D03*
Y994357D03*
X1172833Y984318D03*
Y987664D03*
Y991011D03*
Y994357D03*
X1186391Y1017782D03*
Y1021129D03*
Y1024475D03*
Y1027822D03*
Y1031168D03*
X1172833Y1017782D03*
Y1021129D03*
Y1024475D03*
Y1027822D03*
Y1031168D03*
X1186391Y1034515D03*
Y1037861D03*
Y1041207D03*
Y1044554D03*
Y1047900D03*
X1172833Y1034515D03*
Y1037861D03*
Y1041207D03*
Y1044554D03*
Y1047900D03*
X1186391Y1051247D03*
Y1054593D03*
Y1057940D03*
Y1061286D03*
X1172833Y1051247D03*
Y1054593D03*
Y1057940D03*
Y1061286D03*
X1186391Y1064633D03*
Y1067979D03*
Y1071326D03*
Y1074672D03*
Y1078018D03*
X1172833Y1064633D03*
Y1067979D03*
Y1071326D03*
Y1074672D03*
Y1078018D03*
X1186391Y1081365D03*
Y1084711D03*
Y1088058D03*
Y1091404D03*
Y1094751D03*
X1172833Y1081365D03*
Y1084711D03*
Y1088058D03*
Y1091404D03*
Y1094751D03*
X1186391Y1098097D03*
Y1101444D03*
Y1104790D03*
Y1108137D03*
Y1111483D03*
X1172833Y1098097D03*
Y1101444D03*
Y1104790D03*
Y1108137D03*
Y1111483D03*
X1186391Y1114829D03*
Y1118176D03*
Y1121522D03*
Y1124869D03*
Y1128215D03*
X1172833Y1114829D03*
Y1118176D03*
Y1121522D03*
Y1124869D03*
Y1128215D03*
X1186391Y1131562D03*
Y1134908D03*
Y1138255D03*
Y1141601D03*
Y1144948D03*
X1172833Y1131562D03*
Y1134908D03*
Y1138255D03*
Y1141601D03*
Y1144948D03*
X1186391Y1148294D03*
Y1151641D03*
Y1154987D03*
Y1158333D03*
Y1161680D03*
X1172833Y1148294D03*
Y1151641D03*
Y1154987D03*
Y1158333D03*
Y1161680D03*
X1186391Y1165026D03*
Y1168373D03*
Y1171719D03*
Y1175066D03*
X1172833Y1165026D03*
Y1168373D03*
Y1171719D03*
Y1175066D03*
X1186391Y1178412D03*
Y1181759D03*
Y1185105D03*
Y1188452D03*
Y1191798D03*
X1172833Y1178412D03*
Y1181759D03*
Y1185105D03*
Y1188452D03*
Y1191798D03*
X1186391Y1195144D03*
Y1198491D03*
Y1201837D03*
Y1205184D03*
Y1208530D03*
X1172833Y1195144D03*
Y1198491D03*
Y1201837D03*
Y1205184D03*
Y1208530D03*
X1186391Y1211877D03*
Y1215223D03*
Y1218570D03*
Y1221916D03*
Y1225263D03*
X1172833Y1211877D03*
Y1215223D03*
Y1218570D03*
Y1221916D03*
Y1225263D03*
X1186391Y1228609D03*
Y1231955D03*
Y1235302D03*
Y1238648D03*
Y1241995D03*
X1172833Y1228609D03*
Y1231955D03*
Y1235302D03*
Y1238648D03*
Y1241995D03*
X1186391Y1245341D03*
Y1248688D03*
Y1252034D03*
Y1255381D03*
Y1258727D03*
X1172833Y1245341D03*
Y1248688D03*
Y1252034D03*
Y1255381D03*
Y1258727D03*
X1186391Y1262074D03*
Y1265420D03*
X1172833Y1262074D03*
Y1265420D03*
X1202533Y766798D03*
Y770144D03*
Y773491D03*
Y776837D03*
Y780184D03*
Y783530D03*
Y786877D03*
Y790223D03*
Y793570D03*
Y796916D03*
Y800263D03*
Y803609D03*
Y806955D03*
Y810302D03*
Y813648D03*
Y816995D03*
Y820341D03*
Y823688D03*
Y827034D03*
Y830381D03*
Y833727D03*
Y837074D03*
Y840420D03*
Y843766D03*
Y847113D03*
Y850459D03*
Y853806D03*
Y857152D03*
Y860499D03*
Y863845D03*
Y867192D03*
Y870538D03*
Y873885D03*
Y877231D03*
Y880577D03*
Y883924D03*
Y887270D03*
Y890617D03*
Y893963D03*
Y897310D03*
Y900656D03*
Y904003D03*
Y907349D03*
Y910696D03*
Y914042D03*
Y917389D03*
Y920735D03*
Y924081D03*
Y927428D03*
Y930774D03*
Y934121D03*
Y937467D03*
Y940814D03*
Y944160D03*
Y947507D03*
Y950853D03*
Y954200D03*
Y957546D03*
Y960892D03*
Y964239D03*
Y967585D03*
Y970932D03*
Y974278D03*
Y977625D03*
Y980971D03*
Y984318D03*
Y987664D03*
Y991011D03*
Y994357D03*
Y1017782D03*
Y1021129D03*
Y1024475D03*
Y1027822D03*
Y1031168D03*
Y1034515D03*
Y1037861D03*
Y1041207D03*
Y1044554D03*
Y1047900D03*
Y1051247D03*
Y1054593D03*
Y1057940D03*
Y1061286D03*
Y1064633D03*
Y1067979D03*
Y1071326D03*
Y1074672D03*
Y1078018D03*
Y1081365D03*
Y1084711D03*
Y1088058D03*
Y1091404D03*
Y1094751D03*
Y1098097D03*
Y1101444D03*
Y1104790D03*
Y1108137D03*
Y1111483D03*
Y1114829D03*
Y1118176D03*
Y1121522D03*
Y1124869D03*
Y1128215D03*
Y1131562D03*
Y1134908D03*
Y1138255D03*
Y1141601D03*
Y1144948D03*
Y1148294D03*
Y1151641D03*
Y1154987D03*
Y1158333D03*
Y1161680D03*
Y1165026D03*
Y1168373D03*
Y1171719D03*
Y1175066D03*
Y1178412D03*
Y1181759D03*
Y1185105D03*
Y1188452D03*
Y1191798D03*
Y1195144D03*
Y1198491D03*
Y1201837D03*
Y1205184D03*
Y1208530D03*
Y1211877D03*
Y1215223D03*
Y1218570D03*
Y1221916D03*
Y1225263D03*
Y1228609D03*
Y1231955D03*
Y1235302D03*
Y1238648D03*
Y1241995D03*
Y1245341D03*
Y1248688D03*
Y1252034D03*
Y1255381D03*
Y1258727D03*
Y1262074D03*
Y1265420D03*
X1216091Y766798D03*
Y770144D03*
Y773491D03*
Y776837D03*
Y780184D03*
Y783530D03*
Y786877D03*
Y790223D03*
Y793570D03*
Y796916D03*
Y800263D03*
Y803609D03*
Y806955D03*
Y810302D03*
Y813648D03*
Y816995D03*
Y820341D03*
Y823688D03*
Y827034D03*
Y830381D03*
Y833727D03*
Y837074D03*
Y840420D03*
Y843766D03*
Y847113D03*
Y850459D03*
Y853806D03*
Y857152D03*
Y860499D03*
Y863845D03*
Y867192D03*
Y870538D03*
Y873885D03*
Y877231D03*
Y880577D03*
Y883924D03*
Y887270D03*
Y890617D03*
Y893963D03*
Y897310D03*
Y900656D03*
Y904003D03*
Y907349D03*
Y910696D03*
Y914042D03*
Y917389D03*
Y920735D03*
Y924081D03*
Y927428D03*
Y930774D03*
Y934121D03*
Y937467D03*
Y940814D03*
Y944160D03*
Y947507D03*
Y950853D03*
Y954200D03*
Y957546D03*
Y960892D03*
Y964239D03*
Y967585D03*
Y970932D03*
Y974278D03*
Y977625D03*
Y980971D03*
Y984318D03*
Y987664D03*
Y991011D03*
Y994357D03*
Y1017782D03*
Y1021129D03*
Y1024475D03*
Y1027822D03*
Y1031168D03*
Y1034515D03*
Y1037861D03*
Y1041207D03*
Y1044554D03*
Y1047900D03*
Y1051247D03*
Y1054593D03*
Y1057940D03*
Y1061286D03*
Y1064633D03*
Y1067979D03*
Y1071326D03*
Y1074672D03*
Y1078018D03*
Y1081365D03*
Y1084711D03*
Y1088058D03*
Y1091404D03*
Y1094751D03*
Y1098097D03*
Y1101444D03*
Y1104790D03*
Y1108137D03*
Y1111483D03*
Y1114829D03*
Y1118176D03*
Y1121522D03*
Y1124869D03*
Y1128215D03*
Y1131562D03*
Y1134908D03*
Y1138255D03*
Y1141601D03*
Y1144948D03*
Y1148294D03*
Y1151641D03*
Y1154987D03*
Y1158333D03*
Y1161680D03*
Y1165026D03*
Y1168373D03*
Y1171719D03*
Y1175066D03*
Y1178412D03*
Y1181759D03*
Y1185105D03*
Y1188452D03*
Y1191798D03*
Y1195144D03*
Y1198491D03*
Y1201837D03*
Y1205184D03*
Y1208530D03*
Y1211877D03*
Y1215223D03*
Y1218570D03*
Y1221916D03*
Y1225263D03*
Y1228609D03*
Y1231955D03*
Y1235302D03*
Y1238648D03*
Y1241995D03*
Y1245341D03*
Y1248688D03*
Y1252034D03*
Y1255381D03*
Y1258727D03*
Y1262074D03*
Y1265420D03*
X1232233Y766798D03*
Y770144D03*
Y773491D03*
Y776837D03*
Y780184D03*
Y783530D03*
Y786877D03*
Y790223D03*
Y793570D03*
Y796916D03*
Y800263D03*
Y803609D03*
Y806955D03*
Y810302D03*
Y813648D03*
Y816995D03*
Y820341D03*
Y823688D03*
Y827034D03*
Y830381D03*
Y833727D03*
Y837074D03*
Y840420D03*
Y843766D03*
Y847113D03*
Y850459D03*
Y853806D03*
Y857152D03*
Y860499D03*
Y863845D03*
Y867192D03*
Y870538D03*
Y873885D03*
Y877231D03*
Y880577D03*
Y883924D03*
Y887270D03*
Y890617D03*
Y893963D03*
Y897310D03*
Y900656D03*
Y904003D03*
Y907349D03*
Y910696D03*
Y914042D03*
Y917389D03*
Y920735D03*
Y924081D03*
Y927428D03*
Y930774D03*
Y934121D03*
Y937467D03*
Y940814D03*
Y944160D03*
Y947507D03*
Y950853D03*
Y954200D03*
Y957546D03*
Y960892D03*
Y964239D03*
Y967585D03*
Y970932D03*
Y974278D03*
Y977625D03*
Y980971D03*
Y984318D03*
Y987664D03*
Y991011D03*
Y994357D03*
Y1017782D03*
Y1021129D03*
Y1024475D03*
Y1027822D03*
Y1031168D03*
Y1034515D03*
Y1037861D03*
Y1041207D03*
Y1044554D03*
Y1047900D03*
Y1051247D03*
Y1054593D03*
Y1057940D03*
Y1061286D03*
Y1064633D03*
Y1067979D03*
Y1071326D03*
Y1074672D03*
Y1078018D03*
Y1081365D03*
Y1084711D03*
Y1088058D03*
Y1091404D03*
Y1094751D03*
Y1098097D03*
Y1101444D03*
Y1104790D03*
Y1108137D03*
Y1111483D03*
Y1114829D03*
Y1118176D03*
Y1121522D03*
Y1124869D03*
Y1128215D03*
Y1131562D03*
Y1134908D03*
Y1138255D03*
Y1141601D03*
Y1144948D03*
Y1148294D03*
Y1151641D03*
Y1154987D03*
Y1158333D03*
Y1161680D03*
Y1165026D03*
Y1168373D03*
Y1171719D03*
Y1175066D03*
Y1178412D03*
Y1181759D03*
Y1185105D03*
Y1188452D03*
Y1191798D03*
Y1195144D03*
Y1198491D03*
Y1201837D03*
Y1205184D03*
Y1208530D03*
Y1211877D03*
Y1215223D03*
Y1218570D03*
Y1221916D03*
Y1225263D03*
Y1228609D03*
Y1231955D03*
Y1235302D03*
Y1238648D03*
Y1241995D03*
Y1245341D03*
Y1248688D03*
Y1252034D03*
Y1255381D03*
Y1258727D03*
Y1262074D03*
Y1265420D03*
X1601391Y766798D03*
Y770144D03*
Y773491D03*
Y776837D03*
Y780184D03*
Y783530D03*
Y786877D03*
Y790223D03*
Y793570D03*
Y796916D03*
Y800263D03*
Y803609D03*
Y806955D03*
Y810302D03*
Y813648D03*
Y816995D03*
Y820341D03*
Y823688D03*
Y827034D03*
Y830381D03*
Y833727D03*
Y837074D03*
Y840420D03*
Y843766D03*
Y847113D03*
Y850459D03*
Y853806D03*
Y857152D03*
Y860499D03*
Y863845D03*
Y867192D03*
Y870538D03*
Y873885D03*
Y877231D03*
Y880577D03*
Y883924D03*
Y887270D03*
Y890617D03*
Y893963D03*
Y897310D03*
Y900656D03*
Y904003D03*
Y907349D03*
Y910696D03*
Y914042D03*
Y917389D03*
Y920735D03*
Y924081D03*
Y927428D03*
Y930774D03*
Y934121D03*
Y937467D03*
Y940814D03*
Y944160D03*
Y947507D03*
Y950853D03*
Y954200D03*
Y957546D03*
Y960892D03*
Y964239D03*
Y967585D03*
Y970932D03*
Y974278D03*
Y977625D03*
Y980971D03*
Y984318D03*
Y987664D03*
Y991011D03*
Y994357D03*
Y1017782D03*
Y1021129D03*
Y1024475D03*
Y1027822D03*
Y1031168D03*
Y1034515D03*
Y1037861D03*
Y1041207D03*
Y1044554D03*
Y1047900D03*
Y1051247D03*
Y1054593D03*
Y1057940D03*
Y1061286D03*
Y1064633D03*
Y1067979D03*
Y1071326D03*
Y1074672D03*
Y1078018D03*
Y1081365D03*
Y1084711D03*
Y1088058D03*
Y1091404D03*
Y1094751D03*
Y1098097D03*
Y1101444D03*
Y1104790D03*
Y1108137D03*
Y1111483D03*
Y1114829D03*
Y1118176D03*
Y1121522D03*
Y1124869D03*
Y1128215D03*
Y1131562D03*
Y1134908D03*
Y1138255D03*
Y1141601D03*
Y1144948D03*
Y1148294D03*
Y1151641D03*
Y1154987D03*
Y1158333D03*
Y1161680D03*
Y1165026D03*
Y1168373D03*
Y1171719D03*
Y1175066D03*
Y1178412D03*
Y1181759D03*
Y1185105D03*
Y1188452D03*
Y1191798D03*
Y1195144D03*
Y1198491D03*
Y1201837D03*
Y1205184D03*
Y1208530D03*
Y1211877D03*
Y1215223D03*
Y1218570D03*
Y1221916D03*
Y1225263D03*
Y1228609D03*
Y1231955D03*
Y1235302D03*
Y1238648D03*
Y1241995D03*
Y1245341D03*
Y1248688D03*
Y1252034D03*
Y1255381D03*
Y1258727D03*
Y1262074D03*
Y1265420D03*
X1617533Y766798D03*
Y770144D03*
Y773491D03*
Y776837D03*
Y780184D03*
Y783530D03*
Y786877D03*
Y790223D03*
Y793570D03*
Y796916D03*
Y800263D03*
Y803609D03*
Y806955D03*
Y810302D03*
Y813648D03*
Y816995D03*
Y820341D03*
Y823688D03*
Y827034D03*
Y830381D03*
Y833727D03*
Y837074D03*
Y840420D03*
Y843766D03*
Y847113D03*
Y850459D03*
Y853806D03*
Y857152D03*
Y860499D03*
Y863845D03*
Y867192D03*
Y870538D03*
Y873885D03*
Y877231D03*
Y880577D03*
Y883924D03*
Y887270D03*
Y890617D03*
Y893963D03*
Y897310D03*
Y900656D03*
Y904003D03*
Y907349D03*
Y910696D03*
Y914042D03*
Y917389D03*
Y920735D03*
Y924081D03*
Y927428D03*
Y930774D03*
Y934121D03*
Y937467D03*
Y940814D03*
Y944160D03*
Y947507D03*
Y950853D03*
Y954200D03*
Y957546D03*
Y960892D03*
Y964239D03*
Y967585D03*
Y970932D03*
Y974278D03*
Y977625D03*
Y980971D03*
Y984318D03*
Y987664D03*
Y991011D03*
Y994357D03*
Y1017782D03*
Y1021129D03*
Y1024475D03*
Y1027822D03*
Y1031168D03*
Y1034515D03*
Y1037861D03*
Y1041207D03*
Y1044554D03*
Y1047900D03*
Y1051247D03*
Y1054593D03*
Y1057940D03*
Y1061286D03*
Y1064633D03*
Y1067979D03*
Y1071326D03*
Y1074672D03*
Y1078018D03*
Y1081365D03*
Y1084711D03*
Y1088058D03*
Y1091404D03*
Y1094751D03*
Y1098097D03*
Y1101444D03*
Y1104790D03*
Y1108137D03*
Y1111483D03*
Y1114829D03*
Y1118176D03*
Y1121522D03*
Y1124869D03*
Y1128215D03*
Y1131562D03*
Y1134908D03*
Y1138255D03*
Y1141601D03*
Y1144948D03*
Y1148294D03*
Y1151641D03*
Y1154987D03*
Y1158333D03*
Y1161680D03*
Y1165026D03*
Y1168373D03*
Y1171719D03*
Y1175066D03*
Y1178412D03*
Y1181759D03*
Y1185105D03*
Y1188452D03*
Y1191798D03*
Y1195144D03*
Y1198491D03*
Y1201837D03*
Y1205184D03*
Y1208530D03*
Y1211877D03*
Y1215223D03*
Y1218570D03*
Y1221916D03*
Y1225263D03*
Y1228609D03*
Y1231955D03*
Y1235302D03*
Y1238648D03*
Y1241995D03*
Y1245341D03*
Y1248688D03*
Y1252034D03*
Y1255381D03*
Y1258727D03*
Y1262074D03*
Y1265420D03*
X1631091Y766798D03*
Y770144D03*
Y773491D03*
Y776837D03*
Y780184D03*
Y783530D03*
Y786877D03*
Y790223D03*
Y793570D03*
Y796916D03*
Y800263D03*
Y803609D03*
Y806955D03*
Y810302D03*
Y813648D03*
Y816995D03*
Y820341D03*
Y823688D03*
Y827034D03*
Y830381D03*
Y833727D03*
Y837074D03*
Y840420D03*
Y843766D03*
Y847113D03*
Y850459D03*
Y853806D03*
Y857152D03*
Y860499D03*
Y863845D03*
Y867192D03*
Y870538D03*
Y873885D03*
Y877231D03*
Y880577D03*
Y883924D03*
Y887270D03*
Y890617D03*
Y893963D03*
Y897310D03*
Y900656D03*
Y904003D03*
Y907349D03*
Y910696D03*
Y914042D03*
Y917389D03*
Y920735D03*
Y924081D03*
Y927428D03*
Y930774D03*
Y934121D03*
Y937467D03*
Y940814D03*
Y944160D03*
Y947507D03*
Y950853D03*
Y954200D03*
Y957546D03*
Y960892D03*
Y964239D03*
Y967585D03*
Y970932D03*
Y974278D03*
Y977625D03*
Y980971D03*
Y984318D03*
Y987664D03*
Y991011D03*
Y994357D03*
Y1017782D03*
Y1021129D03*
Y1024475D03*
Y1027822D03*
Y1031168D03*
Y1034515D03*
Y1037861D03*
Y1041207D03*
Y1044554D03*
Y1047900D03*
Y1051247D03*
Y1054593D03*
Y1057940D03*
Y1061286D03*
Y1064633D03*
Y1067979D03*
Y1071326D03*
Y1074672D03*
Y1078018D03*
Y1081365D03*
Y1084711D03*
Y1088058D03*
Y1091404D03*
Y1094751D03*
Y1098097D03*
Y1101444D03*
Y1104790D03*
Y1108137D03*
Y1111483D03*
Y1114829D03*
Y1118176D03*
Y1121522D03*
Y1124869D03*
Y1128215D03*
Y1131562D03*
Y1134908D03*
Y1138255D03*
Y1141601D03*
Y1144948D03*
Y1148294D03*
Y1151641D03*
Y1154987D03*
Y1158333D03*
Y1161680D03*
Y1165026D03*
Y1168373D03*
Y1171719D03*
Y1175066D03*
Y1178412D03*
Y1181759D03*
Y1185105D03*
Y1188452D03*
Y1191798D03*
Y1195144D03*
Y1198491D03*
Y1201837D03*
Y1205184D03*
Y1208530D03*
Y1211877D03*
Y1215223D03*
Y1218570D03*
Y1221916D03*
Y1225263D03*
Y1228609D03*
Y1231955D03*
Y1235302D03*
Y1238648D03*
Y1241995D03*
Y1245341D03*
Y1248688D03*
Y1252034D03*
Y1255381D03*
Y1258727D03*
Y1262074D03*
Y1265420D03*
X1647233Y766798D03*
Y770144D03*
Y773491D03*
Y776837D03*
Y780184D03*
Y783530D03*
Y786877D03*
Y790223D03*
Y793570D03*
Y796916D03*
Y800263D03*
Y803609D03*
Y806955D03*
Y810302D03*
Y813648D03*
Y816995D03*
Y820341D03*
Y823688D03*
Y827034D03*
Y830381D03*
Y833727D03*
Y837074D03*
Y840420D03*
Y843766D03*
Y847113D03*
Y850459D03*
Y853806D03*
Y857152D03*
Y860499D03*
Y863845D03*
Y867192D03*
Y870538D03*
Y873885D03*
Y877231D03*
Y880577D03*
Y883924D03*
Y887270D03*
Y890617D03*
Y893963D03*
Y897310D03*
Y900656D03*
Y904003D03*
Y907349D03*
Y910696D03*
Y914042D03*
Y917389D03*
Y920735D03*
Y924081D03*
Y927428D03*
Y930774D03*
Y934121D03*
Y937467D03*
Y940814D03*
Y944160D03*
Y947507D03*
Y950853D03*
Y954200D03*
Y957546D03*
Y960892D03*
Y964239D03*
Y967585D03*
Y970932D03*
Y974278D03*
Y977625D03*
Y980971D03*
Y984318D03*
Y987664D03*
Y991011D03*
Y994357D03*
Y1017782D03*
Y1021129D03*
Y1024475D03*
Y1027822D03*
Y1031168D03*
Y1034515D03*
Y1037861D03*
Y1041207D03*
Y1044554D03*
Y1047900D03*
Y1051247D03*
Y1054593D03*
Y1057940D03*
Y1061286D03*
Y1064633D03*
Y1067979D03*
Y1071326D03*
Y1074672D03*
Y1078018D03*
Y1081365D03*
Y1084711D03*
Y1088058D03*
Y1091404D03*
Y1094751D03*
Y1098097D03*
Y1101444D03*
Y1104790D03*
Y1108137D03*
Y1111483D03*
Y1114829D03*
Y1118176D03*
Y1121522D03*
Y1124869D03*
Y1128215D03*
Y1131562D03*
Y1134908D03*
Y1138255D03*
Y1141601D03*
Y1144948D03*
Y1148294D03*
Y1151641D03*
Y1154987D03*
Y1158333D03*
Y1161680D03*
Y1165026D03*
Y1168373D03*
Y1171719D03*
Y1175066D03*
Y1178412D03*
Y1181759D03*
Y1185105D03*
Y1188452D03*
Y1191798D03*
Y1195144D03*
Y1198491D03*
Y1201837D03*
Y1205184D03*
Y1208530D03*
Y1211877D03*
Y1215223D03*
Y1218570D03*
Y1221916D03*
Y1225263D03*
Y1228609D03*
Y1231955D03*
Y1235302D03*
Y1238648D03*
Y1241995D03*
Y1245341D03*
Y1248688D03*
Y1252034D03*
Y1255381D03*
Y1258727D03*
Y1262074D03*
Y1265420D03*
X1660791Y766798D03*
Y770144D03*
Y773491D03*
Y776837D03*
Y780184D03*
Y783530D03*
Y786877D03*
Y790223D03*
Y793570D03*
Y796916D03*
Y800263D03*
Y803609D03*
Y806955D03*
Y810302D03*
Y813648D03*
Y816995D03*
Y820341D03*
Y823688D03*
Y827034D03*
Y830381D03*
Y833727D03*
Y837074D03*
Y840420D03*
Y843766D03*
Y847113D03*
Y850459D03*
Y853806D03*
Y857152D03*
Y860499D03*
Y863845D03*
Y867192D03*
Y870538D03*
Y873885D03*
Y877231D03*
Y880577D03*
Y883924D03*
Y887270D03*
Y890617D03*
Y893963D03*
Y897310D03*
Y900656D03*
Y904003D03*
Y907349D03*
Y910696D03*
Y914042D03*
Y917389D03*
Y920735D03*
Y924081D03*
Y927428D03*
Y930774D03*
Y934121D03*
Y937467D03*
Y940814D03*
Y944160D03*
Y947507D03*
Y950853D03*
Y954200D03*
Y957546D03*
Y960892D03*
Y964239D03*
Y967585D03*
Y970932D03*
Y974278D03*
Y977625D03*
Y980971D03*
Y984318D03*
Y987664D03*
Y991011D03*
Y994357D03*
Y1017782D03*
Y1021129D03*
Y1024475D03*
Y1027822D03*
Y1031168D03*
Y1034515D03*
Y1037861D03*
Y1041207D03*
Y1044554D03*
Y1047900D03*
Y1051247D03*
Y1054593D03*
Y1057940D03*
Y1061286D03*
Y1064633D03*
Y1067979D03*
Y1071326D03*
Y1074672D03*
Y1078018D03*
Y1081365D03*
Y1084711D03*
Y1088058D03*
Y1091404D03*
Y1094751D03*
Y1098097D03*
Y1101444D03*
Y1104790D03*
Y1108137D03*
Y1111483D03*
Y1114829D03*
Y1118176D03*
Y1121522D03*
Y1124869D03*
Y1128215D03*
Y1131562D03*
Y1134908D03*
Y1138255D03*
Y1141601D03*
Y1144948D03*
Y1148294D03*
Y1151641D03*
Y1154987D03*
Y1158333D03*
Y1161680D03*
Y1165026D03*
Y1168373D03*
Y1171719D03*
Y1175066D03*
Y1178412D03*
Y1181759D03*
Y1185105D03*
Y1188452D03*
Y1191798D03*
Y1195144D03*
Y1198491D03*
Y1201837D03*
Y1205184D03*
Y1208530D03*
Y1211877D03*
Y1215223D03*
Y1218570D03*
Y1221916D03*
Y1225263D03*
Y1228609D03*
Y1231955D03*
Y1235302D03*
Y1238648D03*
Y1241995D03*
Y1245341D03*
Y1248688D03*
Y1252034D03*
Y1255381D03*
Y1258727D03*
Y1262074D03*
Y1265420D03*
X1690491Y766798D03*
Y770144D03*
X1676933Y766798D03*
Y770144D03*
X1690491Y773491D03*
Y776837D03*
Y780184D03*
Y783530D03*
Y786877D03*
X1676933Y773491D03*
Y776837D03*
Y780184D03*
Y783530D03*
Y786877D03*
X1690491Y790223D03*
Y793570D03*
Y796916D03*
Y800263D03*
Y803609D03*
X1676933Y790223D03*
Y793570D03*
Y796916D03*
Y800263D03*
Y803609D03*
X1690491Y806955D03*
Y810302D03*
Y813648D03*
Y816995D03*
Y820341D03*
X1676933Y806955D03*
Y810302D03*
Y813648D03*
Y816995D03*
Y820341D03*
X1690491Y823688D03*
Y827034D03*
Y830381D03*
Y833727D03*
X1676933Y823688D03*
Y827034D03*
Y830381D03*
Y833727D03*
X1690491Y837074D03*
Y840420D03*
Y843766D03*
Y847113D03*
Y850459D03*
X1676933Y837074D03*
Y840420D03*
Y843766D03*
Y847113D03*
Y850459D03*
X1690491Y853806D03*
Y857152D03*
Y860499D03*
Y863845D03*
Y867192D03*
X1676933Y853806D03*
Y857152D03*
Y860499D03*
Y863845D03*
Y867192D03*
X1690491Y870538D03*
Y873885D03*
Y877231D03*
Y880577D03*
Y883924D03*
X1676933Y870538D03*
Y873885D03*
Y877231D03*
Y880577D03*
Y883924D03*
X1690491Y887270D03*
Y890617D03*
Y893963D03*
Y897310D03*
Y900656D03*
X1676933Y887270D03*
Y890617D03*
Y893963D03*
Y897310D03*
Y900656D03*
X1690491Y904003D03*
Y907349D03*
Y910696D03*
Y914042D03*
Y917389D03*
X1676933Y904003D03*
Y907349D03*
Y910696D03*
Y914042D03*
Y917389D03*
X1690491Y920735D03*
Y924081D03*
Y927428D03*
Y930774D03*
Y934121D03*
X1676933Y920735D03*
Y924081D03*
Y927428D03*
Y930774D03*
Y934121D03*
X1690491Y937467D03*
Y940814D03*
Y944160D03*
Y947507D03*
X1676933Y937467D03*
Y940814D03*
Y944160D03*
Y947507D03*
X1690491Y950853D03*
Y954200D03*
Y957546D03*
Y960892D03*
Y964239D03*
X1676933Y950853D03*
Y954200D03*
Y957546D03*
Y960892D03*
Y964239D03*
X1690491Y967585D03*
Y970932D03*
Y974278D03*
Y977625D03*
Y980971D03*
X1676933Y967585D03*
Y970932D03*
Y974278D03*
Y977625D03*
Y980971D03*
X1690491Y984318D03*
Y987664D03*
Y991011D03*
Y994357D03*
X1676933Y984318D03*
Y987664D03*
Y991011D03*
Y994357D03*
X1690491Y1017782D03*
Y1021129D03*
Y1024475D03*
Y1027822D03*
Y1031168D03*
X1676933Y1017782D03*
Y1021129D03*
Y1024475D03*
Y1027822D03*
Y1031168D03*
X1690491Y1034515D03*
Y1037861D03*
Y1041207D03*
Y1044554D03*
Y1047900D03*
X1676933Y1034515D03*
Y1037861D03*
Y1041207D03*
Y1044554D03*
Y1047900D03*
X1690491Y1051247D03*
Y1054593D03*
Y1057940D03*
Y1061286D03*
X1676933Y1051247D03*
Y1054593D03*
Y1057940D03*
Y1061286D03*
X1690491Y1064633D03*
Y1067979D03*
Y1071326D03*
Y1074672D03*
Y1078018D03*
X1676933Y1064633D03*
Y1067979D03*
Y1071326D03*
Y1074672D03*
Y1078018D03*
X1690491Y1081365D03*
Y1084711D03*
Y1088058D03*
Y1091404D03*
Y1094751D03*
X1676933Y1081365D03*
Y1084711D03*
Y1088058D03*
Y1091404D03*
Y1094751D03*
X1690491Y1098097D03*
Y1101444D03*
Y1104790D03*
Y1108137D03*
Y1111483D03*
X1676933Y1098097D03*
Y1101444D03*
Y1104790D03*
Y1108137D03*
Y1111483D03*
X1690491Y1114829D03*
Y1118176D03*
Y1121522D03*
Y1124869D03*
Y1128215D03*
X1676933Y1114829D03*
Y1118176D03*
Y1121522D03*
Y1124869D03*
Y1128215D03*
X1690491Y1131562D03*
Y1134908D03*
Y1138255D03*
Y1141601D03*
Y1144948D03*
X1676933Y1131562D03*
Y1134908D03*
Y1138255D03*
Y1141601D03*
Y1144948D03*
X1690491Y1148294D03*
Y1151641D03*
Y1154987D03*
Y1158333D03*
Y1161680D03*
X1676933Y1148294D03*
Y1151641D03*
Y1154987D03*
Y1158333D03*
Y1161680D03*
X1690491Y1165026D03*
Y1168373D03*
Y1171719D03*
Y1175066D03*
X1676933Y1165026D03*
Y1168373D03*
Y1171719D03*
Y1175066D03*
X1690491Y1178412D03*
Y1181759D03*
Y1185105D03*
Y1188452D03*
Y1191798D03*
X1676933Y1178412D03*
Y1181759D03*
Y1185105D03*
Y1188452D03*
Y1191798D03*
X1690491Y1195144D03*
Y1198491D03*
Y1201837D03*
Y1205184D03*
Y1208530D03*
X1676933Y1195144D03*
Y1198491D03*
Y1201837D03*
Y1205184D03*
Y1208530D03*
X1690491Y1211877D03*
Y1215223D03*
Y1218570D03*
Y1221916D03*
Y1225263D03*
X1676933Y1211877D03*
Y1215223D03*
Y1218570D03*
Y1221916D03*
Y1225263D03*
X1690491Y1228609D03*
Y1231955D03*
Y1235302D03*
Y1238648D03*
Y1241995D03*
X1676933Y1228609D03*
Y1231955D03*
Y1235302D03*
Y1238648D03*
Y1241995D03*
X1690491Y1245341D03*
Y1248688D03*
Y1252034D03*
Y1255381D03*
Y1258727D03*
X1676933Y1245341D03*
Y1248688D03*
Y1252034D03*
Y1255381D03*
Y1258727D03*
X1690491Y1262074D03*
Y1265420D03*
X1676933Y1262074D03*
Y1265420D03*
X1706633Y766798D03*
Y770144D03*
Y773491D03*
Y776837D03*
Y780184D03*
Y783530D03*
Y786877D03*
Y790223D03*
Y793570D03*
Y796916D03*
Y800263D03*
Y803609D03*
Y806955D03*
Y810302D03*
Y813648D03*
Y816995D03*
Y820341D03*
Y823688D03*
Y827034D03*
Y830381D03*
Y833727D03*
Y837074D03*
Y840420D03*
Y843766D03*
Y847113D03*
Y850459D03*
Y853806D03*
Y857152D03*
Y860499D03*
Y863845D03*
Y867192D03*
Y870538D03*
Y873885D03*
Y877231D03*
Y880577D03*
Y883924D03*
Y887270D03*
Y890617D03*
Y893963D03*
Y897310D03*
Y900656D03*
Y904003D03*
Y907349D03*
Y910696D03*
Y914042D03*
Y917389D03*
Y920735D03*
Y924081D03*
Y927428D03*
Y930774D03*
Y934121D03*
Y937467D03*
Y940814D03*
Y944160D03*
Y947507D03*
Y950853D03*
Y954200D03*
Y957546D03*
Y960892D03*
Y964239D03*
Y967585D03*
Y970932D03*
Y974278D03*
Y977625D03*
Y980971D03*
Y984318D03*
Y987664D03*
Y991011D03*
Y994357D03*
Y1017782D03*
Y1021129D03*
Y1024475D03*
Y1027822D03*
Y1031168D03*
Y1034515D03*
Y1037861D03*
Y1041207D03*
Y1044554D03*
Y1047900D03*
Y1051247D03*
Y1054593D03*
Y1057940D03*
Y1061286D03*
Y1064633D03*
Y1067979D03*
Y1071326D03*
Y1074672D03*
Y1078018D03*
Y1081365D03*
Y1084711D03*
Y1088058D03*
Y1091404D03*
Y1094751D03*
Y1098097D03*
Y1101444D03*
Y1104790D03*
Y1108137D03*
Y1111483D03*
Y1114829D03*
Y1118176D03*
Y1121522D03*
Y1124869D03*
Y1128215D03*
Y1131562D03*
Y1134908D03*
Y1138255D03*
Y1141601D03*
Y1144948D03*
Y1148294D03*
Y1151641D03*
Y1154987D03*
Y1158333D03*
Y1161680D03*
Y1165026D03*
Y1168373D03*
Y1171719D03*
Y1175066D03*
Y1178412D03*
Y1181759D03*
Y1185105D03*
Y1188452D03*
Y1191798D03*
Y1195144D03*
Y1198491D03*
Y1201837D03*
Y1205184D03*
Y1208530D03*
Y1211877D03*
Y1215223D03*
Y1218570D03*
Y1221916D03*
Y1225263D03*
Y1228609D03*
Y1231955D03*
Y1235302D03*
Y1238648D03*
Y1241995D03*
Y1245341D03*
Y1248688D03*
Y1252034D03*
Y1255381D03*
Y1258727D03*
Y1262074D03*
Y1265420D03*
X1720191Y766798D03*
Y770144D03*
Y773491D03*
Y776837D03*
Y780184D03*
Y783530D03*
Y786877D03*
Y790223D03*
Y793570D03*
Y796916D03*
Y800263D03*
Y803609D03*
Y806955D03*
Y810302D03*
Y813648D03*
Y816995D03*
Y820341D03*
Y823688D03*
Y827034D03*
Y830381D03*
Y833727D03*
Y837074D03*
Y840420D03*
Y843766D03*
Y847113D03*
Y850459D03*
Y853806D03*
Y857152D03*
Y860499D03*
Y863845D03*
Y867192D03*
Y870538D03*
Y873885D03*
Y877231D03*
Y880577D03*
Y883924D03*
Y887270D03*
Y890617D03*
Y893963D03*
Y897310D03*
Y900656D03*
Y904003D03*
Y907349D03*
Y910696D03*
Y914042D03*
Y917389D03*
Y920735D03*
Y924081D03*
Y927428D03*
Y930774D03*
Y934121D03*
Y937467D03*
Y940814D03*
Y944160D03*
Y947507D03*
Y950853D03*
Y954200D03*
Y957546D03*
Y960892D03*
Y964239D03*
Y967585D03*
Y970932D03*
Y974278D03*
Y977625D03*
Y980971D03*
Y984318D03*
Y987664D03*
Y991011D03*
Y994357D03*
Y1017782D03*
Y1021129D03*
Y1024475D03*
Y1027822D03*
Y1031168D03*
Y1034515D03*
Y1037861D03*
Y1041207D03*
Y1044554D03*
Y1047900D03*
Y1051247D03*
Y1054593D03*
Y1057940D03*
Y1061286D03*
Y1064633D03*
Y1067979D03*
Y1071326D03*
Y1074672D03*
Y1078018D03*
Y1081365D03*
Y1084711D03*
Y1088058D03*
Y1091404D03*
Y1094751D03*
Y1098097D03*
Y1101444D03*
Y1104790D03*
Y1108137D03*
Y1111483D03*
Y1114829D03*
Y1118176D03*
Y1121522D03*
Y1124869D03*
Y1128215D03*
Y1131562D03*
Y1134908D03*
Y1138255D03*
Y1141601D03*
Y1144948D03*
Y1148294D03*
Y1151641D03*
Y1154987D03*
Y1158333D03*
Y1161680D03*
Y1165026D03*
Y1168373D03*
Y1171719D03*
Y1175066D03*
Y1178412D03*
Y1181759D03*
Y1185105D03*
Y1188452D03*
Y1191798D03*
Y1195144D03*
Y1198491D03*
Y1201837D03*
Y1205184D03*
Y1208530D03*
Y1211877D03*
Y1215223D03*
Y1218570D03*
Y1221916D03*
Y1225263D03*
Y1228609D03*
Y1231955D03*
Y1235302D03*
Y1238648D03*
Y1241995D03*
Y1245341D03*
Y1248688D03*
Y1252034D03*
Y1255381D03*
Y1258727D03*
Y1262074D03*
Y1265420D03*
X1736333Y766798D03*
Y770144D03*
Y773491D03*
Y776837D03*
Y780184D03*
Y783530D03*
Y786877D03*
Y790223D03*
Y793570D03*
Y796916D03*
Y800263D03*
Y803609D03*
Y806955D03*
Y810302D03*
Y813648D03*
Y816995D03*
Y820341D03*
Y823688D03*
Y827034D03*
Y830381D03*
Y833727D03*
Y837074D03*
Y840420D03*
Y843766D03*
Y847113D03*
Y850459D03*
Y853806D03*
Y857152D03*
Y860499D03*
Y863845D03*
Y867192D03*
Y870538D03*
Y873885D03*
Y877231D03*
Y880577D03*
Y883924D03*
Y887270D03*
Y890617D03*
Y893963D03*
Y897310D03*
Y900656D03*
Y904003D03*
Y907349D03*
Y910696D03*
Y914042D03*
Y917389D03*
Y920735D03*
Y924081D03*
Y927428D03*
Y930774D03*
Y934121D03*
Y937467D03*
Y940814D03*
Y944160D03*
Y947507D03*
Y950853D03*
Y954200D03*
Y957546D03*
Y960892D03*
Y964239D03*
Y967585D03*
Y970932D03*
Y974278D03*
Y977625D03*
Y980971D03*
Y984318D03*
Y987664D03*
Y991011D03*
Y994357D03*
Y1017782D03*
Y1021129D03*
Y1024475D03*
Y1027822D03*
Y1031168D03*
Y1034515D03*
Y1037861D03*
Y1041207D03*
Y1044554D03*
Y1047900D03*
Y1051247D03*
Y1054593D03*
Y1057940D03*
Y1061286D03*
Y1064633D03*
Y1067979D03*
Y1071326D03*
Y1074672D03*
Y1078018D03*
Y1081365D03*
Y1084711D03*
Y1088058D03*
Y1091404D03*
Y1094751D03*
Y1098097D03*
Y1101444D03*
Y1104790D03*
Y1108137D03*
Y1111483D03*
Y1114829D03*
Y1118176D03*
Y1121522D03*
Y1124869D03*
Y1128215D03*
Y1131562D03*
Y1134908D03*
Y1138255D03*
Y1141601D03*
Y1144948D03*
Y1148294D03*
Y1151641D03*
Y1154987D03*
Y1158333D03*
Y1161680D03*
Y1165026D03*
Y1168373D03*
Y1171719D03*
Y1175066D03*
Y1178412D03*
Y1181759D03*
Y1185105D03*
Y1188452D03*
Y1191798D03*
Y1195144D03*
Y1198491D03*
Y1201837D03*
Y1205184D03*
Y1208530D03*
Y1211877D03*
Y1215223D03*
Y1218570D03*
Y1221916D03*
Y1225263D03*
Y1228609D03*
Y1231955D03*
Y1235302D03*
Y1238648D03*
Y1241995D03*
Y1245341D03*
Y1248688D03*
Y1252034D03*
Y1255381D03*
Y1258727D03*
Y1262074D03*
Y1265420D03*
X1749891Y766798D03*
Y770144D03*
Y773491D03*
Y776837D03*
Y780184D03*
Y783530D03*
Y786877D03*
Y790223D03*
Y793570D03*
Y796916D03*
Y800263D03*
Y803609D03*
Y806955D03*
Y810302D03*
Y813648D03*
Y816995D03*
Y820341D03*
Y823688D03*
Y827034D03*
Y830381D03*
Y833727D03*
Y837074D03*
Y840420D03*
Y843766D03*
Y847113D03*
Y850459D03*
Y853806D03*
Y857152D03*
Y860499D03*
Y863845D03*
Y867192D03*
Y870538D03*
Y873885D03*
Y877231D03*
Y880577D03*
Y883924D03*
Y887270D03*
Y890617D03*
Y893963D03*
Y897310D03*
Y900656D03*
Y904003D03*
Y907349D03*
Y910696D03*
Y914042D03*
Y917389D03*
Y920735D03*
Y924081D03*
Y927428D03*
Y930774D03*
Y934121D03*
Y937467D03*
Y940814D03*
Y944160D03*
Y947507D03*
Y950853D03*
Y954200D03*
Y957546D03*
Y960892D03*
Y964239D03*
Y967585D03*
Y970932D03*
Y974278D03*
Y977625D03*
Y980971D03*
Y984318D03*
Y987664D03*
Y991011D03*
Y994357D03*
Y1017782D03*
Y1021129D03*
Y1024475D03*
Y1027822D03*
Y1031168D03*
Y1034515D03*
Y1037861D03*
Y1041207D03*
Y1044554D03*
Y1047900D03*
Y1051247D03*
Y1054593D03*
Y1057940D03*
Y1061286D03*
Y1064633D03*
Y1067979D03*
Y1071326D03*
Y1074672D03*
Y1078018D03*
Y1081365D03*
Y1084711D03*
Y1088058D03*
Y1091404D03*
Y1094751D03*
Y1098097D03*
Y1101444D03*
Y1104790D03*
Y1108137D03*
Y1111483D03*
Y1114829D03*
Y1118176D03*
Y1121522D03*
Y1124869D03*
Y1128215D03*
Y1131562D03*
Y1134908D03*
Y1138255D03*
Y1141601D03*
Y1144948D03*
Y1148294D03*
Y1151641D03*
Y1154987D03*
Y1158333D03*
Y1161680D03*
Y1165026D03*
Y1168373D03*
Y1171719D03*
Y1175066D03*
Y1178412D03*
Y1181759D03*
Y1185105D03*
Y1188452D03*
Y1191798D03*
Y1195144D03*
Y1198491D03*
Y1201837D03*
Y1205184D03*
Y1208530D03*
Y1211877D03*
Y1215223D03*
Y1218570D03*
Y1221916D03*
Y1225263D03*
Y1228609D03*
Y1231955D03*
Y1235302D03*
Y1238648D03*
Y1241995D03*
Y1245341D03*
Y1248688D03*
Y1252034D03*
Y1255381D03*
Y1258727D03*
Y1262074D03*
Y1265420D03*
X1766033Y766798D03*
Y770144D03*
Y773491D03*
Y776837D03*
Y780184D03*
Y783530D03*
Y786877D03*
Y790223D03*
Y793570D03*
Y796916D03*
Y800263D03*
Y803609D03*
Y806955D03*
Y810302D03*
Y813648D03*
Y816995D03*
Y820341D03*
Y823688D03*
Y827034D03*
Y830381D03*
Y833727D03*
Y837074D03*
Y840420D03*
Y843766D03*
Y847113D03*
Y850459D03*
Y853806D03*
Y857152D03*
Y860499D03*
Y863845D03*
Y867192D03*
Y870538D03*
Y873885D03*
Y877231D03*
Y880577D03*
Y883924D03*
Y887270D03*
Y890617D03*
Y893963D03*
Y897310D03*
Y900656D03*
Y904003D03*
Y907349D03*
Y910696D03*
Y914042D03*
Y917389D03*
Y920735D03*
Y924081D03*
Y927428D03*
Y930774D03*
Y934121D03*
Y937467D03*
Y940814D03*
Y944160D03*
Y947507D03*
Y950853D03*
Y954200D03*
Y957546D03*
Y960892D03*
Y964239D03*
Y967585D03*
Y970932D03*
Y974278D03*
Y977625D03*
Y980971D03*
Y984318D03*
Y987664D03*
Y991011D03*
Y994357D03*
Y1017782D03*
Y1021129D03*
Y1024475D03*
Y1027822D03*
Y1031168D03*
Y1034515D03*
Y1037861D03*
Y1041207D03*
Y1044554D03*
Y1047900D03*
Y1051247D03*
Y1054593D03*
Y1057940D03*
Y1061286D03*
Y1064633D03*
Y1067979D03*
Y1071326D03*
Y1074672D03*
Y1078018D03*
Y1081365D03*
Y1084711D03*
Y1088058D03*
Y1091404D03*
Y1094751D03*
Y1098097D03*
Y1101444D03*
Y1104790D03*
Y1108137D03*
Y1111483D03*
Y1114829D03*
Y1118176D03*
Y1121522D03*
Y1124869D03*
Y1128215D03*
Y1131562D03*
Y1134908D03*
Y1138255D03*
Y1141601D03*
Y1144948D03*
Y1148294D03*
Y1151641D03*
Y1154987D03*
Y1158333D03*
Y1161680D03*
Y1165026D03*
Y1168373D03*
Y1171719D03*
Y1175066D03*
Y1178412D03*
Y1181759D03*
Y1185105D03*
Y1188452D03*
Y1191798D03*
Y1195144D03*
Y1198491D03*
Y1201837D03*
Y1205184D03*
Y1208530D03*
Y1211877D03*
Y1215223D03*
Y1218570D03*
Y1221916D03*
Y1225263D03*
Y1228609D03*
Y1231955D03*
Y1235302D03*
Y1238648D03*
Y1241995D03*
Y1245341D03*
Y1248688D03*
Y1252034D03*
Y1255381D03*
Y1258727D03*
Y1262074D03*
Y1265420D03*
X1779591Y766798D03*
Y770144D03*
Y773491D03*
Y776837D03*
Y780184D03*
Y783530D03*
Y786877D03*
Y790223D03*
Y793570D03*
Y796916D03*
Y800263D03*
Y803609D03*
Y806955D03*
Y810302D03*
Y813648D03*
Y816995D03*
Y820341D03*
Y823688D03*
Y827034D03*
Y830381D03*
Y833727D03*
Y837074D03*
Y840420D03*
Y843766D03*
Y847113D03*
Y850459D03*
Y853806D03*
Y857152D03*
Y860499D03*
Y863845D03*
Y867192D03*
Y870538D03*
Y873885D03*
Y877231D03*
Y880577D03*
Y883924D03*
Y887270D03*
Y890617D03*
Y893963D03*
Y897310D03*
Y900656D03*
Y904003D03*
Y907349D03*
Y910696D03*
Y914042D03*
Y917389D03*
Y920735D03*
Y924081D03*
Y927428D03*
Y930774D03*
Y934121D03*
Y937467D03*
Y940814D03*
Y944160D03*
Y947507D03*
Y950853D03*
Y954200D03*
Y957546D03*
Y960892D03*
Y964239D03*
Y967585D03*
Y970932D03*
Y974278D03*
Y977625D03*
Y980971D03*
Y984318D03*
Y987664D03*
Y991011D03*
Y994357D03*
Y1017782D03*
Y1021129D03*
Y1024475D03*
Y1027822D03*
Y1031168D03*
Y1034515D03*
Y1037861D03*
Y1041207D03*
Y1044554D03*
Y1047900D03*
Y1051247D03*
Y1054593D03*
Y1057940D03*
Y1061286D03*
Y1064633D03*
Y1067979D03*
Y1071326D03*
Y1074672D03*
Y1078018D03*
Y1081365D03*
Y1084711D03*
Y1088058D03*
Y1091404D03*
Y1094751D03*
Y1098097D03*
Y1101444D03*
Y1104790D03*
Y1108137D03*
Y1111483D03*
Y1114829D03*
Y1118176D03*
Y1121522D03*
Y1124869D03*
Y1128215D03*
Y1131562D03*
Y1134908D03*
Y1138255D03*
Y1141601D03*
Y1144948D03*
Y1148294D03*
Y1151641D03*
Y1154987D03*
Y1158333D03*
Y1161680D03*
Y1165026D03*
Y1168373D03*
Y1171719D03*
Y1175066D03*
Y1178412D03*
Y1181759D03*
Y1185105D03*
Y1188452D03*
Y1191798D03*
Y1195144D03*
Y1198491D03*
Y1201837D03*
Y1205184D03*
Y1208530D03*
Y1211877D03*
Y1215223D03*
Y1218570D03*
Y1221916D03*
Y1225263D03*
Y1228609D03*
Y1231955D03*
Y1235302D03*
Y1238648D03*
Y1241995D03*
Y1245341D03*
Y1248688D03*
Y1252034D03*
Y1255381D03*
Y1258727D03*
Y1262074D03*
Y1265420D03*
X1795733Y766798D03*
Y770144D03*
Y773491D03*
Y776837D03*
Y780184D03*
Y783530D03*
Y786877D03*
Y790223D03*
Y793570D03*
Y796916D03*
Y800263D03*
Y803609D03*
Y806955D03*
Y810302D03*
Y813648D03*
Y816995D03*
Y820341D03*
Y823688D03*
Y827034D03*
Y830381D03*
Y833727D03*
Y837074D03*
Y840420D03*
Y843766D03*
Y847113D03*
Y850459D03*
Y853806D03*
Y857152D03*
Y860499D03*
Y863845D03*
Y867192D03*
Y870538D03*
Y873885D03*
Y877231D03*
Y880577D03*
Y883924D03*
Y887270D03*
Y890617D03*
Y893963D03*
Y897310D03*
Y900656D03*
Y904003D03*
Y907349D03*
Y910696D03*
Y914042D03*
Y917389D03*
Y920735D03*
Y924081D03*
Y927428D03*
Y930774D03*
Y934121D03*
Y937467D03*
Y940814D03*
Y944160D03*
Y947507D03*
Y950853D03*
Y954200D03*
Y957546D03*
Y960892D03*
Y964239D03*
Y967585D03*
Y970932D03*
Y974278D03*
Y977625D03*
Y980971D03*
Y984318D03*
Y987664D03*
Y991011D03*
Y994357D03*
Y1017782D03*
Y1021129D03*
Y1024475D03*
Y1027822D03*
Y1031168D03*
Y1034515D03*
Y1037861D03*
Y1041207D03*
Y1044554D03*
Y1047900D03*
Y1051247D03*
Y1054593D03*
Y1057940D03*
Y1061286D03*
Y1064633D03*
Y1067979D03*
Y1071326D03*
Y1074672D03*
Y1078018D03*
Y1081365D03*
Y1084711D03*
Y1088058D03*
Y1091404D03*
Y1094751D03*
Y1098097D03*
Y1101444D03*
Y1104790D03*
Y1108137D03*
Y1111483D03*
Y1114829D03*
Y1118176D03*
Y1121522D03*
Y1124869D03*
Y1128215D03*
Y1131562D03*
Y1134908D03*
Y1138255D03*
Y1141601D03*
Y1144948D03*
Y1148294D03*
Y1151641D03*
Y1154987D03*
Y1158333D03*
Y1161680D03*
Y1165026D03*
Y1168373D03*
Y1171719D03*
Y1175066D03*
Y1178412D03*
Y1181759D03*
Y1185105D03*
Y1188452D03*
Y1191798D03*
Y1195144D03*
Y1198491D03*
Y1201837D03*
Y1205184D03*
Y1208530D03*
Y1211877D03*
Y1215223D03*
Y1218570D03*
Y1221916D03*
Y1225263D03*
Y1228609D03*
Y1231955D03*
Y1235302D03*
Y1238648D03*
Y1241995D03*
Y1245341D03*
Y1248688D03*
Y1252034D03*
Y1255381D03*
Y1258727D03*
Y1262074D03*
Y1265420D03*
X1809291Y766798D03*
Y770144D03*
Y773491D03*
Y776837D03*
Y780184D03*
Y783530D03*
Y786877D03*
Y790223D03*
Y793570D03*
Y796916D03*
Y800263D03*
Y803609D03*
Y806955D03*
Y810302D03*
Y813648D03*
Y816995D03*
Y820341D03*
Y823688D03*
Y827034D03*
Y830381D03*
Y833727D03*
Y837074D03*
Y840420D03*
Y843766D03*
Y847113D03*
Y850459D03*
Y853806D03*
Y857152D03*
Y860499D03*
Y863845D03*
Y867192D03*
Y870538D03*
Y873885D03*
Y877231D03*
Y880577D03*
Y883924D03*
Y887270D03*
Y890617D03*
Y893963D03*
Y897310D03*
Y900656D03*
Y904003D03*
Y907349D03*
Y910696D03*
Y914042D03*
Y917389D03*
Y920735D03*
Y924081D03*
Y927428D03*
Y930774D03*
Y934121D03*
Y937467D03*
Y940814D03*
Y944160D03*
Y947507D03*
Y950853D03*
Y954200D03*
Y957546D03*
Y960892D03*
Y964239D03*
Y967585D03*
Y970932D03*
Y974278D03*
Y977625D03*
Y980971D03*
Y984318D03*
Y987664D03*
Y991011D03*
Y994357D03*
Y1017782D03*
Y1021129D03*
Y1024475D03*
Y1027822D03*
Y1031168D03*
Y1034515D03*
Y1037861D03*
Y1041207D03*
Y1044554D03*
Y1047900D03*
Y1051247D03*
Y1054593D03*
Y1057940D03*
Y1061286D03*
Y1064633D03*
Y1067979D03*
Y1071326D03*
Y1074672D03*
Y1078018D03*
Y1081365D03*
Y1084711D03*
Y1088058D03*
Y1091404D03*
Y1094751D03*
Y1098097D03*
Y1101444D03*
Y1104790D03*
Y1108137D03*
Y1111483D03*
Y1114829D03*
Y1118176D03*
Y1121522D03*
Y1124869D03*
Y1128215D03*
Y1131562D03*
Y1134908D03*
Y1138255D03*
Y1141601D03*
Y1144948D03*
Y1148294D03*
Y1151641D03*
Y1154987D03*
Y1158333D03*
Y1161680D03*
Y1165026D03*
Y1168373D03*
Y1171719D03*
Y1175066D03*
Y1178412D03*
Y1181759D03*
Y1185105D03*
Y1188452D03*
Y1191798D03*
Y1195144D03*
Y1198491D03*
Y1201837D03*
Y1205184D03*
Y1208530D03*
Y1211877D03*
Y1215223D03*
Y1218570D03*
Y1221916D03*
Y1225263D03*
Y1228609D03*
Y1231955D03*
Y1235302D03*
Y1238648D03*
Y1241995D03*
Y1245341D03*
Y1248688D03*
Y1252034D03*
Y1255381D03*
Y1258727D03*
Y1262074D03*
Y1265420D03*
X1825433Y766798D03*
Y770144D03*
Y773491D03*
Y776837D03*
Y780184D03*
Y783530D03*
Y786877D03*
Y790223D03*
Y793570D03*
Y796916D03*
Y800263D03*
Y803609D03*
Y806955D03*
Y810302D03*
Y813648D03*
Y816995D03*
Y820341D03*
Y823688D03*
Y827034D03*
Y830381D03*
Y833727D03*
Y837074D03*
Y840420D03*
Y843766D03*
Y847113D03*
Y850459D03*
Y853806D03*
Y857152D03*
Y860499D03*
Y863845D03*
Y867192D03*
Y870538D03*
Y873885D03*
Y877231D03*
Y880577D03*
Y883924D03*
Y887270D03*
Y890617D03*
Y893963D03*
Y897310D03*
Y900656D03*
Y904003D03*
Y907349D03*
Y910696D03*
Y914042D03*
Y917389D03*
Y920735D03*
Y924081D03*
Y927428D03*
Y930774D03*
Y934121D03*
Y937467D03*
Y940814D03*
Y944160D03*
Y947507D03*
Y950853D03*
Y954200D03*
Y957546D03*
Y960892D03*
Y964239D03*
Y967585D03*
Y970932D03*
Y974278D03*
Y977625D03*
Y980971D03*
Y984318D03*
Y987664D03*
Y991011D03*
Y994357D03*
Y1017782D03*
Y1021129D03*
Y1024475D03*
Y1027822D03*
Y1031168D03*
Y1034515D03*
Y1037861D03*
Y1041207D03*
Y1044554D03*
Y1047900D03*
Y1051247D03*
Y1054593D03*
Y1057940D03*
Y1061286D03*
Y1064633D03*
Y1067979D03*
Y1071326D03*
Y1074672D03*
Y1078018D03*
Y1081365D03*
Y1084711D03*
Y1088058D03*
Y1091404D03*
Y1094751D03*
Y1098097D03*
Y1101444D03*
Y1104790D03*
Y1108137D03*
Y1111483D03*
Y1114829D03*
Y1118176D03*
Y1121522D03*
Y1124869D03*
Y1128215D03*
Y1131562D03*
Y1134908D03*
Y1138255D03*
Y1141601D03*
Y1144948D03*
Y1148294D03*
Y1151641D03*
Y1154987D03*
Y1158333D03*
Y1161680D03*
Y1165026D03*
Y1168373D03*
Y1171719D03*
Y1175066D03*
Y1178412D03*
Y1181759D03*
Y1185105D03*
Y1188452D03*
Y1191798D03*
Y1195144D03*
Y1198491D03*
Y1201837D03*
Y1205184D03*
Y1208530D03*
Y1211877D03*
Y1215223D03*
Y1218570D03*
Y1221916D03*
Y1225263D03*
Y1228609D03*
Y1231955D03*
Y1235302D03*
Y1238648D03*
Y1241995D03*
Y1245341D03*
Y1248688D03*
Y1252034D03*
Y1255381D03*
Y1258727D03*
Y1262074D03*
Y1265420D03*
G54D38*
X53701Y1631013D03*
Y1654045D03*
X82637Y1631013D03*
Y1654045D03*
G54D257*
X1100097Y1650635D03*
X1096357D03*
X1092617D03*
Y1661265D03*
X1096357D03*
X1100097D03*
G54D266*
X1212643Y228495D03*
X1210084D03*
X1207525D03*
Y236369D03*
X1210084D03*
X1212643D03*
X1313919Y81133D03*
Y89007D03*
X1329891Y72577D03*
X1327332D03*
X1324773D03*
Y80451D03*
X1327332D03*
X1329891D03*
X1319037Y81133D03*
X1316478D03*
Y89007D03*
X1319037D03*
G54D185*
X611000Y491201D03*
Y503799D03*
X627000Y491201D03*
X619000D03*
X627000Y503799D03*
X619000D03*
X635000Y491201D03*
Y503799D03*
G54D194*
X709692Y177187D03*
X711792D03*
X709692Y173587D03*
X711792D03*
X709692Y185587D03*
X711792D03*
X709692Y189187D03*
X711792D03*
X709692Y197087D03*
X711792D03*
X709692Y200687D03*
X711792D03*
X709692Y212521D03*
X711792D03*
X709692Y208921D03*
X711792D03*
X940496Y211897D03*
Y215497D03*
Y204775D03*
Y208375D03*
Y229635D03*
Y226035D03*
X942596Y211897D03*
Y215497D03*
Y204775D03*
Y208375D03*
Y229635D03*
Y226035D03*
X947196Y222548D03*
X949296D03*
X947196Y218948D03*
X949296D03*
X1375400Y249262D03*
X1373300D03*
X1375400Y245662D03*
X1373300D03*
X1379624Y238551D03*
Y242151D03*
X1374916Y263736D03*
X1372816D03*
X1374916Y260136D03*
X1372816D03*
X1375121Y272170D03*
X1373021D03*
X1375121Y268570D03*
X1373021D03*
X1381724Y238551D03*
Y242151D03*
X1385600Y257303D03*
X1383500D03*
X1385600Y253703D03*
X1383500D03*
G54D293*
X1645030Y185952D03*
X1641290Y196188D03*
X1648770D03*
G54D56*
X88406Y708379D03*
X1701838Y712505D03*
G54D74*
X112578Y517044D03*
X115704Y635278D03*
X1662285Y543813D03*
X1702700Y498681D03*
G54D47*
X81899Y631160D03*
Y637060D03*
X138469Y539903D03*
Y534003D03*
X397819Y1403108D03*
Y1408908D03*
X455434Y1398569D03*
Y1404469D03*
X651490Y220802D03*
Y226602D03*
X656926Y220797D03*
Y226597D03*
X982385Y213233D03*
Y207433D03*
X987285D03*
Y213233D03*
X1047371Y367937D03*
Y373737D03*
X1133220Y1612190D03*
Y1606390D03*
X1431575Y1398569D03*
Y1404469D03*
X1542018Y298126D03*
Y303926D03*
X1690028Y566600D03*
Y560700D03*
X1750847Y280163D03*
X1745000Y290962D03*
Y296762D03*
X1750500Y296962D03*
X1750847Y285963D03*
X1750500Y302762D03*
X1830852Y1503991D03*
Y1509791D03*
G54D83*
X144883Y1725289D03*
Y1727848D03*
Y1730408D03*
Y1732967D03*
X170829Y1707678D03*
Y1710237D03*
Y1712797D03*
Y1715356D03*
X162461Y1730408D03*
Y1727848D03*
Y1725289D03*
Y1732967D03*
X188407Y1712797D03*
Y1710237D03*
Y1707678D03*
Y1715356D03*
X1422534Y1562932D03*
Y1565491D03*
Y1568051D03*
Y1570610D03*
X1440112Y1568051D03*
Y1565491D03*
Y1562932D03*
Y1570610D03*
G54D167*
X467150Y1422842D03*
X463410Y1431504D03*
X470890D03*
X854820Y430793D03*
X858560Y422131D03*
X851080D03*
X1067070Y365631D03*
X1059590D03*
X1063330Y374293D03*
X1443482Y1423962D03*
X1439742Y1432624D03*
X1447222D03*
G54D92*
X154193Y1392019D03*
Y1393791D03*
Y1395563D03*
Y1397334D03*
Y1399106D03*
Y1400878D03*
X192336Y1392019D03*
Y1393791D03*
Y1395563D03*
Y1397334D03*
Y1399106D03*
Y1400878D03*
X204723Y574220D03*
Y590165D03*
Y588394D03*
Y586622D03*
Y584850D03*
Y583079D03*
Y575992D03*
Y577764D03*
Y579535D03*
Y581307D03*
Y608220D03*
Y624165D03*
Y622394D03*
Y620622D03*
Y618850D03*
Y617079D03*
Y609992D03*
Y611764D03*
Y613535D03*
Y615307D03*
Y656394D03*
Y654622D03*
Y652850D03*
Y651079D03*
Y642220D03*
Y643992D03*
Y645764D03*
Y647535D03*
Y649307D03*
Y658165D03*
X280741Y151850D03*
Y153819D03*
Y155787D03*
Y157756D03*
X291765Y151850D03*
Y157756D03*
Y155787D03*
Y153819D03*
X308176Y1350165D03*
Y1351937D03*
Y1353709D03*
Y1355480D03*
Y1357252D03*
Y1359024D03*
X340304Y1327367D03*
Y1329139D03*
Y1330911D03*
Y1332682D03*
Y1334454D03*
Y1336226D03*
X372432Y1313941D03*
Y1315713D03*
Y1317485D03*
Y1319256D03*
Y1321028D03*
Y1322800D03*
X404560Y1313941D03*
Y1315713D03*
Y1317485D03*
Y1319256D03*
Y1321028D03*
Y1322800D03*
X436688Y1313941D03*
Y1315713D03*
Y1317485D03*
Y1319256D03*
Y1321028D03*
Y1322800D03*
X468816Y1313941D03*
Y1315713D03*
Y1317485D03*
Y1319256D03*
Y1321028D03*
Y1322800D03*
X500944Y1327367D03*
Y1329139D03*
Y1330911D03*
Y1332682D03*
Y1334454D03*
Y1336226D03*
X533072Y1350165D03*
Y1351937D03*
Y1353709D03*
Y1355480D03*
Y1357252D03*
Y1359024D03*
X595644Y203025D03*
Y204994D03*
Y206962D03*
Y208931D03*
X606668D03*
Y206962D03*
Y204994D03*
Y203025D03*
X667812Y1392044D03*
Y1393816D03*
Y1395588D03*
Y1397359D03*
Y1399131D03*
Y1400903D03*
X705955Y1392044D03*
Y1393816D03*
Y1395588D03*
Y1397359D03*
Y1399131D03*
Y1400903D03*
X818002Y133945D03*
Y135914D03*
Y137882D03*
Y139851D03*
X829026Y135914D03*
Y133945D03*
Y139851D03*
Y137882D03*
X841967Y211438D03*
Y213407D03*
Y215375D03*
Y217344D03*
X852991D03*
Y215375D03*
Y213407D03*
Y211438D03*
X1127504Y1428348D03*
Y1430120D03*
Y1431892D03*
Y1433663D03*
Y1435435D03*
Y1437207D03*
X1165647Y1428348D03*
Y1430120D03*
Y1431892D03*
Y1433663D03*
Y1435435D03*
Y1437207D03*
X1180193Y1628173D03*
Y1626204D03*
Y1624236D03*
Y1622267D03*
X1169169D03*
Y1624236D03*
Y1626204D03*
Y1628173D03*
X1284437Y1350401D03*
Y1352173D03*
Y1353945D03*
Y1355716D03*
Y1357488D03*
Y1359260D03*
X1316445Y1327367D03*
Y1329139D03*
Y1330911D03*
Y1332682D03*
Y1334454D03*
Y1336226D03*
X1348573Y1313941D03*
Y1315713D03*
Y1317485D03*
Y1319256D03*
Y1321028D03*
Y1322800D03*
X1380701Y1313941D03*
Y1315713D03*
Y1317485D03*
Y1319256D03*
Y1321028D03*
Y1322800D03*
X1412829Y1313941D03*
Y1315713D03*
Y1317485D03*
Y1319256D03*
Y1321028D03*
Y1322800D03*
X1444957Y1313941D03*
Y1315713D03*
Y1317485D03*
Y1319256D03*
Y1321028D03*
Y1322800D03*
X1477085Y1327367D03*
Y1329139D03*
Y1330911D03*
Y1332682D03*
Y1334454D03*
Y1336226D03*
X1509213Y1350165D03*
Y1351937D03*
Y1353709D03*
Y1355480D03*
Y1357252D03*
Y1359024D03*
X1628978Y1425640D03*
Y1427412D03*
Y1429184D03*
Y1430955D03*
Y1432727D03*
Y1434499D03*
X1649250Y630417D03*
Y632188D03*
Y633960D03*
Y635732D03*
Y637503D03*
Y639275D03*
Y646362D03*
Y644590D03*
Y642818D03*
Y641047D03*
Y664417D03*
Y666188D03*
Y667960D03*
Y669732D03*
Y671503D03*
Y673275D03*
Y680362D03*
Y678590D03*
Y676818D03*
Y675047D03*
Y698417D03*
Y700188D03*
Y701960D03*
Y703732D03*
Y705503D03*
Y714362D03*
Y712590D03*
Y710818D03*
Y709047D03*
Y707275D03*
X1667121Y1425640D03*
Y1427412D03*
Y1429184D03*
Y1430955D03*
Y1432727D03*
Y1434499D03*
X1729480Y367431D03*
Y369400D03*
Y371368D03*
Y373337D03*
X1740504D03*
Y371368D03*
Y369400D03*
Y367431D03*
G54D284*
X1316569Y268316D03*
Y275008D03*
X1325231Y268316D03*
Y275008D03*
G54D239*
X963586Y1600926D03*
Y1607042D03*
X995198Y1600942D03*
Y1607058D03*
X1026798Y1600942D03*
Y1607058D03*
X1058398Y1600942D03*
Y1607058D03*
G54D149*
X370890Y1627042D03*
X368331D03*
Y1634522D03*
X370890D03*
X373449Y1627042D03*
Y1634522D03*
X380668Y1664844D03*
X378109D03*
X375550D03*
Y1672324D03*
X378109D03*
X380668D03*
X448079Y1552197D03*
X445520D03*
X442961D03*
Y1559677D03*
X445520D03*
X448079D03*
X462079Y1562197D03*
X459520D03*
X456961D03*
Y1569677D03*
X459520D03*
X462079D03*
X459779Y1599255D03*
X457220D03*
X454661D03*
Y1606735D03*
X457220D03*
X459779D03*
X600351Y472248D03*
X602910D03*
X605469D03*
Y464768D03*
X602910D03*
X600351D03*
X656877Y504277D03*
X654318D03*
X651759D03*
Y511757D03*
X654318D03*
X656877D03*
X1150704Y222677D03*
Y230157D03*
X1158382Y197407D03*
X1155823D03*
X1153264D03*
Y204887D03*
X1155823D03*
X1158382D03*
X1155822Y222677D03*
X1153263D03*
Y230157D03*
X1155822D03*
X1163789Y1665575D03*
X1161230D03*
X1158671D03*
Y1673055D03*
X1161230D03*
X1163789D03*
X1183230Y1665575D03*
X1180671D03*
X1174789D03*
X1172230D03*
X1169671D03*
X1180671Y1673055D03*
X1183230D03*
X1169671D03*
X1172230D03*
X1174789D03*
X1196459Y1665885D03*
X1193900D03*
X1191341D03*
X1185789Y1665575D03*
X1191341Y1673365D03*
X1193900D03*
X1196459D03*
X1185789Y1673055D03*
X1196199Y1711365D03*
X1193640D03*
X1191081D03*
Y1718845D03*
X1193640D03*
X1196199D03*
X1215210Y1711675D03*
X1212651D03*
X1206969Y1711410D03*
X1204410D03*
X1201851D03*
X1212651Y1719155D03*
X1215210D03*
X1201851Y1718890D03*
X1204410D03*
X1206969D03*
X1217769Y1711675D03*
Y1719155D03*
G54D248*
X994322Y382138D03*
Y384107D03*
Y386075D03*
Y388044D03*
Y390013D03*
Y391981D03*
Y393949D03*
Y395918D03*
Y397887D03*
Y399855D03*
Y401824D03*
X1018928Y395918D03*
Y393949D03*
Y391981D03*
Y390013D03*
Y388044D03*
Y386075D03*
Y384107D03*
Y382138D03*
Y401824D03*
Y399855D03*
Y397887D03*
G54D158*
X418813Y1401470D03*
Y1424108D03*
X434561Y1401470D03*
X432986D03*
X431411D03*
X429836D03*
X428261D03*
X426687D03*
X425112D03*
X423537D03*
X421962D03*
X420387D03*
Y1424108D03*
X421962D03*
X423537D03*
X425112D03*
X426687D03*
X428261D03*
X429836D03*
X431411D03*
X432986D03*
X434561D03*
X436135Y1401470D03*
Y1424108D03*
X1394954Y1401470D03*
Y1424108D03*
X1410702Y1401470D03*
X1409127D03*
X1407552D03*
X1405977D03*
X1404402D03*
X1402828D03*
X1401253D03*
X1399678D03*
X1398103D03*
X1396528D03*
Y1424108D03*
X1398103D03*
X1399678D03*
X1401253D03*
X1402828D03*
X1404402D03*
X1405977D03*
X1407552D03*
X1409127D03*
X1410702D03*
X1412276Y1401470D03*
Y1424108D03*
G54D176*
X489626Y1417955D03*
X1465767D03*
G54D65*
X86274Y1538094D03*
G54D285*
X1388056Y1415546D03*
G54D276*
X1283688Y129742D03*
G54D294*
X1651534Y604566D03*
G54D57*
X87225Y712316D03*
X1700657Y716442D03*
G54D93*
X157323Y1545001D03*
G54D258*
X1109429Y364235D03*
Y369235D03*
Y374235D03*
Y379235D03*
X1129901Y364235D03*
Y379235D03*
Y374235D03*
Y369235D03*
G54D168*
X478316Y152187D03*
Y147069D03*
X471316D03*
Y149628D03*
Y152187D03*
G54D39*
X65933Y32756D03*
X68295D03*
X70657D03*
X73020D03*
X75382D03*
X77744D03*
X65933Y44370D03*
X68295D03*
X70657D03*
X73020D03*
X75382D03*
X77744D03*
X80106Y32756D03*
X82468D03*
X84831D03*
X87193D03*
X89555D03*
X91917D03*
X94279D03*
X80106Y44370D03*
X82468D03*
X84831D03*
X87193D03*
X89555D03*
X91917D03*
X94279D03*
X96642Y32756D03*
X99004D03*
X101366D03*
X103728D03*
X106090D03*
X108453D03*
X110815D03*
X96642Y44370D03*
X99004D03*
X101366D03*
X103728D03*
X106090D03*
X108453D03*
X110815D03*
X113177Y32756D03*
X115539D03*
X117902D03*
X120264D03*
X122626D03*
X124988D03*
X127350D03*
X113177Y44370D03*
X115539D03*
X117902D03*
X120264D03*
X122626D03*
X124988D03*
X127350D03*
X129713Y32756D03*
Y44370D03*
X149043Y32756D03*
X151405D03*
X153768D03*
X156130D03*
X158492D03*
X149043Y44370D03*
X151405D03*
X153768D03*
X156130D03*
X158492D03*
X160854Y32756D03*
X163216D03*
X165579D03*
X167941D03*
X170303D03*
X172665D03*
X175028D03*
X160854Y44370D03*
X163216D03*
X165579D03*
X167941D03*
X170303D03*
X172665D03*
X175028D03*
X177390Y32756D03*
X179752D03*
X177390Y44370D03*
X179752D03*
X195539Y32756D03*
X197902D03*
X200264D03*
X202626D03*
X204988D03*
X207350D03*
X195539Y44370D03*
X197902D03*
X200264D03*
X202626D03*
X204988D03*
X207350D03*
X209713Y32756D03*
X212075D03*
X214437D03*
X216799D03*
X219161D03*
X221524D03*
X223886D03*
X209713Y44370D03*
X212075D03*
X214437D03*
X216799D03*
X219161D03*
X221524D03*
X223886D03*
X226248Y32756D03*
X228610D03*
X230972D03*
X233335D03*
X235697D03*
X238059D03*
X240421D03*
X226248Y44370D03*
X228610D03*
X230972D03*
X233335D03*
X235697D03*
X238059D03*
X240421D03*
X242783Y32756D03*
X245146D03*
X247508D03*
X249870D03*
X252232D03*
X254594D03*
X256957D03*
X242783Y44370D03*
X245146D03*
X247508D03*
X249870D03*
X252232D03*
X254594D03*
X256957D03*
X259319Y32756D03*
Y44370D03*
X276622Y32756D03*
X278984D03*
X281346D03*
X283709D03*
X286071D03*
X288433D03*
X276622Y44370D03*
X278984D03*
X281346D03*
X283709D03*
X286071D03*
X288433D03*
X290795Y32756D03*
X293157D03*
X295520D03*
X297882D03*
X300244D03*
X302606D03*
X304968D03*
X290795Y44370D03*
X293157D03*
X295520D03*
X297882D03*
X300244D03*
X302606D03*
X304968D03*
X307331Y32756D03*
Y44370D03*
X510815Y53544D03*
X513177D03*
X515539D03*
X510815Y65158D03*
X513177D03*
X515539D03*
X517902Y53544D03*
X520264D03*
X522626D03*
X524988D03*
X527350D03*
X529713D03*
X532075D03*
X517902Y65158D03*
X520264D03*
X522626D03*
X524988D03*
X527350D03*
X529713D03*
X532075D03*
X534437Y53544D03*
X536799D03*
X539161D03*
X541524D03*
X543886D03*
X546248D03*
X548610D03*
X534437Y65158D03*
X536799D03*
X539161D03*
X541524D03*
X543886D03*
X546248D03*
X548610D03*
X550972Y53544D03*
X553335D03*
X555697D03*
X558059D03*
X560421D03*
X562784D03*
X565146D03*
X550972Y65158D03*
X553335D03*
X555697D03*
X558059D03*
X560421D03*
X562784D03*
X565146D03*
X567508Y53544D03*
X569870D03*
X572232D03*
X574595D03*
X567508Y65158D03*
X569870D03*
X572232D03*
X574595D03*
X593925Y53544D03*
X596287D03*
X598650D03*
X593925Y65158D03*
X596287D03*
X598650D03*
X601012Y53544D03*
X603374D03*
X605736D03*
X608098D03*
X610461D03*
X612823D03*
X615185D03*
X601012Y65158D03*
X603374D03*
X605736D03*
X608098D03*
X610461D03*
X612823D03*
X615185D03*
X617547Y53544D03*
X619910D03*
X622272D03*
X624634D03*
X617547Y65158D03*
X619910D03*
X622272D03*
X624634D03*
X640421Y53544D03*
X642784D03*
X645146D03*
X647508D03*
X640421Y65158D03*
X642784D03*
X645146D03*
X647508D03*
X649870Y53544D03*
X652232D03*
X654595D03*
X656957D03*
X659319D03*
X661681D03*
X664043D03*
X649870Y65158D03*
X652232D03*
X654595D03*
X656957D03*
X659319D03*
X661681D03*
X664043D03*
X666406Y53544D03*
X668768D03*
X671130D03*
X673492D03*
X675854D03*
X678217D03*
X666406Y65158D03*
X668768D03*
X671130D03*
X673492D03*
X675854D03*
X678217D03*
X680579Y53544D03*
X682941D03*
X685303D03*
X687665D03*
X690028D03*
X692390D03*
X694752D03*
X680579Y65158D03*
X682941D03*
X685303D03*
X687665D03*
X690028D03*
X692390D03*
X694752D03*
X697114Y53544D03*
X699476D03*
X701839D03*
X704201D03*
X697114Y65158D03*
X699476D03*
X701839D03*
X704201D03*
X721504Y53544D03*
X723866D03*
X726228D03*
X728591D03*
X721504Y65158D03*
X723866D03*
X726228D03*
X728591D03*
X730953Y53544D03*
X733315D03*
X735677D03*
X738039D03*
X740402D03*
X742764D03*
X745126D03*
X730953Y65158D03*
X733315D03*
X735677D03*
X738039D03*
X740402D03*
X742764D03*
X745126D03*
X747488Y53544D03*
X749850D03*
X752213D03*
X747488Y65158D03*
X749850D03*
X752213D03*
X1540342Y32756D03*
Y44370D03*
X1542704Y32756D03*
X1545066D03*
X1547429D03*
X1549791D03*
X1552153D03*
X1554515D03*
X1556877D03*
X1542704Y44370D03*
X1545066D03*
X1547429D03*
X1549791D03*
X1552153D03*
X1554515D03*
X1556877D03*
X1559240Y32756D03*
X1561602D03*
X1563964D03*
X1566326D03*
X1568688D03*
X1571051D03*
X1573413D03*
X1559240Y44370D03*
X1561602D03*
X1563964D03*
X1566326D03*
X1568688D03*
X1571051D03*
X1573413D03*
X1575775Y32756D03*
X1578137D03*
X1580499D03*
X1582862D03*
X1585224D03*
X1587586D03*
X1589948D03*
X1575775Y44370D03*
X1578137D03*
X1580499D03*
X1582862D03*
X1585224D03*
X1587586D03*
X1589948D03*
X1592311Y32756D03*
X1594673D03*
X1597035D03*
X1599397D03*
X1601759D03*
X1604122D03*
X1592311Y44370D03*
X1594673D03*
X1597035D03*
X1599397D03*
X1601759D03*
X1604122D03*
X1623452Y32756D03*
Y44370D03*
X1625814Y32756D03*
X1628177D03*
X1630539D03*
X1632901D03*
X1635263D03*
X1637625D03*
X1639988D03*
X1625814Y44370D03*
X1628177D03*
X1630539D03*
X1632901D03*
X1635263D03*
X1637625D03*
X1639988D03*
X1642350Y32756D03*
X1644712D03*
X1647074D03*
X1649437D03*
X1651799D03*
X1654161D03*
X1642350Y44370D03*
X1644712D03*
X1647074D03*
X1649437D03*
X1651799D03*
X1654161D03*
X1669948Y32756D03*
X1672311D03*
X1669948Y44370D03*
X1672311D03*
X1674673Y32756D03*
X1677035D03*
X1679397D03*
X1681759D03*
X1684122D03*
X1686484D03*
X1688846D03*
X1674673Y44370D03*
X1677035D03*
X1679397D03*
X1681759D03*
X1684122D03*
X1686484D03*
X1688846D03*
X1691208Y32756D03*
X1693570D03*
X1695933D03*
X1698295D03*
X1700657D03*
X1703019D03*
X1691208Y44370D03*
X1693570D03*
X1695933D03*
X1698295D03*
X1700657D03*
X1703019D03*
X1705381Y32756D03*
X1707744D03*
X1710106D03*
X1712468D03*
X1714830D03*
X1717192D03*
X1719555D03*
X1705381Y44370D03*
X1707744D03*
X1710106D03*
X1712468D03*
X1714830D03*
X1717192D03*
X1719555D03*
X1721917Y32756D03*
X1724279D03*
X1726641D03*
X1729003D03*
X1731366D03*
X1733728D03*
X1721917Y44370D03*
X1724279D03*
X1726641D03*
X1729003D03*
X1731366D03*
X1733728D03*
X1751031Y32756D03*
X1753393D03*
X1751031Y44370D03*
X1753393D03*
X1755755Y32756D03*
X1758118D03*
X1760480D03*
X1762842D03*
X1765204D03*
X1767566D03*
X1769929D03*
X1755755Y44370D03*
X1758118D03*
X1760480D03*
X1762842D03*
X1765204D03*
X1767566D03*
X1769929D03*
X1772291Y32756D03*
X1774653D03*
X1777015D03*
X1779377D03*
X1781740D03*
X1772291Y44370D03*
X1774653D03*
X1777015D03*
X1779377D03*
X1781740D03*
G54D267*
X1247638Y269488D03*
X1405118Y112008D03*
X1766929Y1714960D03*
G54D186*
X615480Y520299D03*
X629480Y512425D03*
X619220D03*
X622960Y520299D03*
X633220D03*
X636960Y512425D03*
X759289Y143438D03*
X763029Y151312D03*
X766769Y143438D03*
X805480Y425425D03*
X809220Y433299D03*
X812960Y425425D03*
X1194713Y118101D03*
X1198453Y110227D03*
X1190973D03*
X1656896Y187187D03*
X1660636Y179313D03*
X1664376Y187187D03*
G54D75*
X109696Y639477D03*
X108122D03*
X106547D03*
X104972D03*
X103397D03*
X101822D03*
Y658375D03*
X103397D03*
X104972D03*
X106547D03*
X108122D03*
X109696D03*
X125438Y500919D03*
X123863D03*
X122288D03*
X120713D03*
X119138D03*
Y519817D03*
X120713D03*
X122288D03*
X123863D03*
X125438D03*
X115996Y639477D03*
X114421D03*
X112846D03*
X111271D03*
Y658375D03*
X112846D03*
X114421D03*
X115996D03*
X133312Y500919D03*
X131737D03*
X130162D03*
X128587D03*
X127012D03*
Y519817D03*
X128587D03*
X130162D03*
X131737D03*
X133312D03*
X1672067Y527616D03*
X1670492D03*
X1668917D03*
Y546514D03*
X1670492D03*
X1672067D03*
X1683091Y527616D03*
X1681516D03*
X1679941D03*
X1678366D03*
X1676791D03*
X1675217D03*
X1673642D03*
Y546514D03*
X1675217D03*
X1676791D03*
X1678366D03*
X1679941D03*
X1681516D03*
X1683091D03*
X1703547Y474758D03*
X1701973D03*
X1700398D03*
X1698823D03*
X1697248D03*
X1695673D03*
Y493656D03*
X1697248D03*
X1698823D03*
X1700398D03*
X1701973D03*
X1703547D03*
X1709847Y474758D03*
X1708272D03*
X1706697D03*
X1705122D03*
Y493656D03*
X1706697D03*
X1708272D03*
X1709847D03*
G54D177*
X489429Y1406538D03*
Y1408112D03*
Y1409687D03*
Y1411262D03*
Y1412837D03*
Y1414412D03*
Y1415986D03*
X1465570Y1406538D03*
Y1408112D03*
Y1409687D03*
Y1411262D03*
Y1412837D03*
Y1414412D03*
Y1415986D03*
G54D159*
X416155Y1404128D03*
Y1405702D03*
Y1407277D03*
Y1408852D03*
Y1410427D03*
Y1412002D03*
Y1413576D03*
Y1415151D03*
Y1416726D03*
Y1418301D03*
Y1419876D03*
Y1421450D03*
X438793Y1404128D03*
Y1421450D03*
Y1419876D03*
Y1418301D03*
Y1416726D03*
Y1415151D03*
Y1413576D03*
Y1412002D03*
Y1410427D03*
Y1408852D03*
Y1407277D03*
Y1405702D03*
X1392296Y1404128D03*
Y1405702D03*
Y1407277D03*
Y1408852D03*
Y1410427D03*
Y1412002D03*
Y1413576D03*
Y1415151D03*
Y1416726D03*
Y1418301D03*
Y1419876D03*
Y1421450D03*
X1414934Y1404128D03*
Y1421450D03*
Y1419876D03*
Y1418301D03*
Y1416726D03*
Y1415151D03*
Y1413576D03*
Y1412002D03*
Y1410427D03*
Y1408852D03*
Y1407277D03*
Y1405702D03*
G54D249*
X1006625Y391981D03*
G54D66*
X79187Y1543015D03*
G54D48*
X94705Y704442D03*
X1708137Y708568D03*
G54D195*
X717110Y-11500D03*
X834070Y18500D03*
X1026502Y-21511D03*
Y-1511D03*
Y18489D03*
X1335821Y-21511D03*
Y-1511D03*
Y18489D03*
G54D84*
X159474Y1320753D03*
X183847Y1320778D03*
X208247D03*
X275289Y575702D03*
Y599861D03*
Y624015D03*
Y648169D03*
X278126Y676260D03*
Y700414D03*
X395771Y1242785D03*
X420171D03*
X444493D03*
X468893D03*
X493293D03*
X676508Y224606D03*
X673093Y1320778D03*
X697466Y1320803D03*
X721866D03*
X1100800Y251488D03*
X1100700Y275788D03*
X1131100Y1357088D03*
X1155500D03*
X1179900D03*
X1371912Y1242785D03*
X1396312D03*
X1420634D03*
X1445034D03*
X1469434D03*
X1577000Y591888D03*
Y616388D03*
Y640888D03*
Y665288D03*
Y689788D03*
Y714288D03*
X1634259Y1354374D03*
X1658632Y1354399D03*
X1683032D03*
G54D268*
X1265107Y54022D03*
Y62422D03*
X1272587Y54022D03*
Y62422D03*
G54D67*
X80762Y1543015D03*
X82337D03*
X83912D03*
X85487D03*
X87061D03*
X88636D03*
X90211D03*
X91786D03*
G54D286*
X1511063Y299780D03*
X1515393Y297812D03*
Y301748D03*
G54D196*
X720360Y-12484D03*
Y-10516D03*
X837320Y17516D03*
Y19484D03*
X983580Y-10516D03*
Y-12484D03*
Y19484D03*
Y17516D03*
X1029752Y-22495D03*
Y-20527D03*
Y-2495D03*
Y-527D03*
Y17505D03*
Y19473D03*
X1292972Y-20527D03*
Y-22495D03*
Y-527D03*
Y-2495D03*
Y19473D03*
Y17505D03*
X1339071Y-22495D03*
Y-20527D03*
Y-2495D03*
Y-527D03*
Y17505D03*
Y19473D03*
X1485331Y-20527D03*
Y-22495D03*
Y-527D03*
Y-2495D03*
Y19473D03*
Y17505D03*
X1759327Y286919D03*
G54D76*
X99460Y641839D03*
Y643414D03*
Y644989D03*
Y646564D03*
Y648139D03*
Y649713D03*
Y651288D03*
Y652863D03*
Y654438D03*
Y656013D03*
X116776Y503281D03*
Y504856D03*
Y506431D03*
Y508006D03*
Y509581D03*
Y511155D03*
Y512730D03*
Y514305D03*
Y515880D03*
Y517455D03*
X118358Y656013D03*
Y654438D03*
Y652863D03*
Y651288D03*
Y649713D03*
Y648139D03*
Y646564D03*
Y644989D03*
Y643414D03*
Y641839D03*
X135674Y509581D03*
Y508006D03*
Y506431D03*
Y504856D03*
Y503281D03*
Y517455D03*
Y515880D03*
Y514305D03*
Y512730D03*
Y511155D03*
X1666555Y529978D03*
Y531553D03*
Y533128D03*
Y534703D03*
Y536278D03*
Y537852D03*
Y539427D03*
Y541002D03*
Y542577D03*
Y544152D03*
X1685453Y542577D03*
Y541002D03*
Y539427D03*
Y537852D03*
Y536278D03*
Y534703D03*
Y533128D03*
Y531553D03*
Y529978D03*
Y544152D03*
X1693311Y477120D03*
Y478695D03*
Y480270D03*
Y481845D03*
Y483420D03*
Y484994D03*
Y486569D03*
Y488144D03*
Y489719D03*
Y491294D03*
X1712209Y477120D03*
Y491294D03*
Y489719D03*
Y488144D03*
Y486569D03*
Y484994D03*
Y483420D03*
Y481845D03*
Y480270D03*
Y478695D03*
G54D85*
X163677Y1344383D03*
Y1370367D03*
X201777Y1344383D03*
Y1370367D03*
X677296Y1344408D03*
Y1370392D03*
X715396Y1344408D03*
Y1370392D03*
X1136988Y1380712D03*
Y1406696D03*
X1175088Y1380712D03*
Y1406696D03*
X1638462Y1378004D03*
Y1403988D03*
X1676562Y1378004D03*
Y1403988D03*
G54D277*
X1289620Y135702D03*
G54D49*
X91949Y702670D03*
X1705381Y706796D03*
G54D169*
X473500Y246362D03*
X498563Y607067D03*
X520000Y278543D03*
X549236Y1441207D03*
X688500Y1621900D03*
X1041435Y163357D03*
X1056225Y163131D03*
X1099970Y1722570D03*
X1679646Y175669D03*
X1771457Y1624646D03*
G54D178*
X494926Y1432143D03*
Y1455173D03*
X1471404Y1431721D03*
Y1454751D03*
G54D295*
X1643670Y602634D03*
G54D259*
X1131715Y1532913D03*
X1175215D03*
G54D187*
X640246Y197466D03*
Y221966D03*
X791526Y125647D03*
Y150147D03*
X882183Y213783D03*
Y238283D03*
G54D58*
X84430Y1310256D03*
X1093936Y1591739D03*
X1769097Y1308506D03*
G54D94*
X158307Y1537521D03*
X156339D03*
X154370D03*
X152402D03*
Y1552481D03*
X154370D03*
X156339D03*
X158307D03*
X162244Y1537521D03*
X160276D03*
Y1552481D03*
X162244D03*
G54D77*
X108909Y648926D03*
X126225Y510368D03*
X1676004Y537065D03*
X1702760Y484207D03*
G54D197*
X724465Y1581092D03*
Y1589950D03*
G54D188*
X646505Y1665405D03*
X643945D03*
X641386D03*
Y1682983D03*
X643945D03*
X646505D03*
X649064Y1665405D03*
Y1682983D03*
X711558Y1651562D03*
X708999D03*
X706439D03*
X703880D03*
Y1669140D03*
X706439D03*
X708999D03*
X711558D03*
G54D59*
X84430Y1311831D03*
Y1333091D03*
X1093936Y1593314D03*
Y1614574D03*
X1769097Y1310081D03*
Y1331341D03*
G54D179*
X518430Y291864D03*
Y305446D03*
G54D95*
X149843Y1540080D03*
Y1542048D03*
Y1544017D03*
Y1545985D03*
Y1547954D03*
Y1549922D03*
X164803D03*
Y1547954D03*
Y1545985D03*
Y1544017D03*
Y1542048D03*
Y1540080D03*
G54D287*
X1526675Y136146D03*
X1534155D03*
X1530415Y145202D03*
G54D68*
X93361Y1543015D03*
G54D278*
X1287521Y133603D03*
G54D86*
X159474Y1328627D03*
X183847Y1328652D03*
X208247D03*
X275289Y583576D03*
Y607735D03*
Y631889D03*
Y656043D03*
X270252Y676260D03*
Y700414D03*
X387897Y1242785D03*
X412297D03*
X436619D03*
X461019D03*
X485419D03*
X673093Y1328652D03*
X697466Y1328677D03*
X721866D03*
X1100800Y259362D03*
X1100700Y283662D03*
X1131100Y1364962D03*
X1155500D03*
X1179900D03*
X1364038Y1242785D03*
X1388438D03*
X1412760D03*
X1437160D03*
X1461560D03*
X1577000Y599762D03*
Y624262D03*
Y648762D03*
Y673162D03*
Y697662D03*
Y722162D03*
X1634259Y1362248D03*
X1658632Y1362273D03*
X1683032D03*
G54D269*
X1276480Y118820D03*
X1269520Y125780D03*
G54D296*
X1683921Y386516D03*
X1708421D03*
G54D69*
X95132Y1541244D03*
G54D288*
X1543444Y195866D03*
Y197834D03*
Y199803D03*
Y201771D03*
Y203740D03*
Y205708D03*
Y207677D03*
Y209645D03*
Y211614D03*
Y213582D03*
Y215551D03*
Y217519D03*
Y219488D03*
Y221456D03*
Y223425D03*
Y225393D03*
Y227362D03*
Y229330D03*
Y231299D03*
Y233267D03*
Y235236D03*
Y237204D03*
Y239173D03*
Y241141D03*
Y243110D03*
Y245078D03*
Y247047D03*
Y249015D03*
Y250984D03*
Y252952D03*
X1566004Y195866D03*
Y197834D03*
Y199803D03*
Y201771D03*
Y203740D03*
Y205708D03*
Y207677D03*
Y209645D03*
Y211614D03*
Y213582D03*
Y215551D03*
Y217519D03*
Y219488D03*
Y221456D03*
Y223425D03*
Y225393D03*
Y227362D03*
Y229330D03*
Y231299D03*
Y233267D03*
Y235236D03*
Y237204D03*
Y239173D03*
Y241141D03*
Y243110D03*
Y245078D03*
Y247047D03*
Y249015D03*
Y250984D03*
Y252952D03*
G54D96*
X170014Y230928D03*
X166274D03*
X241354Y278685D03*
X232494D03*
X228754D03*
X240624Y311334D03*
X231764D03*
X228024D03*
X245094Y278685D03*
X257694D03*
X253954D03*
X244364Y311334D03*
X256964D03*
X253224D03*
X270294Y278685D03*
X266554D03*
X269564Y311334D03*
X265824D03*
X282894Y278685D03*
X279154D03*
X282164Y311334D03*
X278424D03*
X295494Y278685D03*
X291754D03*
X304354D03*
X294764Y311334D03*
X291024D03*
X303624D03*
X320694Y278685D03*
X316954D03*
X308094D03*
X319964Y311334D03*
X316224D03*
X307364D03*
X333294Y278685D03*
X329554D03*
X332564Y311334D03*
X328824D03*
X345894Y278685D03*
X342154D03*
X354754D03*
X345164Y311334D03*
X341424D03*
X354024D03*
X358494Y278685D03*
X371094D03*
X367354D03*
X370364Y311334D03*
X366624D03*
X357764D03*
X383694Y278685D03*
X379954D03*
X382964Y311334D03*
X379224D03*
X396294Y278685D03*
X392554D03*
X395564Y311334D03*
X391824D03*
X408894Y278685D03*
X405154D03*
X417754D03*
X408164Y311334D03*
X404424D03*
X417024D03*
X435654Y278715D03*
X431914D03*
X421494Y278685D03*
X420764Y311334D03*
X433364D03*
X429624D03*
X445964D03*
X442224D03*
X863450Y437462D03*
X867190D03*
X1453670Y281190D03*
X1449930D03*
G54D198*
X719199Y1579320D03*
Y1581092D03*
Y1582864D03*
Y1584635D03*
Y1586407D03*
Y1588178D03*
Y1589950D03*
Y1591722D03*
X744691Y1582864D03*
Y1581092D03*
Y1579320D03*
Y1591722D03*
Y1589950D03*
Y1588178D03*
Y1586407D03*
Y1584635D03*
G54D78*
X109608Y707039D03*
X132638D03*
X1473922Y298220D03*
X1496952D03*
X1723150Y708355D03*
X1746180D03*
G54D189*
X676508Y145866D03*
X1881720Y988279D03*
X1886720Y1001463D03*
X1876720D03*
X1875836Y1303980D03*
X1885836D03*
X1880836Y1317164D03*
X1881211Y1350983D03*
X1886211Y1364167D03*
X1876211D03*
X1876165Y1669023D03*
X1886165D03*
X1881165Y1682207D03*
X1902608Y988322D03*
X1897608Y1001506D03*
X1898086Y1305044D03*
X1903086Y1318228D03*
X1902682Y1351295D03*
X1897682Y1364479D03*
X1902402Y1683256D03*
X1897402Y1670072D03*
X1907608Y1001506D03*
X1908086Y1305044D03*
X1907682Y1364479D03*
X1907402Y1670072D03*
X1930200Y1349548D03*
X1935200Y1362732D03*
X1925200D03*
X1929695Y1683220D03*
X1924695Y1670036D03*
X1934695D03*
X1951178Y1349597D03*
X1946178Y1362781D03*
X1950484Y1683497D03*
X1945484Y1670313D03*
X1967697Y1362790D03*
X1956178Y1362781D03*
X1966555Y1669946D03*
X1955484Y1670313D03*
X1972697Y1349606D03*
X1977697Y1362790D03*
X1976555Y1669946D03*
X1971555Y1683130D03*
X1993618Y1349897D03*
X1988618Y1363081D03*
X1998618D03*
X1998147Y1669691D03*
X1988147D03*
X1993147Y1682875D03*
G54D87*
X163642Y1380504D03*
X201785D03*
X317625Y1338650D03*
X349753Y1315852D03*
X381881Y1302426D03*
X414009D03*
X446137D03*
X478265D03*
X510393Y1315852D03*
X542521Y1338650D03*
X677261Y1380529D03*
X715404D03*
X1136953Y1416833D03*
X1175096D03*
X1293886Y1338886D03*
X1325894Y1315852D03*
X1358022Y1302426D03*
X1390150D03*
X1422278D03*
X1454406D03*
X1486534Y1315852D03*
X1518662Y1338650D03*
X1638427Y1414125D03*
X1676570D03*
G54D279*
X1285767Y150750D03*
X1288347Y148170D03*
X1290927D03*
X1285767Y153329D03*
X1290927Y233328D03*
X1294866D03*
X1288347Y230748D03*
X1285767Y228169D03*
Y224230D03*
X1357888Y148170D03*
X1361827D03*
X1357888Y233328D03*
X1361827D03*
X1366987Y150750D03*
X1364407Y148170D03*
X1366987Y157268D03*
Y153329D03*
X1364407Y233328D03*
X1366987Y230748D03*
Y228169D03*
Y224230D03*
G54D297*
X1726412Y217580D03*
G54D88*
X163642Y1387393D03*
X201785D03*
X317625Y1345539D03*
X349753Y1322741D03*
X381881Y1309315D03*
X414009D03*
X446137D03*
X478265D03*
X510393Y1322741D03*
X542521Y1345539D03*
X677261Y1387418D03*
X715404D03*
X1136953Y1423722D03*
X1175096D03*
X1293886Y1345775D03*
X1325894Y1322741D03*
X1358022Y1309315D03*
X1390150D03*
X1422278D03*
X1454406D03*
X1486534Y1322741D03*
X1518662Y1345539D03*
X1638427Y1421014D03*
X1676570D03*
G54D199*
X728402Y1576712D03*
X726630D03*
X724858D03*
X723087D03*
X721315D03*
Y1594330D03*
X723087D03*
X724858D03*
X726630D03*
X728402D03*
X742575Y1576712D03*
X740803D03*
X739032D03*
X737260D03*
X735488D03*
X733717D03*
X731945D03*
X730173D03*
Y1594330D03*
X731945D03*
X733717D03*
X735488D03*
X737260D03*
X739032D03*
X740803D03*
X742575D03*
G54D298*
X1710959Y210080D03*
Y215080D03*
Y220080D03*
Y225080D03*
G54D79*
X106818Y1586793D03*
Y1589352D03*
Y1591911D03*
Y1598572D03*
Y1617262D03*
Y1601131D03*
Y1603690D03*
Y1619821D03*
Y1622380D03*
Y1635303D03*
Y1637862D03*
Y1640421D03*
X114298Y1591911D03*
Y1589352D03*
Y1586793D03*
Y1598572D03*
Y1617262D03*
Y1603690D03*
Y1601131D03*
Y1622380D03*
Y1619821D03*
Y1640421D03*
Y1637862D03*
Y1635303D03*
X242215Y144320D03*
Y146879D03*
Y149438D03*
X249695D03*
Y146879D03*
Y144320D03*
X249735Y160162D03*
Y157603D03*
Y155044D03*
X242255D03*
Y157603D03*
Y160162D03*
X333174Y363143D03*
Y375364D03*
Y377923D03*
Y380482D03*
Y365702D03*
Y368261D03*
X340654Y363143D03*
Y380482D03*
Y377923D03*
Y375364D03*
Y368261D03*
Y365702D03*
X366679Y389478D03*
Y392037D03*
Y394596D03*
X374159D03*
Y392037D03*
Y389478D03*
X395960Y323761D03*
Y321202D03*
Y318643D03*
X388480D03*
Y321202D03*
Y323761D03*
X401175Y363081D03*
X393695D03*
X401081Y378439D03*
Y375880D03*
X393601D03*
Y378439D03*
X401175Y368199D03*
Y365640D03*
X393695D03*
Y368199D03*
X401070Y393992D03*
Y391433D03*
Y388874D03*
X393590D03*
Y391433D03*
Y393992D03*
X401081Y380998D03*
X393601D03*
X401129Y406863D03*
Y404304D03*
Y401745D03*
X393649D03*
Y404304D03*
Y406863D03*
X418960Y1606441D03*
Y1609000D03*
Y1611559D03*
X429249Y363644D03*
X421769D03*
X429003Y379201D03*
Y376642D03*
X421523D03*
Y379201D03*
X429249Y368762D03*
Y366203D03*
X421769D03*
Y368762D03*
X429003Y381760D03*
X421523D03*
X428839Y394722D03*
Y392163D03*
Y389604D03*
X421359D03*
Y392163D03*
Y394722D03*
X428962Y407847D03*
Y405288D03*
Y402729D03*
X421482D03*
Y405288D03*
Y407847D03*
X426440Y1611559D03*
Y1609000D03*
Y1606441D03*
X531980Y178803D03*
Y181362D03*
Y183921D03*
X539460D03*
Y181362D03*
Y178803D03*
X586760Y514303D03*
Y516862D03*
Y519421D03*
X594240D03*
Y516862D03*
Y514303D03*
X673612Y1634844D03*
Y1637403D03*
Y1639962D03*
X679148Y1652262D03*
Y1654821D03*
Y1657380D03*
X681092Y1639962D03*
Y1637403D03*
Y1634844D03*
X686628Y1657380D03*
Y1654821D03*
Y1652262D03*
X761245Y167518D03*
Y170077D03*
Y172636D03*
X768725Y167518D03*
Y172636D03*
Y170077D03*
X819684Y264580D03*
Y267139D03*
Y269698D03*
X827164Y264580D03*
Y269698D03*
Y267139D03*
X1134512Y1620851D03*
Y1623410D03*
Y1625969D03*
X1141992D03*
Y1623410D03*
Y1620851D03*
X1408260Y1583441D03*
Y1586000D03*
Y1588559D03*
X1415740Y1583441D03*
Y1588559D03*
Y1586000D03*
X1419270Y1623391D03*
Y1625950D03*
Y1628509D03*
X1426750D03*
Y1625950D03*
Y1623391D03*
X1423240Y1639921D03*
Y1637362D03*
Y1634803D03*
X1415760D03*
Y1637362D03*
Y1639921D03*
X1440273Y1518976D03*
X1432793D03*
X1440513Y1534796D03*
X1433033D03*
X1440273Y1524094D03*
Y1521535D03*
X1432793D03*
Y1524094D03*
X1440663Y1551134D03*
Y1548575D03*
Y1546016D03*
X1433183D03*
Y1548575D03*
Y1551134D03*
X1440513Y1539914D03*
Y1537355D03*
X1433033D03*
Y1539914D03*
X1457540Y1607559D03*
Y1605000D03*
Y1602441D03*
X1450060D03*
Y1605000D03*
Y1607559D03*
X1682008Y1498303D03*
Y1500862D03*
Y1503421D03*
Y1517803D03*
Y1520362D03*
Y1522921D03*
Y1538803D03*
Y1541362D03*
Y1543921D03*
Y1558262D03*
Y1560821D03*
Y1563380D03*
Y1578762D03*
Y1581321D03*
Y1583880D03*
X1689488Y1503421D03*
Y1500862D03*
Y1498303D03*
Y1517803D03*
Y1522921D03*
Y1520362D03*
Y1543921D03*
Y1541362D03*
Y1538803D03*
Y1563380D03*
Y1560821D03*
Y1558262D03*
Y1583880D03*
Y1581321D03*
Y1578762D03*
X1813335Y158868D03*
Y161427D03*
Y163986D03*
X1831277Y151402D03*
X1820815Y163986D03*
Y161427D03*
Y158868D03*
X1831277Y153961D03*
Y156520D03*
X1838757Y151402D03*
Y156520D03*
Y153961D03*
G54D97*
X180336Y593159D03*
Y578789D03*
X1831062Y251934D03*
Y237564D03*
G54D289*
X1554724Y192657D03*
Y256161D03*
G54D89*
X157638Y1390937D03*
X195781D03*
X311621Y1349083D03*
X343749Y1326285D03*
X375877Y1312859D03*
X408005D03*
X440133D03*
X472261D03*
X504389Y1326285D03*
X536517Y1349083D03*
X671257Y1390962D03*
X709400D03*
X1130949Y1427266D03*
X1169092D03*
X1287882Y1349319D03*
X1319890Y1326285D03*
X1352018Y1312859D03*
X1384146D03*
X1416274D03*
X1448402D03*
X1480530Y1326285D03*
X1512658Y1349083D03*
X1632423Y1424558D03*
X1670566D03*
G54D98*
X174685Y647210D03*
X174393Y678354D03*
X195316Y1430034D03*
X383224Y1354446D03*
X412990D03*
X443326D03*
X458600Y1379662D03*
X472700Y1353962D03*
X526478Y1449795D03*
X708795Y1429579D03*
X1168627Y1466363D03*
X1359365Y1353946D03*
X1389131D03*
X1419467D03*
X1434200Y1379362D03*
X1449233Y1353946D03*
X1502956Y1449373D03*
X1670101Y1463655D03*
X1682882Y628017D03*
Y678952D03*
X1769790Y204632D03*
X1799350D03*
X1826405Y269763D03*
Y299056D03*
G54D299*
X1713488Y1525698D03*
X1730810D03*
G54D99*
X168666Y716471D03*
X180084D03*
X290586Y624181D03*
X302004D03*
X1575511Y735362D03*
Y744362D03*
X1586929Y735362D03*
Y744362D03*
M02*
